# ODB++ job TAP-GM-V2.zip
### matrix/matrix

STEP {
    COL=1
    NAME=PCB
}


LAYER {
    ROW=1
    CONTEXT=BOARD
    TYPE=COMPONENT
    NAME=COMP_+_TOP
    POLARITY=POSITIVE
    START_NAME=
    END_NAME=
    OLD_NAME=
}

LAYER {
    ROW=2
    CONTEXT=BOARD
    TYPE=SILK_SCREEN
    NAME=TOP_OVERLAY
    POLARITY=POSITIVE
    START_NAME=
    END_NAME=
    OLD_NAME=
}

LAYER {
    ROW=3
    CONTEXT=BOARD
    TYPE=SOLDER_PASTE
    NAME=TOP_PASTE
    POLARITY=POSITIVE
    START_NAME=
    END_NAME=
    OLD_NAME=
}

LAYER {
    ROW=4
    CONTEXT=BOARD
    TYPE=SOLDER_MASK
    NAME=TOP_SOLDER
    POLARITY=POSITIVE
    START_NAME=
    END_NAME=
    OLD_NAME=
}

LAYER {
    ROW=5
    CONTEXT=BOARD
    TYPE=SIGNAL
    NAME=TOP
    POLARITY=POSITIVE
    START_NAME=
    END_NAME=
    OLD_NAME=
}

LAYER {
    ROW=6
    CONTEXT=BOARD
    TYPE=SIGNAL
    NAME=SGND
    POLARITY=POSITIVE
    START_NAME=
    END_NAME=
    OLD_NAME=
}

LAYER {
    ROW=7
    CONTEXT=BOARD
    TYPE=SIGNAL
    NAME=IN1
    POLARITY=POSITIVE
    START_NAME=
    END_NAME=
    OLD_NAME=
}

LAYER {
    ROW=8
    CONTEXT=BOARD
    TYPE=SIGNAL
    NAME=IN2
    POLARITY=POSITIVE
    START_NAME=
    END_NAME=
    OLD_NAME=
}

LAYER {
    ROW=9
    CONTEXT=BOARD
    TYPE=SIGNAL
    NAME=SGND1
    POLARITY=POSITIVE
    START_NAME=
    END_NAME=
    OLD_NAME=
}

LAYER {
    ROW=10
    CONTEXT=BOARD
    TYPE=SIGNAL
    NAME=BOTTOM
    POLARITY=POSITIVE
    START_NAME=
    END_NAME=
    OLD_NAME=
}

LAYER {
    ROW=11
    CONTEXT=BOARD
    TYPE=SOLDER_MASK
    NAME=BOTTOM_SOLDER
    POLARITY=POSITIVE
    START_NAME=
    END_NAME=
    OLD_NAME=
}

LAYER {
    ROW=12
    CONTEXT=BOARD
    TYPE=SOLDER_PASTE
    NAME=BOTTOM_PASTE
    POLARITY=POSITIVE
    START_NAME=
    END_NAME=
    OLD_NAME=
}

LAYER {
    ROW=13
    CONTEXT=BOARD
    TYPE=SILK_SCREEN
    NAME=BOTTOM_OVERLAY
    POLARITY=POSITIVE
    START_NAME=
    END_NAME=
    OLD_NAME=
}

LAYER {
    ROW=14
    CONTEXT=BOARD
    TYPE=DRILL
    NAME=DRILL
    POLARITY=POSITIVE
    START_NAME=TOP
    END_NAME=BOTTOM
    OLD_NAME=
}

LAYER {
    ROW=15
    CONTEXT=BOARD
    TYPE=COMPONENT
    NAME=COMP_+_BOT
    POLARITY=POSITIVE
    START_NAME=
    END_NAME=
    OLD_NAME=
}

### misc/attrlist
.customer = 
.comment = 
.technology = 
.global_camtek_aoiset = 
.drc_route_keepin_lyr = 
.drc_comp_keepin_lyr = 
.drc_tp_keepin_lyr = 
.drc_route_keepout_lyr = 
.drc_via_keepout_lyr = 
.drc_trace_keepout_lyr = 
.drc_trace_keepout_lyr = 
.drc_plane_keepout_lyr = 
.drc_pad_keepout_lyr = 
.drc_comp_keepout_lyr = 
.drc_comp_height_lyr = 
.drc_tp_keepout_lyr = 
.variant_list = 
.primary_side = top
.design_origin_x = 0
.design_origin_y = 0
.board_thickness = 0.0472
_board_material = thermon

### steps/pcb/stephdr
X_DATUM=0.0000
Y_DATUM=0.0000

TOP_ACTIVE=0
BOTTOM_ACTIVE=0
RIGHT_ACTIVE=0
LEFT_ACTIVE=0
ONLINE_DRC_NAME=
ONLINE_DRC_MODE=DISABLED
ONLINE_DRC_STAT=RED
ONLINE_DRC_TIME=0
ONLINE_DRC_BEEP_VOL=2
ONLINE_DRC_BEEP_TONE=500
ONLINE_NET_MODE=DISABLED
ONLINE_NET_STAT=RED
ONLINE_NET_TIME=0
ONLINE_NET_BEEP_VOL=2
ONLINE_NET_BEEP_TONE=1000

### steps/pcb/attrlist
.out_drill_full = no
.out_drill_optional = no
.out_rout_optional = no
.array_with_rotation = no
.flipped_out_of_date = no
.comment = 
.out_name = 
.assembly_proc_top = 
.assembly_proc_bottom = 
.all_eda_layers = 
.etm_tester = 
.flipped_of = 
.pnl_scheme = 
.pnl_pcb = 
.pnl_class = 
.pnl_place = 
.fs_direction_top = right2left
.fs_direction_bottom = right2left
.smt_direction_top = right2left
.smt_direction_bottom = right2left
.viacap_layer = none
.etm_pin_style = regular
.etm_repear_fmt = none
.out_drill_order = 0
.out_rout_order = 0
.etm_adapter_h = 3750.000000
.gold_plating = no

### steps/pcb/layers/bottom/attrlist
.out_mirror = no
.lpol_done = no
.cu_base = no
.comment =
.inp_file =
.eda_layers = "BOTTOM"
.out_angle = 0.0
.out_polarity = positive
.layer_hdi_type = buildup
.out_x_scale = 1.000000
.out_y_scale = 1.000000
.out_comp = 0.000000
.et_adjacency = 20.000000
.layer_dielectric = 0.0004
.copper_weight = 0.85106383

### steps/pcb/layers/bottom_overlay/attrlist
.out_mirror = no
.lpol_done = no
.cu_base = no
.comment =
.inp_file =
.eda_layers = "BottomOverlay"
.out_angle = 0.0
.out_polarity = positive
.layer_hdi_type = buildup
.out_x_scale = 1.000000
.out_y_scale = 1.000000
.out_comp = 0.000000
.et_adjacency = 20.000000
.layer_dielectric = 0.0001
.copper_weight = 1

### steps/pcb/layers/bottom_paste/attrlist
.out_mirror = no
.lpol_done = no
.cu_base = no
.comment =
.inp_file =
.eda_layers = "BottomPaste"
.out_angle = 0.0
.out_polarity = positive
.layer_hdi_type = buildup
.out_x_scale = 1.000000
.out_y_scale = 1.000000
.out_comp = 0.000000
.et_adjacency = 20.000000
.layer_dielectric = 0.0001
.copper_weight = 1

### steps/pcb/layers/bottom_solder/attrlist
.out_mirror = no
.lpol_done = no
.cu_base = no
.comment =
.inp_file =
.eda_layers = "BottomSolderMask"
.out_angle = 0.0
.out_polarity = positive
.layer_hdi_type = buildup
.out_x_scale = 1.000000
.out_y_scale = 1.000000
.out_comp = 0.000000
.et_adjacency = 20.000000
.layer_dielectric = 0.0001
.copper_weight = 1

### steps/pcb/layers/drill/attrlist
.out_mirror = no
.lpol_done = no
.cu_base = no
.comment =
.inp_file =
.eda_layers = ""
.out_angle = 0.0
.out_polarity = positive
.layer_hdi_type = buildup
.out_x_scale = 1.000000
.out_y_scale = 1.000000
.out_comp = 0.000000
.et_adjacency = 20.000000
.layer_dielectric = 0.0001
.copper_weight = 1

### steps/pcb/layers/in1/attrlist
.out_mirror = no
.lpol_done = no
.cu_base = no
.comment =
.inp_file =
.eda_layers = "IN1"
.out_angle = 0.0
.out_polarity = positive
.layer_hdi_type = buildup
.out_x_scale = 1.000000
.out_y_scale = 1.000000
.out_comp = 0.000000
.et_adjacency = 20.000000
.layer_dielectric = 0.008
.copper_weight = 0.85106383

### steps/pcb/layers/in2/attrlist
.out_mirror = no
.lpol_done = no
.cu_base = no
.comment =
.inp_file =
.eda_layers = "IN2"
.out_angle = 0.0
.out_polarity = positive
.layer_hdi_type = buildup
.out_x_scale = 1.000000
.out_y_scale = 1.000000
.out_comp = 0.000000
.et_adjacency = 20.000000
.layer_dielectric = 0.008
.copper_weight = 0.85106383

### steps/pcb/layers/sgnd/attrlist
.out_mirror = no
.lpol_done = no
.cu_base = no
.comment =
.inp_file =
.eda_layers = "SGND"
.out_angle = 0.0
.out_polarity = positive
.layer_hdi_type = buildup
.out_x_scale = 1.000000
.out_y_scale = 1.000000
.out_comp = 0.000000
.et_adjacency = 20.000000
.layer_dielectric = 0.008
.copper_weight = 0.85106383

### steps/pcb/layers/sgnd1/attrlist
.out_mirror = no
.lpol_done = no
.cu_base = no
.comment =
.inp_file =
.eda_layers = "SGND1"
.out_angle = 0.0
.out_polarity = positive
.layer_hdi_type = buildup
.out_x_scale = 1.000000
.out_y_scale = 1.000000
.out_comp = 0.000000
.et_adjacency = 20.000000
.layer_dielectric = 0.008
.copper_weight = 0.85106383

### steps/pcb/layers/top/attrlist
.out_mirror = no
.lpol_done = no
.cu_base = no
.comment =
.inp_file =
.eda_layers = "TOP"
.out_angle = 0.0
.out_polarity = positive
.layer_hdi_type = buildup
.out_x_scale = 1.000000
.out_y_scale = 1.000000
.out_comp = 0.000000
.et_adjacency = 20.000000
.layer_dielectric = 0.008
.copper_weight = 0.85106383

### steps/pcb/layers/top_overlay/attrlist
.out_mirror = no
.lpol_done = no
.cu_base = no
.comment =
.inp_file =
.eda_layers = "TopOverlay"
.out_angle = 0.0
.out_polarity = positive
.layer_hdi_type = buildup
.out_x_scale = 1.000000
.out_y_scale = 1.000000
.out_comp = 0.000000
.et_adjacency = 20.000000
.layer_dielectric = 0.0001
.copper_weight = 1

### steps/pcb/layers/top_paste/attrlist
.out_mirror = no
.lpol_done = no
.cu_base = no
.comment =
.inp_file =
.eda_layers = "TopPaste"
.out_angle = 0.0
.out_polarity = positive
.layer_hdi_type = buildup
.out_x_scale = 1.000000
.out_y_scale = 1.000000
.out_comp = 0.000000
.et_adjacency = 20.000000
.layer_dielectric = 0.0001
.copper_weight = 1

### steps/pcb/layers/top_solder/attrlist
.out_mirror = no
.lpol_done = no
.cu_base = no
.comment =
.inp_file =
.eda_layers = "TopSolderMask"
.out_angle = 0.0
.out_polarity = positive
.layer_hdi_type = buildup
.out_x_scale = 1.000000
.out_y_scale = 1.000000
.out_comp = 0.000000
.et_adjacency = 20.000000
.layer_dielectric = 0.0001
.copper_weight = 1

### steps/pcb/profile
#
#Layer features
#
S P 0
OB 0.5905512 0.1771654 I
OS 0.5905512 0.5019685
OS 1.3129921 0.5019685
OS 1.3129921 0.1771654
OS 1.6279528 0.1771654
OS 1.6279528 0.4301181
OS 1.6282986 0.4371606
OS 1.6310465 0.4509751
OS 1.6364367 0.4639881
OS 1.6442619 0.4756995
OS 1.6542216 0.4856592
OS 1.665933 0.4934844
OS 1.678946 0.4988746
OS 1.6927605 0.5016225
OS 1.7068456 0.5016225
OS 1.7206601 0.4988746
OS 1.7336731 0.4934844
OS 1.7453845 0.4856592
OS 1.7553442 0.4756995
OS 1.7631694 0.4639881
OS 1.7685596 0.4509751
OS 1.7713075 0.4371606
OS 1.7716536 0.4301181
OS 1.7716536 0.019685
OS 1.7913386 0
OS 2.1929134 0
OS 2.2125984 0.019685
OS 2.2125984 0.2933071
OS 2.2129183 0.2981889
OS 2.2154454 0.30762
OS 2.2203273 0.3160757
OS 2.2272313 0.3229797
OS 2.235687 0.3278616
OS 2.2451181 0.3303887
OS 2.2548818 0.3303887
OS 2.2643129 0.3278616
OS 2.2727686 0.3229797
OS 2.2796726 0.3160757
OS 2.2845545 0.30762
OS 2.2870816 0.2981889
OS 2.2874016 0.2933071
OS 2.2874016 0.019685
OS 2.3070866 0
OS 3.1023622 0
OS 3.1220472 0.019685
OS 3.1220472 0.5019685
OS 7.0875986 0.5019685
OS 7.0875984 4.3759843
OS 0 4.3759843
OS 0 0.1771654
OS 0.5905512 0.1771654
OE
SE

### steps/pcb/eda/data
# 11/4/2020 4:09:06 PM
#
HDR Altium Designer file - Version 1.0.0.30000
LYR bottom_overlay bottom_paste in2 in1 sgnd sgnd1 top_overlay bottom_solder bottom top_paste top_solder top drill 
#
#NET 0
NET $NONE$
SNT TOP T 76 18
FID C 1 47
FID C 7 87
FID C 8 271
SNT TOP T 76 7
FID C 1 16
FID C 7 49
FID C 8 237
SNT TOP T 76 6
FID C 1 15
FID C 7 45
FID C 8 233
SNT TOP T 76 5
FID C 1 14
FID C 7 44
FID C 8 232
SNT TOP T 76 4
FID C 1 13
FID C 7 43
FID C 8 231
SNT TOP T 76 31
FID C 1 76
FID C 7 119
FID C 8 303
SNT TOP T 81 0
FID C 7 156
FID C 8 338
FID C 10 873
FID C 11 2239
FID H 12 77
SNT TOP T 81 0
FID C 7 151
FID C 8 333
FID C 10 829
FID C 11 2195
FID H 12 72
SNT TOP T 44 11
FID C 7 120
FID C 8 304
FID C 10 488
FID C 11 1856
FID H 12 41
SNT TOP T 44 10
FID C 7 114
FID C 8 298
FID C 10 449
FID C 11 1817
FID H 12 40
SNT TOP T 80 0
FID C 7 126
FID C 8 308
FID C 10 648
FID C 11 2014
FID H 12 47
SNT TOP T 80 0
FID C 7 125
FID C 8 307
FID C 10 632
FID C 11 1998
FID H 12 46
SNT TOP T 13 0
FID C 7 132
FID C 8 314
FID C 10 703
FID C 11 2069
FID H 12 53
SNT TOP T 41 0
FID C 7 73
FID C 10 284
FID H 12 37
SNT TOP T 41 0
FID C 7 72
FID C 10 283
FID H 12 36
SNT TOP T 77 332
FID C 7 112
FID C 8 296
FID C 10 447
FID C 11 1815
FID H 12 38
SNT TOP T 77 328
FID C 7 113
FID C 8 297
FID C 10 448
FID C 11 1816
FID H 12 39
SNT TOP T 77 332
FID C 7 54
FID C 8 243
FID C 10 215
FID C 11 1588
FID H 12 33
SNT TOP T 77 332
FID C 7 38
FID C 8 225
FID C 10 136
FID C 11 1507
FID H 12 28
SNT TOP T 77 328
FID C 7 37
FID C 8 224
FID C 10 135
FID C 11 1506
FID H 12 27
SNT TOP T 77 328
FID C 7 53
FID C 8 242
FID C 10 214
FID C 11 1587
FID H 12 32
SNT TOP T 77 332
FID C 7 121
FID C 8 305
FID C 10 559
FID C 11 1927
FID H 12 42
SNT TOP T 77 328
FID C 7 122
FID C 8 306
FID C 10 560
FID C 11 1928
FID H 12 43
SNT TOP T 77 0
FID C 7 123
FID C 10 566
FID H 12 44
SNT TOP T 77 0
FID C 7 35
FID C 10 131
FID H 12 25
SNT TOP T 77 0
FID C 7 36
FID C 10 132
FID H 12 26
SNT TOP T 77 0
FID C 7 124
FID C 10 567
FID H 12 45
SNT TOP B 0 0
FID C 7 70
FID C 10 281
FID H 12 34
SNT TOP B 0 0
FID C 7 71
FID C 10 282
FID H 12 35
SNT TOP T 43 13
FID C 9 606
FID C 10 658
FID C 11 2024
SNT TOP T 43 14
FID C 9 607
FID C 10 659
FID C 11 2025
SNT TOP T 43 15
FID C 9 608
FID C 10 660
FID C 11 2026
SNT TOP T 43 6
FID C 9 577
FID C 10 625
FID C 11 1991
SNT TOP T 43 5
FID C 9 578
FID C 10 626
FID C 11 1992
SNT TOP T 43 1
FID C 9 582
FID C 10 630
FID C 11 1996
SNT TOP T 42 23
FID C 9 748
FID C 10 820
FID C 11 2186
SNT TOP T 42 22
FID C 9 749
FID C 10 821
FID C 11 2187
SNT TOP T 42 21
FID C 9 750
FID C 10 822
FID C 11 2188
SNT TOP T 42 20
FID C 9 751
FID C 10 823
FID C 11 2189
SNT TOP T 42 12
FID C 9 728
FID C 10 800
FID C 11 2166
SNT TOP T 42 11
FID C 9 727
FID C 10 799
FID C 11 2165
SNT TOP T 42 8
FID C 9 724
FID C 10 796
FID C 11 2162
SNT TOP T 42 7
FID C 9 723
FID C 10 795
FID C 11 2161
SNT TOP T 42 6
FID C 9 722
FID C 10 794
FID C 11 2160
SNT TOP T 42 0
FID C 9 743
FID C 10 815
FID C 11 2181
SNT TOP T 44 7
FID C 9 438
FID C 10 481
FID C 11 1849
SNT TOP T 44 6
FID C 9 437
FID C 10 480
FID C 11 1848
SNT TOP T 38 2
FID C 9 456
FID C 10 500
FID C 11 1868
SNT TOP T 38 6
FID C 9 507
FID C 10 551
FID C 11 1919
SNT TOP T 38 7
FID C 9 508
FID C 10 552
FID C 11 1920
SNT TOP T 39 7
FID C 9 458
FID C 10 502
FID C 11 1870
SNT TOP T 39 6
FID C 9 451
FID C 10 495
FID C 11 1863
SNT TOP T 39 8
FID C 9 505
FID C 10 549
FID C 11 1917
SNT TOP T 39 0
FID C 9 513
FID C 10 557
FID C 11 1925
SNT TOP T 37 1
FID C 9 797
FID C 10 877
FID C 11 2243
SNT TOP T 37 2
FID C 9 798
FID C 10 878
FID C 11 2244
SNT TOP T 34 13
FID C 9 157
FID C 10 187
FID C 11 1559
SNT TOP T 34 14
FID C 9 158
FID C 10 188
FID C 11 1560
SNT TOP T 34 15
FID C 9 159
FID C 10 189
FID C 11 1561
SNT TOP T 34 6
FID C 9 98
FID C 10 124
FID C 11 1497
SNT TOP T 34 5
FID C 9 99
FID C 10 125
FID C 11 1498
SNT TOP T 34 1
FID C 9 103
FID C 10 129
FID C 11 1502
SNT TOP T 80 0
FID C 9 612
FID C 10 664
FID C 11 2030
SNT TOP T 80 0
FID C 9 611
FID C 10 663
FID C 11 2029
SNT TOP T 80 0
FID C 9 568
FID C 10 616
FID C 11 1982
SNT TOP T 80 0
FID C 9 569
FID C 10 617
FID C 11 1983
SNT TOP T 80 6
FID C 9 598
FID C 10 647
FID C 11 2013
SNT TOP T 80 9
FID C 9 585
FID C 10 634
FID C 11 2000
SNT TOP T 35 0
FID C 9 198
FID C 10 233
FID C 11 1606
SNT TOP T 35 0
FID C 9 233
FID C 10 268
FID C 11 1641
SNT TOP T 35 0
FID C 9 193
FID C 10 228
FID C 11 1601
SNT TOP T 35 0
FID C 9 251
FID C 10 290
FID C 11 1659
SNT TOP T 35 6
FID C 9 234
FID C 10 269
FID C 11 1642
SNT TOP T 35 9
FID C 9 208
FID C 10 243
FID C 11 1616
SNT TOP T 35 0
FID C 9 256
FID C 10 296
FID C 11 1664
SNT TOP T 35 0
FID C 9 180
FID C 10 213
FID C 11 1586
SNT TOP T 12 0
FID C 9 345
FID C 10 385
FID C 11 1753
SNT TOP T 12 3
FID C 9 342
FID C 10 382
FID C 11 1750
SNT TOP T 12 4
FID C 9 341
FID C 10 381
FID C 11 1749
SNT TOP T 12 5
FID C 9 340
FID C 10 380
FID C 11 1748
SNT TOP T 12 6
FID C 9 339
FID C 10 379
FID C 11 1747
SNT TOP T 12 7
FID C 9 338
FID C 10 378
FID C 11 1746
SNT TOP T 12 11
FID C 9 421
FID C 10 464
FID C 11 1832
SNT TOP T 12 10
FID C 9 420
FID C 10 463
FID C 11 1831
SNT TOP T 12 9
FID C 9 419
FID C 10 462
FID C 11 1830
SNT TOP T 12 8
FID C 9 418
FID C 10 461
FID C 11 1829
SNT TOP T 40 9
FID C 9 592
FID C 10 641
FID C 11 2007
SNT TOP T 40 11
FID C 9 593
FID C 10 642
FID C 11 2008
SNT TOP T 40 10
FID C 9 620
FID C 10 673
FID C 11 2039
SNT TOP T 40 13
FID C 9 594
FID C 10 643
FID C 11 2009
SNT TOP T 40 12
FID C 9 621
FID C 10 674
FID C 11 2040
SNT TOP T 40 15
FID C 9 595
FID C 10 644
FID C 11 2010
SNT TOP T 40 17
FID C 9 596
FID C 10 645
FID C 11 2011
SNT TOP T 0 6
FID C 9 439
FID C 10 482
FID C 11 1850
SNT TOP T 0 4
FID C 9 430
FID C 10 473
FID C 11 1841
SNT TOP T 76 42
FID C 9 179
FID C 10 212
FID C 11 1585
SNT TOP T 76 37
FID C 9 166
FID C 10 196
FID C 11 1568
SNT TOP T 76 36
FID C 9 165
FID C 10 195
FID C 11 1567
SNT TOP T 76 61
FID C 9 407
FID C 10 450
FID C 11 1818
SNT TOP T 76 43
FID C 9 209
FID C 10 244
FID C 11 1617
SNT TOP T 76 40
FID C 9 169
FID C 10 202
FID C 11 1574
SNT TOP T 76 41
FID C 9 176
FID C 10 209
FID C 11 1582
SNT TOP T 77 336
FID C 9 408
FID C 10 451
FID C 11 1819
SNT TOP T 77 322
FID C 9 188
FID C 10 223
FID C 11 1596
SNT TOP T 77 323
FID C 9 187
FID C 10 222
FID C 11 1595
SNT TOP T 77 324
FID C 9 409
FID C 10 452
FID C 11 1820
SNT TOP T 77 336
FID C 9 178
FID C 10 211
FID C 11 1584
SNT TOP T 77 277
FID C 9 313
FID C 10 353
FID C 11 1721
SNT TOP T 77 271
FID C 9 328
FID C 10 368
FID C 11 1736
SNT TOP T 77 265
FID C 9 353
FID C 10 393
FID C 11 1761
SNT TOP T 77 259
FID C 9 368
FID C 10 408
FID C 11 1776
SNT TOP T 77 247
FID C 9 400
FID C 10 440
FID C 11 1808
SNT TOP T 77 246
FID C 9 401
FID C 10 441
FID C 11 1809
SNT TOP T 77 244
FID C 9 406
FID C 10 446
FID C 11 1814
SNT TOP T 77 245
FID C 9 405
FID C 10 445
FID C 11 1813
SNT TOP T 77 248
FID C 9 393
FID C 10 433
FID C 11 1801
SNT TOP T 77 249
FID C 9 392
FID C 10 432
FID C 11 1800
SNT TOP T 77 250
FID C 9 388
FID C 10 428
FID C 11 1796
SNT TOP T 77 251
FID C 9 387
FID C 10 427
FID C 11 1795
SNT TOP T 77 254
FID C 9 379
FID C 10 419
FID C 11 1787
SNT TOP T 77 256
FID C 9 375
FID C 10 415
FID C 11 1783
SNT TOP T 77 290
FID C 9 280
FID C 10 320
FID C 11 1688
SNT TOP T 77 288
FID C 9 285
FID C 10 325
FID C 11 1693
SNT TOP T 77 310
FID C 9 217
FID C 10 252
FID C 11 1625
SNT TOP T 77 308
FID C 9 227
FID C 10 262
FID C 11 1635
SNT TOP T 77 320
FID C 9 192
FID C 10 227
FID C 11 1600
SNT TOP T 77 318
FID C 9 197
FID C 10 232
FID C 11 1605
SNT TOP T 77 316
FID C 9 202
FID C 10 237
FID C 11 1610
SNT TOP T 77 314
FID C 9 207
FID C 10 242
FID C 11 1615
SNT TOP T 77 298
FID C 9 255
FID C 10 295
FID C 11 1663
SNT TOP T 77 294
FID C 9 265
FID C 10 305
FID C 11 1673
SNT TOP T 77 296
FID C 9 261
FID C 10 301
FID C 11 1669
SNT TOP T 77 300
FID C 9 250
FID C 10 289
FID C 11 1658
SNT TOP T 77 304
FID C 9 241
FID C 10 276
FID C 11 1649
SNT TOP T 77 306
FID C 9 232
FID C 10 267
FID C 11 1640
SNT TOP T 77 286
FID C 9 289
FID C 10 329
FID C 11 1697
SNT TOP T 77 317
FID C 9 201
FID C 10 236
FID C 11 1609
SNT TOP T 77 319
FID C 9 196
FID C 10 231
FID C 11 1604
SNT TOP T 77 297
FID C 9 260
FID C 10 300
FID C 11 1668
SNT TOP T 77 299
FID C 9 254
FID C 10 294
FID C 11 1662
SNT TOP T 77 287
FID C 9 288
FID C 10 328
FID C 11 1696
SNT TOP T 77 289
FID C 9 284
FID C 10 324
FID C 11 1692
SNT TOP T 77 291
FID C 9 279
FID C 10 319
FID C 11 1687
SNT TOP T 77 295
FID C 9 264
FID C 10 304
FID C 11 1672
SNT TOP T 77 305
FID C 9 240
FID C 10 275
FID C 11 1648
SNT TOP T 77 315
FID C 9 206
FID C 10 241
FID C 11 1614
SNT TOP T 77 311
FID C 9 216
FID C 10 251
FID C 11 1624
SNT TOP T 77 309
FID C 9 226
FID C 10 261
FID C 11 1634
SNT TOP T 77 307
FID C 9 231
FID C 10 266
FID C 11 1639
SNT TOP T 77 301
FID C 9 249
FID C 10 288
FID C 11 1657
SNT TOP T 77 321
FID C 9 191
FID C 10 226
FID C 11 1599
SNT TOP T 77 284
FID C 9 294
FID C 10 334
FID C 11 1702
SNT TOP T 77 285
FID C 9 293
FID C 10 333
FID C 11 1701
SNT TOP T 77 336
FID C 9 107
FID C 10 137
FID C 11 1508
SNT TOP T 77 324
FID C 9 106
FID C 10 134
FID C 11 1505
SNT TOP T 77 238
FID C 9 146
FID C 10 176
FID C 11 1547
SNT TOP T 77 239
FID C 9 94
FID C 10 120
FID C 11 1493
SNT TOP T 77 199
FID C 9 74
FID C 10 100
FID C 11 1473
SNT TOP T 77 205
FID C 9 77
FID C 10 103
FID C 11 1476
SNT TOP T 77 180
FID C 9 117
FID C 10 147
FID C 11 1518
SNT TOP T 77 174
FID C 9 114
FID C 10 144
FID C 11 1515
SNT TOP T 77 170
FID C 9 112
FID C 10 142
FID C 11 1513
SNT TOP T 77 211
FID C 9 80
FID C 10 106
FID C 11 1479
SNT TOP T 77 197
FID C 9 73
FID C 10 99
FID C 11 1472
SNT TOP T 77 167
FID C 9 58
FID C 10 84
FID C 11 1457
SNT TOP T 77 168
FID C 9 111
FID C 10 141
FID C 11 1512
SNT TOP T 77 209
FID C 9 79
FID C 10 105
FID C 11 1478
SNT TOP T 77 175
FID C 9 62
FID C 10 88
FID C 11 1461
SNT TOP T 77 181
FID C 9 65
FID C 10 91
FID C 11 1464
SNT TOP T 77 171
FID C 9 60
FID C 10 86
FID C 11 1459
SNT TOP T 77 201
FID C 9 75
FID C 10 101
FID C 11 1474
SNT TOP T 77 207
FID C 9 78
FID C 10 104
FID C 11 1477
SNT TOP T 77 195
FID C 9 72
FID C 10 98
FID C 11 1471
SNT TOP T 77 189
FID C 9 69
FID C 10 95
FID C 11 1468
SNT TOP T 77 187
FID C 9 68
FID C 10 94
FID C 11 1467
SNT TOP T 77 177
FID C 9 63
FID C 10 89
FID C 11 1462
SNT TOP T 77 191
FID C 9 70
FID C 10 96
FID C 11 1469
SNT TOP T 77 166
FID C 9 110
FID C 10 140
FID C 11 1511
SNT TOP T 77 169
FID C 9 59
FID C 10 85
FID C 11 1458
SNT TOP T 77 176
FID C 9 115
FID C 10 145
FID C 11 1516
SNT TOP T 77 217
FID C 9 83
FID C 10 109
FID C 11 1482
SNT TOP T 77 215
FID C 9 82
FID C 10 108
FID C 11 1481
SNT TOP T 77 179
FID C 9 64
FID C 10 90
FID C 11 1463
SNT TOP T 77 185
FID C 9 67
FID C 10 93
FID C 11 1466
SNT TOP T 77 190
FID C 9 122
FID C 10 152
FID C 11 1523
SNT TOP T 77 188
FID C 9 121
FID C 10 151
FID C 11 1522
SNT TOP T 77 229
FID C 9 89
FID C 10 115
FID C 11 1488
SNT TOP T 77 204
FID C 9 129
FID C 10 159
FID C 11 1530
SNT TOP T 77 208
FID C 9 131
FID C 10 161
FID C 11 1532
SNT TOP T 77 235
FID C 9 92
FID C 10 118
FID C 11 1491
SNT TOP T 77 198
FID C 9 126
FID C 10 156
FID C 11 1527
SNT TOP T 77 218
FID C 9 136
FID C 10 166
FID C 11 1537
SNT TOP T 77 226
FID C 9 140
FID C 10 170
FID C 11 1541
SNT TOP T 77 231
FID C 9 90
FID C 10 116
FID C 11 1489
SNT TOP T 77 221
FID C 9 85
FID C 10 111
FID C 11 1484
SNT TOP T 77 178
FID C 9 116
FID C 10 146
FID C 11 1517
SNT TOP T 77 230
FID C 9 142
FID C 10 172
FID C 11 1543
SNT TOP T 77 234
FID C 9 144
FID C 10 174
FID C 11 1545
SNT TOP T 77 237
FID C 9 93
FID C 10 119
FID C 11 1492
SNT TOP T 77 225
FID C 9 87
FID C 10 113
FID C 11 1486
SNT TOP T 77 219
FID C 9 84
FID C 10 110
FID C 11 1483
SNT TOP T 77 227
FID C 9 88
FID C 10 114
FID C 11 1487
SNT TOP T 77 210
FID C 9 132
FID C 10 162
FID C 11 1533
SNT TOP T 77 206
FID C 9 130
FID C 10 160
FID C 11 1531
SNT TOP T 77 228
FID C 9 141
FID C 10 171
FID C 11 1542
SNT TOP T 77 216
FID C 9 135
FID C 10 165
FID C 11 1536
SNT TOP T 77 224
FID C 9 139
FID C 10 169
FID C 11 1540
SNT TOP T 77 236
FID C 9 145
FID C 10 175
FID C 11 1546
SNT TOP T 77 220
FID C 9 137
FID C 10 167
FID C 11 1538
SNT TOP T 77 196
FID C 9 125
FID C 10 155
FID C 11 1526
SNT TOP T 77 97
FID C 9 215
FID C 10 250
FID C 11 1623
SNT TOP T 77 95
FID C 9 211
FID C 10 246
FID C 11 1619
SNT TOP T 77 90
FID C 9 199
FID C 10 234
FID C 11 1607
SNT TOP T 77 88
FID C 9 194
FID C 10 229
FID C 11 1602
SNT TOP T 77 161
FID C 9 399
FID C 10 439
FID C 11 1807
SNT TOP T 77 159
FID C 9 391
FID C 10 431
FID C 11 1799
SNT TOP T 77 151
FID C 9 373
FID C 10 413
FID C 11 1781
SNT TOP T 77 149
FID C 9 367
FID C 10 407
FID C 11 1775
SNT TOP T 77 141
FID C 9 347
FID C 10 387
FID C 11 1755
SNT TOP T 77 139
FID C 9 334
FID C 10 374
FID C 11 1742
SNT TOP T 77 145
FID C 9 356
FID C 10 396
FID C 11 1764
SNT TOP T 77 131
FID C 9 312
FID C 10 352
FID C 11 1720
SNT TOP T 77 129
FID C 9 307
FID C 10 347
FID C 11 1715
SNT TOP T 77 137
FID C 9 327
FID C 10 367
FID C 11 1735
SNT TOP T 77 135
FID C 9 322
FID C 10 362
FID C 11 1730
SNT TOP T 77 121
FID C 9 287
FID C 10 327
FID C 11 1695
SNT TOP T 77 127
FID C 9 301
FID C 10 341
FID C 11 1709
SNT TOP T 77 119
FID C 9 283
FID C 10 323
FID C 11 1691
SNT TOP T 77 125
FID C 9 296
FID C 10 336
FID C 11 1704
SNT TOP T 77 115
FID C 9 270
FID C 10 310
FID C 11 1678
SNT TOP T 77 101
FID C 9 230
FID C 10 265
FID C 11 1638
SNT TOP T 77 107
FID C 9 248
FID C 10 287
FID C 11 1656
SNT TOP T 77 105
FID C 9 243
FID C 10 278
FID C 11 1651
SNT TOP T 77 84
FID C 9 185
FID C 10 220
FID C 11 1593
SNT TOP T 77 86
FID C 9 189
FID C 10 224
FID C 11 1597
SNT TOP T 77 87
FID C 9 190
FID C 10 225
FID C 11 1598
SNT TOP T 77 85
FID C 9 186
FID C 10 221
FID C 11 1594
SNT TOP T 77 100
FID C 9 229
FID C 10 264
FID C 11 1637
SNT TOP T 77 98
FID C 9 224
FID C 10 259
FID C 11 1632
SNT TOP T 77 114
FID C 9 269
FID C 10 309
FID C 11 1677
SNT TOP T 77 140
FID C 9 346
FID C 10 386
FID C 11 1754
SNT TOP T 77 138
FID C 9 333
FID C 10 373
FID C 11 1741
SNT TOP T 77 146
FID C 9 361
FID C 10 401
FID C 11 1769
SNT TOP T 77 148
FID C 9 366
FID C 10 406
FID C 11 1774
SNT TOP T 77 156
FID C 9 385
FID C 10 425
FID C 11 1793
SNT TOP T 77 158
FID C 9 390
FID C 10 430
FID C 11 1798
SNT TOP T 77 324
FID C 9 177
FID C 10 210
FID C 11 1583
SNT TOP T 77 54
FID C 9 478
FID C 10 522
FID C 11 1890
SNT TOP T 77 56
FID C 9 477
FID C 10 521
FID C 11 1889
SNT TOP T 77 61
FID C 9 531
FID C 10 579
FID C 11 1945
SNT TOP T 77 40
FID C 9 485
FID C 10 529
FID C 11 1897
SNT TOP T 77 336
FID C 9 514
FID C 10 558
FID C 11 1926
SNT TOP T 77 324
FID C 9 515
FID C 10 561
FID C 11 1929
SNT TOP T 77 83
FID C 9 520
FID C 10 568
FID C 11 1934
SNT TOP T 77 82
FID C 9 464
FID C 10 508
FID C 11 1876
SNT TOP T 77 81
FID C 9 521
FID C 10 569
FID C 11 1935
SNT TOP T 77 79
FID C 9 522
FID C 10 570
FID C 11 1936
SNT TOP T 77 77
FID C 9 523
FID C 10 571
FID C 11 1937
SNT TOP T 77 75
FID C 9 524
FID C 10 572
FID C 11 1938
SNT TOP T 77 71
FID C 9 526
FID C 10 574
FID C 11 1940
SNT TOP T 77 69
FID C 9 527
FID C 10 575
FID C 11 1941
SNT TOP T 77 60
FID C 9 475
FID C 10 519
FID C 11 1887
SNT TOP T 77 55
FID C 9 534
FID C 10 582
FID C 11 1948
SNT TOP T 77 18
FID C 9 496
FID C 10 540
FID C 11 1908
SNT TOP T 77 58
FID C 9 476
FID C 10 520
FID C 11 1888
SNT TOP T 77 20
FID C 9 495
FID C 10 539
FID C 11 1907
SNT TOP T 77 47
FID C 9 538
FID C 10 586
FID C 11 1952
SNT TOP T 77 39
FID C 9 542
FID C 10 590
FID C 11 1956
SNT TOP T 77 41
FID C 9 541
FID C 10 589
FID C 11 1955
SNT TOP T 77 44
FID C 9 483
FID C 10 527
FID C 11 1895
SNT TOP T 77 50
FID C 9 480
FID C 10 524
FID C 11 1892
SNT TOP T 77 45
FID C 9 539
FID C 10 587
FID C 11 1953
SNT TOP T 77 16
FID C 9 497
FID C 10 541
FID C 11 1909
SNT TOP T 77 14
FID C 9 498
FID C 10 542
FID C 11 1910
SNT TOP T 77 17
FID C 9 553
FID C 10 601
FID C 11 1967
SNT TOP T 77 15
FID C 9 554
FID C 10 602
FID C 11 1968
SNT TOP T 77 19
FID C 9 552
FID C 10 600
FID C 11 1966
SNT TOP T 77 31
FID C 9 546
FID C 10 594
FID C 11 1960
SNT TOP T 77 29
FID C 9 547
FID C 10 595
FID C 11 1961
SNT TOP T 77 21
FID C 9 551
FID C 10 599
FID C 11 1965
SNT TOP T 77 27
FID C 9 548
FID C 10 596
FID C 11 1962
SNT TOP T 77 34
FID C 9 488
FID C 10 532
FID C 11 1900
SNT TOP T 77 64
FID C 9 473
FID C 10 517
FID C 11 1885
SNT TOP T 77 36
FID C 9 487
FID C 10 531
FID C 11 1899
SNT TOP T 77 66
FID C 9 472
FID C 10 516
FID C 11 1884
SNT TOP T 77 68
FID C 9 471
FID C 10 515
FID C 11 1883
SNT VIA
FID C 4 18
FID C 5 18
FID C 7 22
FID C 8 212
FID C 10 22
FID C 11 1396
FID H 12 13
SNT VIA
FID C 4 17
FID C 5 17
FID C 7 21
FID C 8 211
FID C 10 21
FID C 11 1395
FID H 12 12
#NET 1
NET GPS1_TX
SNT TOP T 3 0
FID C 2 481
FID C 7 33
FID C 8 223
FID C 10 81
FID C 11 1455
FID H 12 24
SNT TOP T 77 163
FID C 9 404
FID C 10 444
FID C 11 1812
SNT TOP T 41 4
FID C 9 275
FID C 10 315
FID C 11 1683
SNT TRC
FID C 2 111
SNT TRC
FID C 2 110
SNT TRC
FID C 2 112
SNT TRC
FID C 2 180
SNT TRC
FID C 2 221
SNT TRC
FID C 2 202
SNT TRC
FID C 2 182
SNT TRC
FID C 2 181
SNT TRC
FID C 3 121
SNT TRC
FID C 3 201
SNT TRC
FID C 3 205
SNT TRC
FID C 11 574
SNT TRC
FID C 11 566
SNT TRC
FID C 11 346
SNT TRC
FID C 11 353
SNT VIA
FID C 2 532
FID C 3 597
FID C 7 289
FID C 8 474
FID C 10 1013
FID C 11 2383
FID H 12 210
SNT VIA
FID C 2 490
FID C 3 563
FID C 7 184
FID C 8 369
FID C 10 908
FID C 11 2278
FID H 12 105
SNT VIA
FID C 3 643
FID C 7 402
FID C 8 587
FID C 10 1126
FID C 11 2496
FID H 12 323
SNT VIA
FID C 2 533
FID C 3 598
FID C 7 290
FID C 8 475
FID C 10 1014
FID C 11 2384
FID H 12 211
#NET 2
NET GPS1_TP1
SNT TOP T 77 35
FID C 9 544
FID C 10 592
FID C 11 1958
SNT TOP T 7 0
FID C 9 237
FID C 10 272
FID C 11 1645
SNT TOP T 41 7
FID C 9 220
FID C 10 255
FID C 11 1628
SNT TOP T 1 0
FID C 9 38
FID C 10 60
FID C 11 1434
SNT TRC
FID C 2 188
SNT TRC
FID C 2 189
SNT TRC
FID C 2 195
SNT TRC
FID C 2 177
SNT TRC
FID C 2 196
SNT TRC
FID C 2 176
SNT TRC
FID C 2 178
SNT TRC
FID C 2 103
SNT TRC
FID C 2 102
SNT TRC
FID C 2 108
SNT TRC
FID C 2 109
SNT TRC
FID C 3 483
SNT TRC
FID C 3 463
SNT TRC
FID C 3 458
SNT TRC
FID C 3 425
SNT TRC
FID C 3 420
SNT TRC
FID C 3 189
SNT TRC
FID C 3 124
SNT TRC
FID C 3 112
SNT TRC
FID C 11 809
SNT TRC
FID C 11 850
SNT TRC
FID C 11 876
SNT TRC
FID C 11 313
SNT TRC
FID C 11 317
SNT TRC
FID C 11 330
SNT TRC
FID C 11 329
SNT TRC
FID C 11 104
SNT TRC
FID C 11 97
SNT TRC
FID C 11 96
SNT VIA
FID C 3 681
FID C 7 488
FID C 8 673
FID C 10 1212
FID C 11 2582
FID H 12 409
SNT VIA
FID C 2 527
FID C 3 590
FID C 7 273
FID C 8 458
FID C 10 997
FID C 11 2367
FID H 12 194
SNT VIA
FID C 2 529
FID C 7 275
FID C 8 460
FID C 10 999
FID C 11 2369
FID H 12 196
SNT VIA
FID C 2 487
FID C 7 169
FID C 8 354
FID C 10 893
FID C 11 2263
FID H 12 90
SNT VIA
FID C 2 489
FID C 3 561
FID C 7 182
FID C 8 367
FID C 10 906
FID C 11 2276
FID H 12 103
#NET 3
NET GPS1_RX
SNT TOP T 2 0
FID C 2 482
FID C 7 48
FID C 8 236
FID C 10 200
FID C 11 1572
FID H 12 31
SNT TOP T 77 162
FID C 9 403
FID C 10 443
FID C 11 1811
SNT TOP T 41 6
FID C 9 274
FID C 10 314
FID C 11 1682
SNT TRC
FID C 2 28
SNT TRC
FID C 2 36
SNT TRC
FID C 2 245
SNT TRC
FID C 2 249
SNT TRC
FID C 2 286
SNT TRC
FID C 2 244
SNT TRC
FID C 2 257
SNT TRC
FID C 2 1
SNT TRC
FID C 2 32
SNT TRC
FID C 2 173
SNT TRC
FID C 2 174
SNT TRC
FID C 2 255
SNT TRC
FID C 2 154
SNT TRC
FID C 2 147
SNT TRC
FID C 2 248
SNT TRC
FID C 2 246
SNT TRC
FID C 2 247
SNT TRC
FID C 3 266
SNT TRC
FID C 3 282
SNT TRC
FID C 3 232
SNT TRC
FID C 3 375
SNT TRC
FID C 11 573
SNT TRC
FID C 11 564
SNT TRC
FID C 11 563
SNT TRC
FID C 11 394
SNT TRC
FID C 11 376
SNT VIA
FID C 2 543
FID C 3 607
FID C 7 309
FID C 8 494
FID C 10 1033
FID C 11 2403
FID H 12 230
SNT VIA
FID C 3 642
FID C 7 400
FID C 8 585
FID C 10 1124
FID C 11 2494
FID H 12 321
SNT VIA
FID C 2 547
FID C 7 319
FID C 8 504
FID C 10 1043
FID C 11 2413
FID H 12 240
#NET 4
NET NetC44_1
SNT TOP B 14 0
FID C 1 27
FID C 7 62
FID C 8 251
SNT TOP T 76 12
FID C 1 26
FID C 7 61
FID C 8 250
SNT TRC
FID C 8 63
SNT TRC
FID C 8 1
SNT TRC
FID C 8 2
SNT TRC
FID C 8 62
#NET 5
NET NetC45_1
SNT TOP B 13 0
FID C 1 32
FID C 7 67
FID C 8 256
SNT TOP T 76 13
FID C 1 31
FID C 7 66
FID C 8 255
SNT TRC
FID C 8 69
SNT TRC
FID C 8 4
#NET 6
NET NetC46_1
SNT TOP B 12 0
FID C 1 37
FID C 7 77
FID C 8 261
SNT TOP T 76 15
FID C 1 36
FID C 7 76
FID C 8 260
SNT TRC
FID C 8 87
SNT TRC
FID C 8 6
SNT TRC
FID C 8 8
SNT TRC
FID C 8 7
#NET 7
NET NetC47_1
SNT TOP B 11 0
FID C 1 44
FID C 7 84
FID C 8 268
SNT TOP T 76 16
FID C 1 39
FID C 7 79
FID C 8 263
SNT TRC
FID C 8 96
SNT TRC
FID C 8 10
#NET 8
NET NetC48_1
SNT TOP B 10 0
FID C 1 52
FID C 7 92
FID C 8 276
SNT TOP T 76 20
FID C 1 51
FID C 7 91
FID C 8 275
SNT TRC
FID C 8 11
SNT TRC
FID C 8 112
SNT TRC
FID C 8 12
#NET 9
NET NetC50_1
SNT TOP B 8 0
FID C 1 61
FID C 7 101
FID C 8 285
SNT TOP T 76 24
FID C 1 63
FID C 7 103
FID C 8 287
SNT TRC
FID C 8 18
SNT TRC
FID C 8 17
SNT TRC
FID C 8 135
#NET 10
NET NetC51_1
SNT TOP B 7 0
FID C 1 64
FID C 7 104
FID C 8 288
SNT TOP T 76 25
FID C 1 66
FID C 7 106
FID C 8 290
SNT TRC
FID C 8 22
SNT TRC
FID C 8 23
SNT TRC
FID C 8 21
SNT TRC
FID C 8 137
#NET 11
NET NetC52_1
SNT TOP B 6 0
FID C 1 70
FID C 7 110
FID C 8 294
SNT TOP T 76 28
FID C 1 69
FID C 7 109
FID C 8 293
SNT TRC
FID C 8 148
SNT TRC
FID C 8 25
SNT TRC
FID C 8 27
SNT TRC
FID C 8 26
#NET 12
NET NetC53_1
SNT TOP B 5 0
FID C 1 73
FID C 7 116
FID C 8 300
SNT TOP T 76 29
FID C 1 72
FID C 7 115
FID C 8 299
SNT TRC
FID C 8 157
SNT TRC
FID C 8 30
SNT TRC
FID C 8 31
SNT TRC
FID C 8 154
#NET 13
NET NetC72_2
SNT TOP T 16 1
FID C 9 643
FID C 10 697
FID C 11 2063
SNT TOP T 84 1
FID C 9 657
FID C 10 714
FID C 11 2080
SNT TOP T 15 1
FID C 9 652
FID C 10 709
FID C 11 2075
SNT TOP T 83 0
FID C 9 630
FID C 10 683
FID C 11 2049
SNT TRC
FID C 11 1018
SNT TRC
FID C 11 1041
SNT TRC
FID C 11 1037
SNT TRC
FID C 11 1035
SNT TRC
FID C 11 1016
SNT TRC
FID C 11 1008
SNT TRC
FID C 11 1001
SNT TRC
FID C 11 1000
SNT TRC
FID C 11 996
SNT TRC
FID C 11 985
SNT TRC
FID C 11 984
#NET 14
NET NetC85_2
SNT TOP T 28 1
FID C 9 758
FID C 10 833
FID C 11 2199
SNT TOP T 42 26
FID C 9 745
FID C 10 817
FID C 11 2183
SNT TOP T 37 0
FID C 9 781
FID C 10 856
FID C 11 2222
SNT TRC
FID C 11 1279
SNT TRC
FID C 11 1306
SNT TRC
FID C 11 1349
SNT TRC
FID C 11 1341
SNT TRC
FID C 11 1308
#NET 15
NET NetC86_2
SNT TOP T 29 1
FID C 9 759
FID C 10 834
FID C 11 2200
SNT TOP T 42 25
FID C 9 746
FID C 10 818
FID C 11 2184
SNT TOP T 37 3
FID C 9 782
FID C 10 857
FID C 11 2223
SNT TRC
FID C 11 1280
SNT TRC
FID C 11 1292
SNT TRC
FID C 11 1309
SNT TRC
FID C 11 1350
SNT TRC
FID C 11 1342
SNT TRC
FID C 11 1310
#NET 16
NET NetD11_1
SNT TOP T 57 1
FID C 9 14
FID C 10 36
FID C 11 1410
SNT TOP T 93 0
FID C 9 15
FID C 10 37
FID C 11 1411
SNT TRC
FID C 11 62
SNT TRC
FID C 11 63
#NET 17
NET NetD12_1
SNT TOP T 56 1
FID C 9 26
FID C 10 48
FID C 11 1422
SNT TOP T 92 0
FID C 9 27
FID C 10 49
FID C 11 1423
SNT TRC
FID C 11 79
SNT TRC
FID C 11 80
#NET 18
NET NetP2_B17
SNT TOP T 62 1
FID C 9 266
FID C 10 306
FID C 11 1674
SNT TOP T 76 48
FID C 9 268
FID C 10 308
FID C 11 1676
SNT TRC
FID C 11 387
SNT TRC
FID C 11 380
SNT TRC
FID C 11 373
SNT TRC
FID C 11 379
SNT TRC
FID C 11 378
SNT TRC
FID C 11 372
#NET 19
NET NetP2_B31
SNT TOP T 61 1
FID C 9 414
FID C 10 457
FID C 11 1825
SNT TOP T 76 62
FID C 9 416
FID C 10 459
FID C 11 1827
SNT TRC
FID C 11 581
SNT TRC
FID C 11 582
SNT TRC
FID C 11 580
SNT TRC
FID C 11 583
#NET 20
NET NetR3_1
SNT TOP T 73 0
FID C 9 696
FID C 10 768
FID C 11 2134
SNT TOP T 45 6
FID C 9 690
FID C 10 762
FID C 11 2128
SNT TRC
FID C 11 1151
SNT TRC
FID C 11 1154
SNT TRC
FID C 11 1168
#NET 21
NET NetR4_2
SNT TOP T 46 4
FID C 9 787
FID C 10 864
FID C 11 2230
SNT TOP T 71 1
FID C 9 786
FID C 10 863
FID C 11 2229
SNT TOP T 72 1
FID C 9 793
FID C 10 870
FID C 11 2236
SNT TRC
FID C 11 1361
SNT TRC
FID C 11 1364
SNT TRC
FID C 11 1373
SNT TRC
FID C 11 1374
SNT TRC
FID C 11 1358
SNT TRC
FID C 11 1359
SNT TRC
FID C 11 1360
#NET 22
NET NetR5_1
SNT TOP T 36 0
FID C 9 686
FID C 10 758
FID C 11 2124
SNT TOP T 70 1
FID C 9 699
FID C 10 771
FID C 11 2137
SNT TOP T 45 4
FID C 9 692
FID C 10 764
FID C 11 2130
SNT TRC
FID C 11 1170
SNT TRC
FID C 11 1155
SNT TRC
FID C 11 1152
SNT TRC
FID C 11 1148
SNT TRC
FID C 11 1146
SNT TRC
FID C 11 1145
SNT TRC
FID C 11 1144
SNT TRC
FID C 11 1143
SNT TRC
FID C 11 1142
SNT TRC
FID C 11 1140
#NET 23
NET NetR18_2
SNT TOP T 67 1
FID C 9 395
FID C 10 435
FID C 11 1803
SNT TOP T 44 0
FID C 9 396
FID C 10 436
FID C 11 1804
SNT TRC
FID C 11 562
#NET 24
NET NetR20_2
SNT TOP T 65 1
FID C 9 427
FID C 10 470
FID C 11 1838
SNT TOP T 44 4
FID C 9 428
FID C 10 471
FID C 11 1839
SNT TRC
FID C 11 597
#NET 25
NET NetR21_2
SNT TOP T 64 1
FID C 9 450
FID C 10 494
FID C 11 1862
SNT TOP T 44 8
FID C 9 447
FID C 10 491
FID C 11 1859
SNT TRC
FID C 11 650
SNT TRC
FID C 11 654
#NET 26
NET NetR27_2
SNT TOP T 43 10
FID C 9 603
FID C 10 655
FID C 11 2021
SNT TOP T 58 1
FID C 9 629
FID C 10 682
FID C 11 2048
SNT TRC
FID C 11 917
SNT TRC
FID C 11 953
SNT TRC
FID C 11 966
#NET 27
NET NetR32_1
SNT TOP T 49 1
FID C 9 660
FID C 10 717
FID C 11 2083
SNT TOP T 51 1
FID C 9 662
FID C 10 719
FID C 11 2085
SNT TOP T 53 0
FID C 9 661
FID C 10 718
FID C 11 2084
SNT TRC
FID C 11 1058
SNT TRC
FID C 11 1059
SNT TRC
FID C 11 1057
#NET 28
NET NetR33_1
SNT TOP T 50 1
FID C 9 670
FID C 10 732
FID C 11 2098
SNT TOP T 52 0
FID C 9 669
FID C 10 731
FID C 11 2097
SNT TOP T 48 1
FID C 9 668
FID C 10 728
FID C 11 2094
SNT TRC
FID C 11 1092
SNT TRC
FID C 11 1091
SNT TRC
FID C 11 1088
#NET 29
NET NetR42_1
SNT TOP T 32 0
FID C 9 461
FID C 10 505
FID C 11 1873
SNT TOP T 38 4
FID C 9 462
FID C 10 506
FID C 11 1874
SNT TRC
FID C 11 720
SNT TRC
FID C 11 719
#NET 30
NET NetR43_2
SNT TOP T 33 1
FID C 9 163
FID C 10 193
FID C 11 1565
SNT TOP T 34 10
FID C 9 154
FID C 10 184
FID C 11 1556
SNT TRC
FID C 11 253
SNT TRC
FID C 11 233
#NET 31
NET NetU6_3
SNT TOP T 43 9
FID C 9 602
FID C 10 654
FID C 11 2020
SNT TOP T 43 2
FID C 9 581
FID C 10 629
FID C 11 1995
SNT TRC
FID C 8 182
SNT TRC
FID C 8 184
SNT TRC
FID C 8 186
SNT TRC
FID C 11 859
SNT TRC
FID C 11 879
SNT TRC
FID C 11 916
SNT TRC
FID C 11 928
SNT TRC
FID C 11 934
SNT VIA
FID C 7 491
FID C 8 676
FID C 10 1215
FID C 11 2585
FID H 12 412
SNT VIA
FID C 7 509
FID C 8 694
FID C 10 1233
FID C 11 2603
FID H 12 430
#NET 32
NET NetU16_3
SNT TOP T 34 9
FID C 9 153
FID C 10 183
FID C 11 1555
SNT TOP T 34 2
FID C 9 102
FID C 10 128
FID C 11 1501
SNT TRC
FID C 11 169
SNT TRC
FID C 11 170
SNT TRC
FID C 11 184
SNT TRC
FID C 11 210
#NET 33
NET NetJP2_2
SNT TOP T 2 1
FID C 3 550
FID C 7 47
FID C 8 235
FID C 10 199
FID C 11 1571
FID H 12 30
SNT TOP T 34 0
FID C 9 104
FID C 10 130
FID C 11 1503
SNT TRC
FID C 3 159
SNT TRC
FID C 3 127
SNT TRC
FID C 3 132
SNT TRC
FID C 3 160
SNT TRC
FID C 11 149
SNT TRC
FID C 11 152
SNT TRC
FID C 11 166
SNT TRC
FID C 11 150
SNT TRC
FID C 11 148
SNT VIA
FID C 3 567
FID C 7 190
FID C 8 375
FID C 10 914
FID C 11 2284
FID H 12 111
#NET 34
NET NetJP1_2
SNT TOP T 3 1
FID C 7 32
FID C 8 222
FID C 10 80
FID C 11 1454
FID H 12 23
SNT TOP T 34 3
FID C 9 101
FID C 10 127
FID C 11 1500
SNT TRC
FID C 11 143
SNT TRC
FID C 11 142
#NET 35
NET NetJ4_3
SNT TOP T 34 7
FID C 9 97
FID C 10 123
FID C 11 1496
SNT TOP T 35 8
FID C 9 218
FID C 10 253
FID C 11 1626
SNT TRC
FID C 11 174
SNT TRC
FID C 11 173
SNT TRC
FID C 11 167
SNT TRC
FID C 11 175
SNT TRC
FID C 11 291
SNT TRC
FID C 11 316
SNT TRC
FID C 11 188
#NET 36
NET NetJ4_2
SNT TOP T 34 8
FID C 9 152
FID C 10 182
FID C 11 1554
SNT TOP T 35 7
FID C 9 228
FID C 10 263
FID C 11 1636
SNT TRC
FID C 3 154
SNT TRC
FID C 3 155
SNT TRC
FID C 11 232
SNT TRC
FID C 11 246
SNT TRC
FID C 11 247
SNT TRC
FID C 11 323
SNT TRC
FID C 11 324
SNT VIA
FID C 3 577
FID C 7 230
FID C 8 415
FID C 10 954
FID C 11 2324
FID H 12 151
SNT VIA
FID C 3 589
FID C 7 272
FID C 8 457
FID C 10 996
FID C 11 2366
FID H 12 193
#NET 37
NET 5721_STATUS
SNT TOP T 77 147
FID C 9 362
FID C 10 402
FID C 11 1770
SNT TOP T 39 1
FID C 9 506
FID C 10 550
FID C 11 1918
SNT TRC
FID C 2 438
SNT TRC
FID C 2 437
SNT TRC
FID C 3 347
SNT TRC
FID C 3 457
SNT TRC
FID C 3 459
SNT TRC
FID C 3 466
SNT TRC
FID C 11 742
SNT TRC
FID C 11 741
SNT TRC
FID C 11 743
SNT TRC
FID C 11 767
SNT TRC
FID C 11 515
SNT TRC
FID C 11 516
SNT VIA
FID C 2 614
FID C 7 469
FID C 8 654
FID C 10 1193
FID C 11 2563
FID H 12 390
SNT VIA
FID C 2 615
FID C 3 673
FID C 7 470
FID C 8 655
FID C 10 1194
FID C 11 2564
FID H 12 391
SNT VIA
FID C 3 635
FID C 7 377
FID C 8 562
FID C 10 1101
FID C 11 2471
FID H 12 298
#NET 38
NET SDA
SNT TOP T 77 144
FID C 9 355
FID C 10 395
FID C 11 1763
SNT TOP T 38 9
FID C 9 463
FID C 10 507
FID C 11 1875
SNT TOP T 39 3
FID C 9 452
FID C 10 496
FID C 11 1864
SNT TOP T 12 14
FID C 9 424
FID C 10 467
FID C 11 1835
SNT TOP T 0 3
FID C 9 431
FID C 10 474
FID C 11 1842
SNT TRC
FID C 2 423
SNT TRC
FID C 2 422
SNT TRC
FID C 2 420
SNT TRC
FID C 2 418
SNT TRC
FID C 2 421
SNT TRC
FID C 2 419
SNT TRC
FID C 3 349
SNT TRC
FID C 3 344
SNT TRC
FID C 11 507
SNT TRC
FID C 11 511
SNT TRC
FID C 11 721
SNT TRC
FID C 11 605
SNT TRC
FID C 11 609
SNT TRC
FID C 11 611
SNT TRC
FID C 11 626
SNT TRC
FID C 11 600
SNT TRC
FID C 11 589
SNT TRC
FID C 11 724
SNT TRC
FID C 11 722
SNT TRC
FID C 11 726
SNT TRC
FID C 11 643
SNT TRC
FID C 11 723
SNT TRC
FID C 11 625
SNT TRC
FID C 11 606
SNT TRC
FID C 11 604
SNT TRC
FID C 11 610
SNT TRC
FID C 11 699
SNT TRC
FID C 11 644
SNT TRC
FID C 11 666
SNT TRC
FID C 11 668
SNT TRC
FID C 11 669
SNT TRC
FID C 11 670
SNT VIA
FID C 2 609
FID C 3 667
FID C 7 451
FID C 8 636
FID C 10 1175
FID C 11 2545
FID H 12 372
SNT VIA
FID C 3 634
FID C 7 376
FID C 8 561
FID C 10 1100
FID C 11 2470
FID H 12 297
SNT VIA
FID C 2 608
FID C 7 450
FID C 8 635
FID C 10 1174
FID C 11 2544
FID H 12 371
SNT VIA
FID C 2 607
FID C 7 449
FID C 8 634
FID C 10 1173
FID C 11 2543
FID H 12 370
#NET 39
NET SCL
SNT TOP T 77 150
FID C 9 372
FID C 10 412
FID C 11 1780
SNT TOP T 38 1
FID C 9 457
FID C 10 501
FID C 11 1869
SNT TOP T 39 2
FID C 9 459
FID C 10 503
FID C 11 1871
SNT TOP T 12 15
FID C 9 425
FID C 10 468
FID C 11 1836
SNT TOP T 0 1
FID C 9 435
FID C 10 478
FID C 11 1846
SNT TRC
FID C 2 401
SNT TRC
FID C 2 404
SNT TRC
FID C 2 402
SNT TRC
FID C 2 403
SNT TRC
FID C 2 405
SNT TRC
FID C 3 350
SNT TRC
FID C 11 526
SNT TRC
FID C 11 525
SNT TRC
FID C 11 534
SNT TRC
FID C 11 689
SNT TRC
FID C 11 697
SNT TRC
FID C 11 710
SNT TRC
FID C 11 672
SNT TRC
FID C 11 702
SNT TRC
FID C 11 693
SNT TRC
FID C 11 688
SNT TRC
FID C 11 692
SNT TRC
FID C 11 660
SNT TRC
FID C 11 649
SNT TRC
FID C 11 652
SNT TRC
FID C 11 617
SNT TRC
FID C 11 616
SNT TRC
FID C 11 594
SNT TRC
FID C 11 593
SNT TRC
FID C 11 590
SNT TRC
FID C 11 595
SNT TRC
FID C 11 655
SNT TRC
FID C 11 639
SNT TRC
FID C 11 642
SNT TRC
FID C 11 624
SNT VIA
FID C 2 597
FID C 3 656
FID C 7 428
FID C 8 613
FID C 10 1152
FID C 11 2522
FID H 12 349
SNT VIA
FID C 3 637
FID C 7 381
FID C 8 566
FID C 10 1105
FID C 11 2475
FID H 12 302
SNT VIA
FID C 2 598
FID C 7 429
FID C 8 614
FID C 10 1153
FID C 11 2523
FID H 12 350
SNT VIA
FID C 2 599
FID C 7 430
FID C 8 615
FID C 10 1154
FID C 11 2524
FID H 12 351
#NET 40
NET SCK
SNT TOP T 77 28
FID C 9 491
FID C 10 535
FID C 11 1903
SNT TOP T 42 18
FID C 9 741
FID C 10 813
FID C 11 2179
SNT TRC
FID C 2 409
SNT TRC
FID C 2 410
SNT TRC
FID C 2 413
SNT TRC
FID C 2 412
SNT TRC
FID C 3 549
SNT TRC
FID C 3 437
SNT TRC
FID C 3 441
SNT TRC
FID C 11 1264
SNT TRC
FID C 11 1265
SNT TRC
FID C 11 727
SNT TRC
FID C 11 683
SNT TRC
FID C 11 667
SNT VIA
FID C 3 713
FID C 7 570
FID C 8 755
FID C 10 1294
FID C 11 2664
FID H 12 491
SNT VIA
FID C 2 602
FID C 7 436
FID C 8 621
FID C 10 1160
FID C 11 2530
FID H 12 357
SNT VIA
FID C 2 604
FID C 3 665
FID C 7 446
FID C 8 631
FID C 10 1170
FID C 11 2540
FID H 12 367
#NET 41
NET MAC_10Mout
SNT TOP T 13 8
FID C 2 484
FID C 7 133
FID C 8 315
FID C 10 704
FID C 11 2070
FID H 12 54
SNT TOP T 40 20
FID C 2 485
FID C 7 141
FID C 8 323
FID C 10 737
FID C 11 2103
FID H 12 62
SNT TOP T 40 22
FID C 2 486
FID C 7 143
FID C 8 325
FID C 10 739
FID C 11 2105
FID H 12 64
SNT TOP T 77 116
FID C 9 277
FID C 10 317
FID C 11 1685
SNT TOP T 77 94
FID C 9 210
FID C 10 245
FID C 11 1618
SNT TOP T 77 96
FID C 9 214
FID C 10 249
FID C 11 1622
SNT TOP T 4 0
FID C 9 39
FID C 10 61
FID C 11 1435
SNT TRC
FID C 2 475
SNT TRC
FID C 2 476
SNT TRC
FID C 2 473
SNT TRC
FID C 2 472
SNT TRC
FID C 2 471
SNT TRC
FID C 2 479
SNT TRC
FID C 2 480
SNT TRC
FID C 2 478
SNT TRC
FID C 2 477
SNT TRC
FID C 2 474
SNT TRC
FID C 3 227
SNT TRC
FID C 3 98
SNT TRC
FID C 3 225
SNT TRC
FID C 3 95
SNT TRC
FID C 3 93
SNT TRC
FID C 3 94
SNT TRC
FID C 3 187
SNT TRC
FID C 11 371
SNT TRC
FID C 11 384
SNT TRC
FID C 11 314
SNT TRC
FID C 11 315
SNT TRC
FID C 11 304
SNT TRC
FID C 11 107
SNT TRC
FID C 11 99
SNT TRC
FID C 11 98
SNT TRC
FID C 11 1104
SNT TRC
FID C 11 1103
SNT VIA
FID C 2 632
FID C 3 701
FID C 7 540
FID C 8 725
FID C 10 1264
FID C 11 2634
FID H 12 461
SNT VIA
FID C 3 605
FID C 7 304
FID C 8 489
FID C 10 1028
FID C 11 2398
FID H 12 225
SNT VIA
FID C 2 631
FID C 3 700
FID C 7 539
FID C 8 724
FID C 10 1263
FID C 11 2633
FID H 12 460
SNT VIA
FID C 3 588
FID C 7 270
FID C 8 455
FID C 10 994
FID C 11 2364
FID H 12 191
SNT VIA
FID C 3 554
FID C 7 170
FID C 8 355
FID C 10 894
FID C 11 2264
FID H 12 91
#NET 42
NET OE_5356
SNT TOP T 77 89
FID C 9 195
FID C 10 230
FID C 11 1603
SNT TOP T 38 0
FID C 9 454
FID C 10 498
FID C 11 1866
SNT TRC
FID C 2 406
SNT TRC
FID C 2 407
SNT TRC
FID C 2 408
SNT TRC
FID C 2 169
SNT TRC
FID C 2 165
SNT TRC
FID C 3 316
SNT TRC
FID C 3 194
SNT TRC
FID C 3 314
SNT TRC
FID C 3 427
SNT TRC
FID C 3 429
SNT TRC
FID C 3 426
SNT TRC
FID C 3 183
SNT TRC
FID C 3 193
SNT TRC
FID C 11 659
SNT TRC
FID C 11 658
SNT TRC
FID C 11 656
SNT TRC
FID C 11 292
SNT VIA
FID C 2 600
FID C 7 431
FID C 8 616
FID C 10 1155
FID C 11 2525
FID H 12 352
SNT VIA
FID C 2 601
FID C 3 658
FID C 7 433
FID C 8 618
FID C 10 1157
FID C 11 2527
FID H 12 354
SNT VIA
FID C 2 522
FID C 3 585
FID C 7 260
FID C 8 445
FID C 10 984
FID C 11 2354
FID H 12 181
SNT VIA
FID C 2 519
FID C 7 255
FID C 8 440
FID C 10 979
FID C 11 2349
FID H 12 176
#NET 43
NET NetR19_2
SNT TOP T 66 1
FID C 9 411
FID C 10 454
FID C 11 1822
SNT TOP T 44 2
FID C 9 412
FID C 10 455
FID C 11 1823
SNT TRC
FID C 11 577
#NET 44
NET NetR2_1
SNT TOP T 46 6
FID C 9 789
FID C 10 866
FID C 11 2232
SNT TOP T 74 0
FID C 9 784
FID C 10 861
FID C 11 2227
SNT TRC
FID C 11 1362
SNT TRC
FID C 11 1356
SNT TRC
FID C 11 1355
#NET 45
NET NetJ3_3
SNT TOP T 43 7
FID C 9 576
FID C 10 624
FID C 11 1990
SNT TOP T 80 8
FID C 9 586
FID C 10 635
FID C 11 2001
SNT TRC
FID C 11 873
SNT TRC
FID C 11 872
SNT TRC
FID C 11 870
SNT TRC
FID C 11 883
SNT TRC
FID C 11 857
#NET 46
NET NetJ3_2
SNT TOP T 43 8
FID C 9 601
FID C 10 653
FID C 11 2019
SNT TOP T 80 7
FID C 9 587
FID C 10 636
FID C 11 2002
SNT TRC
FID C 11 886
SNT TRC
FID C 11 902
SNT TRC
FID C 11 908
SNT TRC
FID C 11 885
SNT TRC
FID C 11 910
#NET 47
NET NetD14_1
SNT TOP T 54 1
FID C 9 50
FID C 10 72
FID C 11 1446
SNT TOP T 90 0
FID C 9 51
FID C 10 73
FID C 11 1447
SNT TRC
FID C 11 126
SNT TRC
FID C 11 127
#NET 48
NET NetD13_1
SNT TOP T 55 1
FID C 9 42
FID C 10 64
FID C 11 1438
SNT TOP T 91 0
FID C 9 43
FID C 10 65
FID C 11 1439
SNT TRC
FID C 11 112
SNT TRC
FID C 11 113
#NET 49
NET NetD10_1
SNT TOP T 59 1
FID C 9 561
FID C 10 609
FID C 11 1975
SNT TOP T 94 0
FID C 9 516
FID C 10 562
FID C 11 1930
SNT TRC
FID C 11 815
SNT TRC
FID C 11 780
SNT TRC
FID C 11 794
#NET 50
NET NetD9_1
SNT TOP T 60 1
FID C 9 562
FID C 10 610
FID C 11 1976
SNT TOP T 95 0
FID C 9 519
FID C 10 565
FID C 11 1933
SNT TRC
FID C 11 783
SNT TRC
FID C 11 796
SNT TRC
FID C 11 816
#NET 51
NET NetD4_1
SNT TOP T 100 0
FID C 9 646
FID C 10 700
FID C 11 2066
SNT TOP T 75 1
FID C 9 638
FID C 10 692
FID C 11 2058
SNT TRC
FID C 11 1007
#NET 52
NET NetD2_2
SNT TOP T 81 3
FID C 7 153
FID C 8 335
FID C 10 860
FID C 11 2226
FID H 12 74
SNT TOP T 81 4
FID C 7 155
FID C 8 337
FID C 10 872
FID C 11 2238
FID H 12 76
SNT TOP T 81 2
FID C 7 150
FID C 8 332
FID C 10 828
FID C 11 2194
FID H 12 71
SNT TOP T 102 1
FID C 9 709
FID C 10 781
FID C 11 2147
SNT TRC
FID C 11 1295
SNT TRC
FID C 11 1352
SNT TRC
FID C 11 1294
SNT TRC
FID C 11 1272
SNT TRC
FID C 11 1235
SNT TRC
FID C 11 1234
SNT TRC
FID C 11 1226
SNT TRC
FID C 11 1207
#NET 53
NET NetD2_1
SNT TOP T 47 0
FID C 7 145
FID C 8 327
FID C 10 743
FID C 11 2109
FID H 12 66
SNT TOP T 101 0
FID C 9 693
FID C 10 765
FID C 11 2131
SNT TOP T 85 0
FID C 9 684
FID C 10 754
FID C 11 2120
SNT TOP T 102 0
FID C 9 694
FID C 10 766
FID C 11 2132
SNT TRC
FID C 11 1135
SNT TRC
FID C 11 1136
SNT TRC
FID C 11 1153
SNT TRC
FID C 11 1147
SNT TRC
FID C 11 1138
SNT TRC
FID C 11 1118
SNT TRC
FID C 11 1165
SNT TRC
FID C 11 1175
SNT TRC
FID C 11 1166
SNT TRC
FID C 11 1159
SNT TRC
FID C 11 1160
SNT TRC
FID C 11 1164
SNT TRC
FID C 11 1158
SNT TRC
FID C 11 1157
SNT TRC
FID C 11 1162
SNT TRC
FID C 11 1163
SNT TRC
FID C 11 1113
SNT TRC
FID C 11 1137
#NET 54
NET NetD1_2
SNT TOP T 82 0
FID C 7 147
FID C 8 329
FID C 10 756
FID C 11 2122
FID H 12 68
SNT TOP T 103 1
FID C 9 680
FID C 10 750
FID C 11 2116
SNT TRC
FID C 11 1128
SNT TRC
FID C 11 1134
SNT TRC
FID C 11 1139
#NET 55
NET NetD1_1
SNT TOP T 47 1
FID C 7 144
FID C 8 326
FID C 10 742
FID C 11 2108
FID H 12 65
SNT TOP T 103 0
FID C 9 677
FID C 10 746
FID C 11 2112
SNT TRC
FID C 11 1121
SNT TRC
FID C 11 1112
SNT TRC
FID C 11 1115
SNT TRC
FID C 11 1111
SNT TRC
FID C 11 1120
#NET 56
NET NetC49_1
SNT TOP B 9 0
FID C 1 55
FID C 7 95
FID C 8 279
SNT TOP T 76 21
FID C 1 54
FID C 7 94
FID C 8 278
SNT TRC
FID C 8 118
SNT TRC
FID C 8 14
SNT TRC
FID C 8 115
SNT TRC
FID C 8 15
#NET 57
NET NetC22_2
SNT TOP T 68 1
FID C 9 678
FID C 10 748
FID C 11 2114
SNT TOP T 117 1
FID C 9 683
FID C 10 753
FID C 11 2119
SNT TRC
FID C 11 1131
SNT TRC
FID C 11 1129
SNT TRC
FID C 11 1125
SNT TRC
FID C 11 1127
#NET 58
NET NetC22_1
SNT TOP T 117 0
FID C 9 682
FID C 10 752
FID C 11 2118
SNT TOP T 45 5
FID C 9 691
FID C 10 763
FID C 11 2129
SNT TRC
FID C 11 1133
SNT TRC
FID C 11 1132
#NET 59
NET NetC21_2
SNT TOP T 118 1
FID C 9 688
FID C 10 760
FID C 11 2126
SNT TOP T 45 7
FID C 9 689
FID C 10 761
FID C 11 2127
SNT TRC
FID C 11 1150
SNT TRC
FID C 11 1149
#NET 60
NET NetC20_2
SNT TOP T 69 1
FID C 9 799
FID C 10 879
FID C 11 2245
SNT TOP T 119 1
FID C 9 795
FID C 10 875
FID C 11 2241
SNT TRC
FID C 11 1380
SNT TRC
FID C 11 1377
#NET 61
NET NetC20_1
SNT TOP T 46 5
FID C 9 788
FID C 10 865
FID C 11 2231
SNT TOP T 119 0
FID C 9 796
FID C 10 876
FID C 11 2242
SNT TRC
FID C 11 1376
SNT TRC
FID C 11 1365
#NET 62
NET NetC19_2
SNT TOP T 46 7
FID C 9 790
FID C 10 867
FID C 11 2233
SNT TOP T 120 1
FID C 9 792
FID C 10 869
FID C 11 2235
SNT TRC
FID C 11 1371
SNT TRC
FID C 11 1367
SNT TRC
FID C 11 1366
#NET 63
NET NetC4_2
SNT TOP T 46 2
FID C 9 764
FID C 10 839
FID C 11 2205
SNT TOP T 79 1
FID C 9 701
FID C 10 773
FID C 11 2139
SNT TOP T 135 1
FID C 9 753
FID C 10 825
FID C 11 2191
SNT TRC
FID C 11 1283
SNT TRC
FID C 11 1284
SNT TRC
FID C 11 1287
SNT TRC
FID C 11 1194
SNT TRC
FID C 11 1222
SNT TRC
FID C 11 1268
#NET 64
NET NetC4_1
SNT TOP T 46 0
FID C 9 766
FID C 10 841
FID C 11 2207
SNT TOP T 135 0
FID C 9 754
FID C 10 826
FID C 11 2192
SNT TRC
FID C 11 1285
SNT TRC
FID C 11 1286
#NET 65
NET NetC3_2
SNT TOP T 136 1
FID C 9 739
FID C 10 811
FID C 11 2177
SNT TOP T 78 1
FID C 9 777
FID C 10 852
FID C 11 2218
SNT TOP T 45 2
FID C 9 712
FID C 10 784
FID C 11 2150
SNT TRC
FID C 11 1210
SNT TRC
FID C 11 1230
SNT TRC
FID C 11 1243
SNT TRC
FID C 11 1260
SNT TRC
FID C 11 1321
SNT TRC
FID C 11 1333
#NET 66
NET NetC3_1
SNT TOP T 136 0
FID C 9 738
FID C 10 810
FID C 11 2176
SNT TOP T 45 0
FID C 9 710
FID C 10 782
FID C 11 2148
SNT TRC
FID C 11 1258
SNT TRC
FID C 11 1209
#NET 67
NET MOSI
SNT TOP T 77 24
FID C 9 493
FID C 10 537
FID C 11 1905
SNT TOP T 42 16
FID C 9 735
FID C 10 807
FID C 11 2173
SNT TRC
FID C 2 395
SNT TRC
FID C 2 396
SNT TRC
FID C 2 397
SNT TRC
FID C 3 468
SNT TRC
FID C 3 470
SNT TRC
FID C 3 413
SNT TRC
FID C 11 1248
SNT TRC
FID C 11 1242
SNT TRC
FID C 11 1232
SNT TRC
FID C 11 661
SNT TRC
FID C 11 712
SNT TRC
FID C 11 641
SNT VIA
FID C 3 709
FID C 7 563
FID C 8 748
FID C 10 1287
FID C 11 2657
FID H 12 484
SNT VIA
FID C 2 595
FID C 3 655
FID C 7 425
FID C 8 610
FID C 10 1149
FID C 11 2519
FID H 12 346
SNT VIA
FID C 2 594
FID C 7 424
FID C 8 609
FID C 10 1148
FID C 11 2518
FID H 12 345
#NET 68
NET MISO
SNT TOP T 77 26
FID C 9 492
FID C 10 536
FID C 11 1904
SNT TOP T 42 19
FID C 9 752
FID C 10 824
FID C 11 2190
SNT TRC
FID C 2 417
SNT TRC
FID C 2 415
SNT TRC
FID C 2 414
SNT TRC
FID C 2 416
SNT TRC
FID C 3 445
SNT TRC
FID C 11 1281
SNT TRC
FID C 11 1274
SNT TRC
FID C 11 704
SNT TRC
FID C 11 728
SNT VIA
FID C 2 606
FID C 3 666
FID C 7 448
FID C 8 633
FID C 10 1172
FID C 11 2542
FID H 12 369
SNT VIA
FID C 3 714
FID C 7 571
FID C 8 756
FID C 10 1295
FID C 11 2665
FID H 12 492
SNT VIA
FID C 2 605
FID C 7 447
FID C 8 632
FID C 10 1171
FID C 11 2541
FID H 12 368
#NET 69
NET MAC_USB_PWR
SNT TOP T 77 91
FID C 9 200
FID C 10 235
FID C 11 1608
SNT TOP T 40 5
FID C 9 590
FID C 10 639
FID C 11 2005
SNT TRC
FID C 2 170
SNT TRC
FID C 2 171
SNT TRC
FID C 2 172
SNT TRC
FID C 3 501
SNT TRC
FID C 3 509
SNT TRC
FID C 3 499
SNT TRC
FID C 3 464
SNT TRC
FID C 3 456
SNT TRC
FID C 3 184
SNT TRC
FID C 11 296
SNT TRC
FID C 11 911
SNT TRC
FID C 11 893
SNT TRC
FID C 11 926
SNT TRC
FID C 11 927
SNT TRC
FID C 11 889
SNT VIA
FID C 2 524
FID C 3 586
FID C 7 262
FID C 8 447
FID C 10 986
FID C 11 2356
FID H 12 183
SNT VIA
FID C 2 523
FID C 7 261
FID C 8 446
FID C 10 985
FID C 11 2355
FID H 12 182
SNT VIA
FID C 3 689
FID C 7 506
FID C 8 691
FID C 10 1230
FID C 11 2600
FID H 12 427
#NET 70
NET MAC_USB-
SNT TOP T 77 157
FID C 9 386
FID C 10 426
FID C 11 1794
SNT TOP T 40 3
FID C 9 589
FID C 10 638
FID C 11 2004
SNT TRC
FID C 2 350
SNT TRC
FID C 2 351
SNT TRC
FID C 3 496
SNT TRC
FID C 3 373
SNT TRC
FID C 3 497
SNT TRC
FID C 3 516
SNT TRC
FID C 3 513
SNT TRC
FID C 3 512
SNT TRC
FID C 3 507
SNT TRC
FID C 11 557
SNT TRC
FID C 11 556
SNT TRC
FID C 11 558
SNT TRC
FID C 11 892
SNT TRC
FID C 11 921
SNT TRC
FID C 11 909
SNT TRC
FID C 11 888
SNT VIA
FID C 2 578
FID C 3 640
FID C 7 395
FID C 8 580
FID C 10 1119
FID C 11 2489
FID H 12 316
SNT VIA
FID C 2 579
FID C 7 396
FID C 8 581
FID C 10 1120
FID C 11 2490
FID H 12 317
SNT VIA
FID C 3 688
FID C 7 504
FID C 8 689
FID C 10 1228
FID C 11 2598
FID H 12 425
#NET 71
NET MAC_USB+
SNT TOP T 77 155
FID C 9 382
FID C 10 422
FID C 11 1790
SNT TOP T 40 1
FID C 9 588
FID C 10 637
FID C 11 2003
SNT TRC
FID C 2 349
SNT TRC
FID C 3 491
SNT TRC
FID C 3 498
SNT TRC
FID C 3 485
SNT TRC
FID C 3 418
SNT TRC
FID C 3 422
SNT TRC
FID C 3 356
SNT TRC
FID C 3 500
SNT TRC
FID C 3 505
SNT TRC
FID C 3 510
SNT TRC
FID C 11 551
SNT TRC
FID C 11 544
SNT TRC
FID C 11 543
SNT TRC
FID C 11 900
SNT TRC
FID C 11 912
SNT TRC
FID C 11 887
SNT TRC
FID C 11 898
SNT TRC
FID C 11 899
SNT VIA
FID C 2 576
FID C 3 638
FID C 7 391
FID C 8 576
FID C 10 1115
FID C 11 2485
FID H 12 312
SNT VIA
FID C 2 577
FID C 7 392
FID C 8 577
FID C 10 1116
FID C 11 2486
FID H 12 313
SNT VIA
FID C 3 687
FID C 7 503
FID C 8 688
FID C 10 1227
FID C 11 2597
FID H 12 424
#NET 72
NET MAC_TX
SNT TOP T 13 2
FID C 7 137
FID C 8 319
FID C 10 729
FID C 11 2095
FID H 12 58
SNT TOP T 40 27
FID C 3 552
FID C 7 131
FID C 8 313
FID C 10 702
FID C 11 2068
FID H 12 52
SNT TOP T 77 109
FID C 9 253
FID C 10 293
FID C 11 1661
SNT TOP T 10 0
FID C 9 53
FID C 10 75
FID C 11 1449
SNT TRC
FID C 11 1086
SNT TRC
FID C 11 1087
SNT TRC
FID C 11 1072
SNT TRC
FID C 3 527
SNT TRC
FID C 3 229
SNT TRC
FID C 3 134
SNT TRC
FID C 3 115
SNT TRC
FID C 3 180
SNT TRC
FID C 3 224
SNT TRC
FID C 3 188
SNT TRC
FID C 3 114
SNT TRC
FID C 3 117
SNT TRC
FID C 3 118
SNT TRC
FID C 3 119
SNT TRC
FID C 3 116
SNT TRC
FID C 11 1026
SNT TRC
FID C 11 138
SNT TRC
FID C 11 135
SNT TRC
FID C 11 365
SNT TRC
FID C 11 369
SNT TRC
FID C 11 350
SNT TRC
FID C 11 355
SNT TRC
FID C 11 356
SNT TRC
FID C 11 351
SNT VIA
FID C 3 562
FID C 7 183
FID C 8 368
FID C 10 907
FID C 11 2277
FID H 12 104
SNT VIA
FID C 3 604
FID C 7 303
FID C 8 488
FID C 10 1027
FID C 11 2397
FID H 12 224
#NET 73
NET MAC_RX
SNT TOP T 13 3
FID C 7 139
FID C 8 321
FID C 10 735
FID C 11 2101
FID H 12 60
SNT TOP T 40 26
FID C 3 551
FID C 7 130
FID C 8 312
FID C 10 689
FID C 11 2055
FID H 12 51
SNT TOP T 77 111
FID C 9 259
FID C 10 299
FID C 11 1667
SNT TOP T 8 0
FID C 9 184
FID C 10 219
FID C 11 1592
SNT TRC
FID C 3 223
SNT TRC
FID C 2 194
SNT TRC
FID C 11 370
SNT TRC
FID C 2 193
SNT TRC
FID C 11 1089
SNT TRC
FID C 11 1102
SNT TRC
FID C 11 1090
SNT TRC
FID C 11 1074
SNT TRC
FID C 2 166
SNT TRC
FID C 2 236
SNT TRC
FID C 2 192
SNT TRC
FID C 2 167
SNT TRC
FID C 2 190
SNT TRC
FID C 2 191
SNT TRC
FID C 3 523
SNT TRC
FID C 11 999
SNT TRC
FID C 11 1019
SNT TRC
FID C 11 290
SNT TRC
FID C 11 283
SNT TRC
FID C 11 361
SNT TRC
FID C 11 362
SNT VIA
FID C 2 540
FID C 3 603
FID C 7 302
FID C 8 487
FID C 10 1026
FID C 11 2396
FID H 12 223
SNT VIA
FID C 2 520
FID C 7 257
FID C 8 442
FID C 10 981
FID C 11 2351
FID H 12 178
#NET 74
NET MAC_PPS_OUT-
SNT TOP T 77 126
FID C 9 300
FID C 10 340
FID C 11 1708
SNT TOP T 40 18
FID C 9 624
FID C 10 677
FID C 11 2043
SNT TRC
FID C 2 262
SNT TRC
FID C 2 263
SNT TRC
FID C 2 264
SNT TRC
FID C 2 265
SNT TRC
FID C 3 517
SNT TRC
FID C 3 514
SNT TRC
FID C 3 480
SNT TRC
FID C 3 478
SNT TRC
FID C 3 450
SNT TRC
FID C 3 446
SNT TRC
FID C 3 291
SNT TRC
FID C 3 286
SNT TRC
FID C 3 287
SNT TRC
FID C 11 941
SNT TRC
FID C 11 946
SNT TRC
FID C 11 942
SNT TRC
FID C 11 412
SNT TRC
FID C 11 413
SNT TRC
FID C 11 415
SNT VIA
FID C 2 553
FID C 3 618
FID C 7 333
FID C 8 518
FID C 10 1057
FID C 11 2427
FID H 12 254
SNT VIA
FID C 3 692
FID C 7 511
FID C 8 696
FID C 10 1235
FID C 11 2605
FID H 12 432
SNT VIA
FID C 2 551
FID C 7 331
FID C 8 516
FID C 10 1055
FID C 11 2425
FID H 12 252
#NET 75
NET MAC_PPS_OUT+
SNT TOP T 13 7
FID C 7 134
FID C 8 316
FID C 10 722
FID C 11 2088
FID H 12 55
SNT TOP T 40 16
FID C 9 623
FID C 10 676
FID C 11 2042
SNT TOP T 77 124
FID C 9 295
FID C 10 335
FID C 11 1703
SNT TOP T 5 0
FID C 9 37
FID C 10 59
FID C 11 1433
SNT TRC
FID C 11 978
SNT TRC
FID C 11 973
SNT TRC
FID C 11 403
SNT TRC
FID C 11 967
SNT TRC
FID C 11 951
SNT TRC
FID C 11 995
SNT TRC
FID C 11 980
SNT TRC
FID C 3 525
SNT TRC
FID C 3 524
SNT TRC
FID C 3 461
SNT TRC
FID C 3 460
SNT TRC
FID C 11 402
SNT TRC
FID C 3 273
SNT TRC
FID C 2 259
SNT TRC
FID C 11 401
SNT TRC
FID C 11 94
SNT TRC
FID C 3 256
SNT TRC
FID C 3 96
SNT TRC
FID C 11 102
SNT TRC
FID C 11 95
SNT TRC
FID C 11 103
SNT VIA
FID C 3 694
FID C 7 519
FID C 8 704
FID C 10 1243
FID C 11 2613
FID H 12 440
SNT VIA
FID C 2 549
FID C 7 325
FID C 8 510
FID C 10 1049
FID C 11 2419
FID H 12 246
SNT VIA
FID C 2 550
FID C 3 615
FID C 7 326
FID C 8 511
FID C 10 1050
FID C 11 2420
FID H 12 247
SNT VIA
FID C 3 553
FID C 7 168
FID C 8 353
FID C 10 892
FID C 11 2262
FID H 12 89
#NET 76
NET MAC_PPS_IN1-
SNT TOP T 77 136
FID C 9 326
FID C 10 366
FID C 11 1734
SNT TOP T 40 2
FID C 9 616
FID C 10 669
FID C 11 2035
SNT TRC
FID C 2 298
SNT TRC
FID C 2 299
SNT TRC
FID C 2 300
SNT TRC
FID C 3 526
SNT TRC
FID C 3 479
SNT TRC
FID C 3 506
SNT TRC
FID C 3 508
SNT TRC
FID C 3 318
SNT TRC
FID C 3 390
SNT TRC
FID C 3 477
SNT TRC
FID C 3 388
SNT TRC
FID C 11 476
SNT TRC
FID C 11 470
SNT TRC
FID C 11 469
SNT TRC
FID C 11 981
SNT TRC
FID C 11 970
SNT TRC
FID C 11 947
SNT TRC
FID C 11 998
SNT VIA
FID C 2 566
FID C 3 627
FID C 7 356
FID C 8 541
FID C 10 1080
FID C 11 2450
FID H 12 277
SNT VIA
FID C 2 567
FID C 7 361
FID C 8 546
FID C 10 1085
FID C 11 2455
FID H 12 282
SNT VIA
FID C 3 696
FID C 7 522
FID C 8 707
FID C 10 1246
FID C 11 2616
FID H 12 443
#NET 77
NET MAC_PPS_IN1+
SNT TOP T 77 134
FID C 9 321
FID C 10 361
FID C 11 1729
SNT TOP T 40 0
FID C 9 615
FID C 10 668
FID C 11 2034
SNT TRC
FID C 2 292
SNT TRC
FID C 2 294
SNT TRC
FID C 2 293
SNT TRC
FID C 3 515
SNT TRC
FID C 3 462
SNT TRC
FID C 3 455
SNT TRC
FID C 3 315
SNT TRC
FID C 11 459
SNT TRC
FID C 11 458
SNT TRC
FID C 11 462
SNT TRC
FID C 11 465
SNT TRC
FID C 11 461
SNT TRC
FID C 11 940
SNT TRC
FID C 11 939
SNT TRC
FID C 11 945
SNT VIA
FID C 2 562
FID C 3 626
FID C 7 352
FID C 8 537
FID C 10 1076
FID C 11 2446
FID H 12 273
SNT VIA
FID C 2 563
FID C 7 353
FID C 8 538
FID C 10 1077
FID C 11 2447
FID H 12 274
SNT VIA
FID C 3 691
FID C 7 510
FID C 8 695
FID C 10 1234
FID C 11 2604
FID H 12 431
#NET 78
NET MAC_PPS_IN0-
SNT TOP T 77 130
FID C 9 311
FID C 10 351
FID C 11 1719
SNT TOP T 40 6
FID C 9 618
FID C 10 671
FID C 11 2037
SNT TRC
FID C 2 284
SNT TRC
FID C 2 285
SNT TRC
FID C 3 487
SNT TRC
FID C 3 305
SNT TRC
FID C 3 486
SNT TRC
FID C 3 306
SNT TRC
FID C 11 434
SNT TRC
FID C 11 435
SNT TRC
FID C 11 979
SNT TRC
FID C 11 975
SNT TRC
FID C 11 949
SNT VIA
FID C 2 559
FID C 3 623
FID C 7 344
FID C 8 529
FID C 10 1068
FID C 11 2438
FID H 12 265
SNT VIA
FID C 2 558
FID C 7 343
FID C 8 528
FID C 10 1067
FID C 11 2437
FID H 12 264
SNT VIA
FID C 3 693
FID C 7 518
FID C 8 703
FID C 10 1242
FID C 11 2612
FID H 12 439
#NET 79
NET MAC_PPS_IN0+
SNT TOP T 13 6
FID C 7 136
FID C 8 318
FID C 10 726
FID C 11 2092
FID H 12 57
SNT TOP T 77 128
FID C 9 306
FID C 10 346
FID C 11 1714
SNT TOP T 40 4
FID C 9 617
FID C 10 670
FID C 11 2036
SNT TOP T 7 1
FID C 9 236
FID C 10 271
FID C 11 1644
SNT TOP T 6 0
FID C 9 40
FID C 10 62
FID C 11 1436
SNT TRC
FID C 11 326
SNT TRC
FID C 11 21
SNT TRC
FID C 11 4
SNT TRC
FID C 11 449
SNT TRC
FID C 11 354
SNT TRC
FID C 2 272
SNT TRC
FID C 11 1020
SNT TRC
FID C 11 986
SNT TRC
FID C 2 279
SNT TRC
FID C 2 278
SNT TRC
FID C 2 276
SNT TRC
FID C 2 280
SNT TRC
FID C 2 273
SNT TRC
FID C 2 274
SNT TRC
FID C 2 277
SNT TRC
FID C 2 275
SNT TRC
FID C 2 271
SNT TRC
FID C 2 283
SNT TRC
FID C 2 270
SNT TRC
FID C 3 447
SNT TRC
FID C 3 444
SNT TRC
FID C 3 297
SNT TRC
FID C 3 277
SNT TRC
FID C 3 288
SNT TRC
FID C 3 298
SNT TRC
FID C 3 235
SNT TRC
FID C 3 238
SNT TRC
FID C 3 222
SNT TRC
FID C 3 136
SNT TRC
FID C 3 218
SNT TRC
FID C 3 135
SNT TRC
FID C 3 97
SNT TRC
FID C 11 427
SNT TRC
FID C 11 426
SNT TRC
FID C 11 428
SNT TRC
FID C 11 948
SNT TRC
FID C 11 971
SNT TRC
FID C 11 983
SNT TRC
FID C 11 976
SNT TRC
FID C 11 1082
SNT TRC
FID C 11 100
SNT TRC
FID C 11 105
SNT TRC
FID C 11 101
SNT TRC
FID C 11 106
SNT TRC
FID C 11 325
SNT TRC
FID C 11 327
SNT VIA
FID C 2 561
FID C 7 351
FID C 8 536
FID C 10 1075
FID C 11 2445
FID H 12 272
SNT VIA
FID C 2 555
FID C 3 619
FID C 7 337
FID C 8 522
FID C 10 1061
FID C 11 2431
FID H 12 258
SNT VIA
FID C 2 556
FID C 3 620
FID C 7 338
FID C 8 523
FID C 10 1062
FID C 11 2432
FID H 12 259
SNT VIA
FID C 3 695
FID C 7 520
FID C 8 705
FID C 10 1244
FID C 11 2614
FID H 12 441
SNT VIA
FID C 3 555
FID C 7 171
FID C 8 356
FID C 10 895
FID C 11 2265
FID H 12 92
#NET 80
NET NetBT1_2
SNT TOP T 12 13
FID C 9 423
FID C 10 466
FID C 11 1834
SNT TOP T 14 1
FID C 9 665
FID C 10 723
FID C 11 2089
SNT TRC
FID C 3 443
SNT TRC
FID C 3 476
SNT TRC
FID C 3 394
SNT TRC
FID C 3 404
SNT TRC
FID C 3 402
SNT TRC
FID C 3 528
SNT TRC
FID C 11 601
SNT TRC
FID C 11 591
SNT TRC
FID C 11 588
SNT TRC
FID C 11 1070
SNT TRC
FID C 11 1071
SNT TRC
FID C 11 1075
SNT TRC
FID C 11 1073
SNT VIA
FID C 3 648
FID C 7 412
FID C 8 597
FID C 10 1136
FID C 11 2506
FID H 12 333
SNT VIA
FID C 3 698
FID C 7 535
FID C 8 720
FID C 10 1259
FID C 11 2629
FID H 12 456
#NET 81
NET MAC_BITE
SNT TOP T 13 1
FID C 7 135
FID C 8 317
FID C 10 725
FID C 11 2091
FID H 12 56
SNT TOP T 40 25
FID C 2 483
FID C 7 129
FID C 8 311
FID C 10 665
FID C 11 2031
FID H 12 50
SNT TOP T 77 120
FID C 9 286
FID C 10 326
FID C 11 1694
SNT TRC
FID C 2 470
SNT TRC
FID C 2 469
SNT TRC
FID C 3 255
SNT TRC
FID C 3 246
SNT TRC
FID C 3 253
SNT TRC
FID C 11 392
SNT TRC
FID C 11 393
SNT TRC
FID C 11 1083
SNT TRC
FID C 11 1080
SNT TRC
FID C 11 1085
SNT TRC
FID C 11 938
SNT TRC
FID C 11 1002
SNT VIA
FID C 3 610
FID C 7 315
FID C 8 500
FID C 10 1039
FID C 11 2409
FID H 12 236
SNT VIA
FID C 2 630
FID C 3 690
FID C 7 507
FID C 8 692
FID C 10 1231
FID C 11 2601
FID H 12 428
#NET 82
NET MAC_ALARM
SNT TOP T 77 118
FID C 9 282
FID C 10 322
FID C 11 1690
SNT TOP T 40 19
FID C 9 597
FID C 10 646
FID C 11 2012
SNT TRC
FID C 2 256
SNT TRC
FID C 3 471
SNT TRC
FID C 3 469
SNT TRC
FID C 3 449
SNT TRC
FID C 3 442
SNT TRC
FID C 3 299
SNT TRC
FID C 3 252
SNT TRC
FID C 3 294
SNT TRC
FID C 11 390
SNT TRC
FID C 11 894
SNT TRC
FID C 11 895
SNT TRC
FID C 11 891
SNT TRC
FID C 11 896
SNT TRC
FID C 11 391
SNT VIA
FID C 2 545
FID C 3 612
FID C 7 317
FID C 8 502
FID C 10 1041
FID C 11 2411
FID H 12 238
SNT VIA
FID C 3 686
FID C 7 500
FID C 8 685
FID C 10 1224
FID C 11 2594
FID H 12 421
SNT VIA
FID C 2 546
FID C 7 318
FID C 8 503
FID C 10 1042
FID C 11 2412
FID H 12 239
#NET 83
NET IMU_PS1
SNT TOP T 77 59
FID C 9 532
FID C 10 580
FID C 11 1946
SNT TOP T 42 4
FID C 9 731
FID C 10 803
FID C 11 2169
SNT TRC
FID C 2 468
SNT TRC
FID C 2 466
SNT TRC
FID C 2 465
SNT TRC
FID C 2 467
SNT TRC
FID C 3 538
SNT TRC
FID C 3 537
SNT TRC
FID C 3 520
SNT TRC
FID C 3 504
SNT TRC
FID C 3 503
SNT TRC
FID C 3 502
SNT TRC
FID C 3 519
SNT TRC
FID C 11 803
SNT TRC
FID C 11 862
SNT TRC
FID C 11 871
SNT TRC
FID C 11 897
SNT TRC
FID C 11 1189
SNT TRC
FID C 11 1233
SNT TRC
FID C 11 1236
SNT VIA
FID C 2 628
FID C 7 498
FID C 8 683
FID C 10 1222
FID C 11 2592
FID H 12 419
SNT VIA
FID C 2 629
FID C 3 685
FID C 7 499
FID C 8 684
FID C 10 1223
FID C 11 2593
FID H 12 420
SNT VIA
FID C 3 704
FID C 7 551
FID C 8 736
FID C 10 1275
FID C 11 2645
FID H 12 472
#NET 84
NET IMU_PS0
SNT TOP T 77 57
FID C 9 533
FID C 10 581
FID C 11 1947
SNT TOP T 42 5
FID C 9 721
FID C 10 793
FID C 11 2159
SNT TRC
FID C 2 462
SNT TRC
FID C 2 464
SNT TRC
FID C 2 460
SNT TRC
FID C 2 459
SNT TRC
FID C 2 461
SNT TRC
FID C 3 541
SNT TRC
FID C 3 522
SNT TRC
FID C 3 540
SNT TRC
FID C 3 495
SNT TRC
FID C 3 494
SNT TRC
FID C 3 493
SNT TRC
FID C 3 521
SNT TRC
FID C 11 1205
SNT TRC
FID C 11 1204
SNT TRC
FID C 11 867
SNT TRC
FID C 11 869
SNT TRC
FID C 11 804
SNT VIA
FID C 2 625
FID C 3 684
FID C 7 494
FID C 8 679
FID C 10 1218
FID C 11 2588
FID H 12 415
SNT VIA
FID C 3 707
FID C 7 554
FID C 8 739
FID C 10 1278
FID C 11 2648
FID H 12 475
SNT VIA
FID C 2 627
FID C 7 497
FID C 8 682
FID C 10 1221
FID C 11 2591
FID H 12 418
#NET 85
NET IMU_NRST
SNT TOP T 77 51
FID C 9 536
FID C 10 584
FID C 11 1950
SNT TOP T 42 10
FID C 9 726
FID C 10 798
FID C 11 2164
SNT TRC
FID C 2 453
SNT TRC
FID C 2 446
SNT TRC
FID C 2 445
SNT TRC
FID C 2 447
SNT TRC
FID C 2 450
SNT TRC
FID C 3 490
SNT TRC
FID C 3 533
SNT TRC
FID C 3 536
SNT TRC
FID C 11 805
SNT TRC
FID C 11 819
SNT TRC
FID C 11 832
SNT TRC
FID C 11 854
SNT TRC
FID C 11 874
SNT TRC
FID C 11 875
SNT TRC
FID C 11 1183
SNT TRC
FID C 11 1188
SNT TRC
FID C 11 1206
SNT TRC
FID C 11 1208
SNT VIA
FID C 2 621
FID C 7 487
FID C 8 672
FID C 10 1211
FID C 11 2581
FID H 12 408
SNT VIA
FID C 2 622
FID C 3 682
FID C 7 489
FID C 8 674
FID C 10 1213
FID C 11 2583
FID H 12 410
SNT VIA
FID C 3 702
FID C 7 548
FID C 8 733
FID C 10 1272
FID C 11 2642
FID H 12 469
#NET 86
NET IMU_INT
SNT TOP T 77 49
FID C 9 537
FID C 10 585
FID C 11 1951
SNT TOP T 42 13
FID C 9 729
FID C 10 801
FID C 11 2167
SNT TRC
FID C 2 448
SNT TRC
FID C 2 449
SNT TRC
FID C 2 444
SNT TRC
FID C 2 443
SNT TRC
FID C 3 532
SNT TRC
FID C 3 484
SNT TRC
FID C 3 482
SNT TRC
FID C 3 481
SNT TRC
FID C 3 531
SNT TRC
FID C 11 806
SNT TRC
FID C 11 820
SNT TRC
FID C 11 835
SNT TRC
FID C 11 849
SNT TRC
FID C 11 860
SNT TRC
FID C 11 1201
SNT TRC
FID C 11 1200
SNT TRC
FID C 11 1227
SNT TRC
FID C 11 1225
SNT TRC
FID C 11 1202
SNT TRC
FID C 11 1203
SNT TRC
FID C 11 1213
SNT VIA
FID C 2 619
FID C 7 484
FID C 8 669
FID C 10 1208
FID C 11 2578
FID H 12 405
SNT VIA
FID C 2 618
FID C 3 679
FID C 7 482
FID C 8 667
FID C 10 1206
FID C 11 2576
FID H 12 403
SNT VIA
FID C 3 706
FID C 7 553
FID C 8 738
FID C 10 1277
FID C 11 2647
FID H 12 474
#NET 87
NET IMU_ENV_SDA
SNT TOP T 77 200
FID C 9 127
FID C 10 157
FID C 11 1528
SNT TOP T 42 15
FID C 9 732
FID C 10 804
FID C 11 2170
SNT TRC
FID C 2 442
SNT TRC
FID C 2 440
SNT TRC
FID C 2 441
SNT TRC
FID C 2 439
SNT TRC
FID C 3 546
SNT TRC
FID C 3 545
SNT TRC
FID C 3 399
SNT TRC
FID C 3 414
SNT TRC
FID C 3 415
SNT TRC
FID C 3 149
SNT TRC
FID C 3 151
SNT TRC
FID C 3 467
SNT TRC
FID C 3 465
SNT TRC
FID C 3 395
SNT TRC
FID C 3 434
SNT TRC
FID C 3 435
SNT TRC
FID C 3 148
SNT TRC
FID C 3 143
SNT TRC
FID C 3 475
SNT TRC
FID C 3 474
SNT TRC
FID C 3 473
SNT TRC
FID C 3 472
SNT TRC
FID C 11 1239
SNT TRC
FID C 11 1238
SNT TRC
FID C 11 1237
SNT TRC
FID C 11 844
SNT TRC
FID C 11 215
SNT VIA
FID C 3 711
FID C 7 566
FID C 8 751
FID C 10 1290
FID C 11 2660
FID H 12 487
SNT VIA
FID C 2 617
FID C 3 678
FID C 7 480
FID C 8 665
FID C 10 1204
FID C 11 2574
FID H 12 401
SNT VIA
FID C 2 616
FID C 3 674
FID C 7 472
FID C 8 657
FID C 10 1196
FID C 11 2566
FID H 12 393
SNT VIA
FID C 3 572
FID C 7 217
FID C 8 402
FID C 10 941
FID C 11 2311
FID H 12 138
#NET 88
NET IMU_ENV_SCL
SNT TOP T 77 194
FID C 9 124
FID C 10 154
FID C 11 1525
SNT TOP T 42 14
FID C 9 730
FID C 10 802
FID C 11 2168
SNT TRC
FID C 2 433
SNT TRC
FID C 2 436
SNT TRC
FID C 2 435
SNT TRC
FID C 2 434
SNT TRC
FID C 2 432
SNT TRC
FID C 2 431
SNT TRC
FID C 3 436
SNT TRC
FID C 3 417
SNT TRC
FID C 3 416
SNT TRC
FID C 3 397
SNT TRC
FID C 3 152
SNT TRC
FID C 3 433
SNT TRC
FID C 3 396
SNT TRC
FID C 3 454
SNT TRC
FID C 3 542
SNT TRC
FID C 11 1212
SNT TRC
FID C 11 1211
SNT TRC
FID C 11 779
SNT TRC
FID C 11 228
SNT TRC
FID C 11 214
SNT VIA
FID C 3 708
FID C 7 555
FID C 8 740
FID C 10 1279
FID C 11 2649
FID H 12 476
SNT VIA
FID C 2 613
FID C 3 672
FID C 7 465
FID C 8 650
FID C 10 1189
FID C 11 2559
FID H 12 386
SNT VIA
FID C 3 576
FID C 7 228
FID C 8 413
FID C 10 952
FID C 11 2322
FID H 12 149
SNT VIA
FID C 2 611
FID C 3 670
FID C 7 456
FID C 8 641
FID C 10 1180
FID C 11 2550
FID H 12 377
#NET 89
NET IMU_CLKSEL0
SNT TOP T 77 67
FID C 9 528
FID C 10 576
FID C 11 1942
SNT TOP T 42 9
FID C 9 725
FID C 10 797
FID C 11 2163
SNT TRC
FID C 2 451
SNT TRC
FID C 2 452
SNT TRC
FID C 2 458
SNT TRC
FID C 3 539
SNT TRC
FID C 3 488
SNT TRC
FID C 3 489
SNT TRC
FID C 11 881
SNT TRC
FID C 11 801
SNT TRC
FID C 11 812
SNT TRC
FID C 11 1190
SNT TRC
FID C 11 1198
SNT TRC
FID C 11 1218
SNT TRC
FID C 11 1191
SNT VIA
FID C 2 620
FID C 3 680
FID C 7 486
FID C 8 671
FID C 10 1210
FID C 11 2580
FID H 12 407
SNT VIA
FID C 3 705
FID C 7 552
FID C 8 737
FID C 10 1276
FID C 11 2646
FID H 12 473
SNT VIA
FID C 2 624
FID C 7 493
FID C 8 678
FID C 10 1217
FID C 11 2587
FID H 12 414
#NET 90
NET IMU_BOOT
SNT TOP T 77 65
FID C 9 529
FID C 10 577
FID C 11 1943
SNT TOP T 42 3
FID C 9 734
FID C 10 806
FID C 11 2172
SNT TRC
FID C 2 456
SNT TRC
FID C 2 454
SNT TRC
FID C 2 457
SNT TRC
FID C 2 463
SNT TRC
FID C 2 455
SNT TRC
FID C 3 535
SNT TRC
FID C 3 543
SNT TRC
FID C 3 544
SNT TRC
FID C 3 534
SNT TRC
FID C 3 492
SNT TRC
FID C 11 1246
SNT TRC
FID C 11 1247
SNT TRC
FID C 11 861
SNT TRC
FID C 11 802
SNT TRC
FID C 11 851
SNT VIA
FID C 3 710
FID C 7 565
FID C 8 750
FID C 10 1289
FID C 11 2659
FID H 12 486
SNT VIA
FID C 2 623
FID C 3 683
FID C 7 490
FID C 8 675
FID C 10 1214
FID C 11 2584
FID H 12 411
SNT VIA
FID C 2 626
FID C 7 495
FID C 8 680
FID C 10 1219
FID C 11 2589
FID H 12 416
#NET 91
NET NetJP1_3
SNT TOP T 3 2
FID C 7 31
FID C 8 221
FID C 10 79
FID C 11 1453
FID H 12 22
SNT TOP T 10 1
FID C 9 54
FID C 10 76
FID C 11 1450
SNT TOP T 11 1
FID C 9 55
FID C 10 77
FID C 11 1451
SNT TRC
FID C 11 141
SNT TRC
FID C 11 139
SNT TRC
FID C 11 137
SNT TRC
FID C 11 136
#NET 92
NET GPS1_TP2
SNT TOP T 77 37
FID C 9 543
FID C 10 591
FID C 11 1957
SNT TOP T 41 8
FID C 9 273
FID C 10 313
FID C 11 1681
SNT TRC
FID C 2 290
SNT TRC
FID C 2 30
SNT TRC
FID C 2 39
SNT TRC
FID C 2 253
SNT TRC
FID C 2 252
SNT TRC
FID C 2 254
SNT TRC
FID C 2 269
SNT TRC
FID C 3 239
SNT TRC
FID C 3 281
SNT TRC
FID C 3 283
SNT TRC
FID C 3 448
SNT TRC
FID C 3 451
SNT TRC
FID C 11 836
SNT TRC
FID C 11 843
SNT TRC
FID C 11 808
SNT TRC
FID C 11 375
SNT VIA
FID C 3 677
FID C 7 477
FID C 8 662
FID C 10 1201
FID C 11 2571
FID H 12 398
SNT VIA
FID C 2 544
FID C 3 608
FID C 7 313
FID C 8 498
FID C 10 1037
FID C 11 2407
FID H 12 234
SNT VIA
FID C 2 554
FID C 7 335
FID C 8 520
FID C 10 1059
FID C 11 2429
FID H 12 256
#NET 93
NET NetJP2_3
SNT TOP T 2 2
FID C 7 46
FID C 8 234
FID C 10 198
FID C 11 1570
FID H 12 29
SNT TOP T 8 1
FID C 9 183
FID C 10 218
FID C 11 1591
SNT TOP T 9 1
FID C 9 174
FID C 10 207
FID C 11 1580
SNT TRC
FID C 11 264
SNT TRC
FID C 11 258
SNT TRC
FID C 11 278
#NET 94
NET RTC_MFP
SNT TOP T 77 214
FID C 9 134
FID C 10 164
FID C 11 1535
SNT TOP T 12 2
FID C 9 343
FID C 10 383
FID C 11 1751
SNT TRC
FID C 2 385
SNT TRC
FID C 2 384
SNT TRC
FID C 2 388
SNT TRC
FID C 2 386
SNT TRC
FID C 2 387
SNT TRC
FID C 3 147
SNT TRC
FID C 11 244
SNT TRC
FID C 11 216
SNT TRC
FID C 11 493
SNT TRC
FID C 11 524
SNT TRC
FID C 11 579
SNT TRC
FID C 11 584
SNT VIA
FID C 3 574
FID C 7 225
FID C 8 410
FID C 10 949
FID C 11 2319
FID H 12 146
SNT VIA
FID C 2 586
FID C 3 646
FID C 7 408
FID C 8 593
FID C 10 1132
FID C 11 2502
FID H 12 329
SNT VIA
FID C 2 587
FID C 7 409
FID C 8 594
FID C 10 1133
FID C 11 2503
FID H 12 330
#NET 95
NET GPS1_RST
SNT TOP T 77 25
FID C 9 549
FID C 10 597
FID C 11 1963
SNT TOP T 41 5
FID C 9 221
FID C 10 256
FID C 11 1629
SNT TRC
FID C 2 168
SNT TRC
FID C 2 175
SNT TRC
FID C 3 440
SNT TRC
FID C 3 439
SNT TRC
FID C 3 423
SNT TRC
FID C 3 421
SNT TRC
FID C 3 185
SNT TRC
FID C 11 799
SNT TRC
FID C 11 764
SNT TRC
FID C 11 762
SNT TRC
FID C 11 294
SNT TRC
FID C 11 309
SNT TRC
FID C 11 295
SNT VIA
FID C 3 671
FID C 7 460
FID C 8 645
FID C 10 1184
FID C 11 2554
FID H 12 381
SNT VIA
FID C 2 525
FID C 3 587
FID C 7 264
FID C 8 449
FID C 10 988
FID C 11 2358
FID H 12 185
SNT VIA
FID C 2 521
FID C 7 258
FID C 8 443
FID C 10 982
FID C 11 2352
FID H 12 179
#NET 96
NET GPS2_TX
SNT TOP B 0 4
FID C 1 41
FID C 7 81
FID C 8 265
SNT TOP T 77 165
FID C 9 57
FID C 10 83
FID C 11 1456
SNT TOP T 11 0
FID C 9 56
FID C 10 78
FID C 11 1452
SNT TRC
FID C 2 157
SNT TRC
FID C 2 161
SNT TRC
FID C 2 159
SNT TRC
FID C 2 158
SNT TRC
FID C 2 156
SNT TRC
FID C 2 155
SNT TRC
FID C 2 138
SNT TRC
FID C 2 142
SNT TRC
FID C 2 153
SNT TRC
FID C 2 160
SNT TRC
FID C 2 107
SNT TRC
FID C 2 106
SNT TRC
FID C 2 128
SNT TRC
FID C 2 113
SNT TRC
FID C 2 126
SNT TRC
FID C 3 195
SNT TRC
FID C 3 202
SNT TRC
FID C 3 210
SNT TRC
FID C 3 248
SNT TRC
FID C 3 260
SNT TRC
FID C 3 179
SNT TRC
FID C 3 190
SNT TRC
FID C 3 126
SNT TRC
FID C 3 128
SNT TRC
FID C 3 178
SNT TRC
FID C 8 92
SNT TRC
FID C 8 103
SNT TRC
FID C 8 97
SNT TRC
FID C 8 102
SNT TRC
FID C 11 133
SNT TRC
FID C 11 134
SNT TRC
FID C 11 145
SNT TRC
FID C 11 146
SNT TRC
FID C 11 151
SNT VIA
FID C 2 515
FID C 3 582
FID C 7 251
FID C 8 436
FID C 10 975
FID C 11 2345
FID H 12 172
SNT VIA
FID C 2 516
FID C 3 583
FID C 7 252
FID C 8 437
FID C 10 976
FID C 11 2346
FID H 12 173
SNT VIA
FID C 2 488
FID C 7 181
FID C 8 366
FID C 10 905
FID C 11 2275
FID H 12 102
SNT VIA
FID C 3 566
FID C 7 188
FID C 8 373
FID C 10 912
FID C 11 2282
FID H 12 109
SNT VIA
FID C 3 614
FID C 7 323
FID C 8 508
FID C 10 1047
FID C 11 2417
FID H 12 244
#NET 97
NET GPS2_TP2
SNT TOP B 0 8
FID C 1 43
FID C 7 83
FID C 8 267
SNT TOP T 77 48
FID C 9 481
FID C 10 525
FID C 11 1893
SNT TRC
FID C 11 627
SNT TRC
FID C 11 634
SNT TRC
FID C 11 628
SNT TRC
FID C 2 394
SNT TRC
FID C 2 393
SNT TRC
FID C 3 403
SNT TRC
FID C 3 262
SNT TRC
FID C 3 259
SNT TRC
FID C 3 265
SNT TRC
FID C 8 100
SNT TRC
FID C 8 93
SNT TRC
FID C 8 99
SNT TRC
FID C 8 101
SNT VIA
FID C 2 592
FID C 7 419
FID C 8 604
FID C 10 1143
FID C 11 2513
FID H 12 340
SNT VIA
FID C 2 593
FID C 3 652
FID C 7 420
FID C 8 605
FID C 10 1144
FID C 11 2514
FID H 12 341
SNT VIA
FID C 3 613
FID C 7 322
FID C 8 507
FID C 10 1046
FID C 11 2416
FID H 12 243
#NET 98
NET GPS2_TP1
SNT TOP B 0 7
FID C 1 24
FID C 7 59
FID C 8 248
SNT TOP T 77 46
FID C 9 482
FID C 10 526
FID C 11 1894
SNT TRC
FID C 11 637
SNT TRC
FID C 11 623
SNT TRC
FID C 11 633
SNT TRC
FID C 2 391
SNT TRC
FID C 2 392
SNT TRC
FID C 3 311
SNT TRC
FID C 3 214
SNT TRC
FID C 3 317
SNT TRC
FID C 3 380
SNT TRC
FID C 3 197
SNT TRC
FID C 3 207
SNT TRC
FID C 3 204
SNT TRC
FID C 3 198
SNT TRC
FID C 3 382
SNT TRC
FID C 8 61
SNT TRC
FID C 8 59
SNT TRC
FID C 11 615
SNT VIA
FID C 2 590
FID C 7 416
FID C 8 601
FID C 10 1140
FID C 11 2510
FID H 12 337
SNT VIA
FID C 3 595
FID C 7 286
FID C 8 471
FID C 10 1010
FID C 11 2380
FID H 12 207
SNT VIA
FID C 2 591
FID C 3 650
FID C 7 417
FID C 8 602
FID C 10 1141
FID C 11 2511
FID H 12 338
#NET 99
NET GPS2_RX
SNT TOP B 0 6
FID C 1 42
FID C 7 82
FID C 8 266
SNT TOP T 9 0
FID C 9 175
FID C 10 208
FID C 11 1581
SNT TOP T 77 164
FID C 9 109
FID C 10 139
FID C 11 1510
SNT TRC
FID C 8 90
SNT TRC
FID C 8 83
SNT TRC
FID C 3 213
SNT TRC
FID C 3 206
SNT TRC
FID C 2 152
SNT TRC
FID C 11 273
SNT TRC
FID C 11 274
SNT TRC
FID C 11 277
SNT TRC
FID C 2 281
SNT TRC
FID C 2 242
SNT TRC
FID C 2 223
SNT TRC
FID C 2 241
SNT TRC
FID C 2 239
SNT TRC
FID C 2 240
SNT TRC
FID C 2 243
SNT TRC
FID C 2 238
SNT TRC
FID C 3 226
SNT TRC
FID C 2 132
SNT TRC
FID C 2 136
SNT TRC
FID C 2 131
SNT TRC
FID C 2 141
SNT TRC
FID C 2 143
SNT TRC
FID C 2 140
SNT TRC
FID C 2 130
SNT TRC
FID C 2 117
SNT TRC
FID C 2 116
SNT TRC
FID C 2 114
SNT TRC
FID C 2 115
SNT TRC
FID C 3 163
SNT TRC
FID C 3 122
SNT TRC
FID C 3 142
SNT TRC
FID C 3 162
SNT TRC
FID C 3 141
SNT TRC
FID C 11 212
SNT TRC
FID C 11 222
SNT TRC
FID C 11 226
SNT VIA
FID C 2 536
FID C 3 601
FID C 7 295
FID C 8 480
FID C 10 1019
FID C 11 2389
FID H 12 216
SNT VIA
FID C 2 514
FID C 7 247
FID C 8 432
FID C 10 971
FID C 11 2341
FID H 12 168
SNT VIA
FID C 2 541
FID C 3 606
FID C 7 305
FID C 8 490
FID C 10 1029
FID C 11 2399
FID H 12 226
SNT VIA
FID C 2 491
FID C 3 564
FID C 7 185
FID C 8 370
FID C 10 909
FID C 11 2279
FID H 12 106
SNT VIA
FID C 3 571
FID C 7 216
FID C 8 401
FID C 10 940
FID C 11 2310
FID H 12 137
#NET 100
NET GPS2_RST
SNT TOP B 0 5
FID C 1 23
FID C 7 58
FID C 8 247
SNT TOP T 77 38
FID C 9 486
FID C 10 530
FID C 11 1898
SNT TRC
FID C 2 390
SNT TRC
FID C 2 389
SNT TRC
FID C 3 203
SNT TRC
FID C 3 199
SNT TRC
FID C 3 249
SNT TRC
FID C 3 391
SNT TRC
FID C 3 392
SNT TRC
FID C 8 58
SNT TRC
FID C 8 75
SNT TRC
FID C 11 607
SNT TRC
FID C 11 608
SNT TRC
FID C 11 618
SNT VIA
FID C 2 588
FID C 7 413
FID C 8 598
FID C 10 1137
FID C 11 2507
FID H 12 334
SNT VIA
FID C 3 596
FID C 7 287
FID C 8 472
FID C 10 1011
FID C 11 2381
FID H 12 208
SNT VIA
FID C 2 589
FID C 3 649
FID C 7 414
FID C 8 599
FID C 10 1138
FID C 11 2508
FID H 12 335
#NET 101
NET DCXO1
SNT TOP T 77 117
FID C 9 278
FID C 10 318
FID C 11 1686
SNT TOP T 38 5
FID C 9 509
FID C 10 553
FID C 11 1921
SNT TRC
FID C 11 778
SNT TRC
FID C 11 748
SNT TRC
FID C 11 770
SNT TRC
FID C 11 746
SNT TRC
FID C 11 768
SNT TRC
FID C 11 386
SNT TRC
FID C 11 410
SNT TRC
FID C 11 385
#NET 102
NET DCXO2
SNT TOP T 77 99
FID C 9 225
FID C 10 260
FID C 11 1633
SNT TOP T 39 5
FID C 9 445
FID C 10 489
FID C 11 1857
SNT TRC
FID C 3 308
SNT TRC
FID C 3 41
SNT TRC
FID C 3 192
SNT TRC
FID C 3 307
SNT TRC
FID C 3 47
SNT TRC
FID C 3 290
SNT TRC
FID C 3 191
SNT TRC
FID C 3 1
SNT TRC
FID C 3 400
SNT TRC
FID C 3 389
SNT TRC
FID C 3 401
SNT TRC
FID C 11 321
SNT TRC
FID C 11 322
SNT TRC
FID C 11 635
SNT TRC
FID C 11 636
SNT TRC
FID C 11 638
SNT TRC
FID C 11 648
SNT VIA
FID C 3 591
FID C 7 276
FID C 8 461
FID C 10 1000
FID C 11 2370
FID H 12 197
SNT VIA
FID C 3 653
FID C 7 422
FID C 8 607
FID C 10 1146
FID C 11 2516
FID H 12 343
#NET 103
NET CSN
SNT TOP T 77 30
FID C 9 490
FID C 10 534
FID C 11 1902
SNT TOP T 42 17
FID C 9 736
FID C 10 808
FID C 11 2174
SNT TRC
FID C 2 399
SNT TRC
FID C 2 411
SNT TRC
FID C 2 398
SNT TRC
FID C 2 400
SNT TRC
FID C 3 547
SNT TRC
FID C 3 548
SNT TRC
FID C 3 530
SNT TRC
FID C 3 438
SNT TRC
FID C 3 529
SNT TRC
FID C 3 430
SNT TRC
FID C 11 1251
SNT TRC
FID C 11 1249
SNT TRC
FID C 11 674
SNT TRC
FID C 11 645
SNT TRC
FID C 11 682
SNT VIA
FID C 3 712
FID C 7 567
FID C 8 752
FID C 10 1291
FID C 11 2661
FID H 12 488
SNT VIA
FID C 2 603
FID C 3 661
FID C 7 437
FID C 8 622
FID C 10 1161
FID C 11 2531
FID H 12 358
SNT VIA
FID C 2 596
FID C 7 426
FID C 8 611
FID C 10 1150
FID C 11 2520
FID H 12 347
#NET 104
NET ANT4
SNT TOP T 143 0
FID C 7 17
FID C 8 207
FID C 10 17
FID C 11 1391
FID H 12 8
SNT TOP T 77 110
FID C 9 258
FID C 10 298
FID C 11 1666
SNT TOP T 86 0
FID C 9 33
FID C 10 55
FID C 11 1429
SNT TOP T 139 0
FID C 9 9
FID C 10 31
FID C 11 1405
SNT TOP T 1 1
FID C 9 30
FID C 10 52
FID C 11 1426
SNT TRC
FID C 2 235
SNT TRC
FID C 2 231
SNT TRC
FID C 3 209
SNT TRC
FID C 3 219
SNT TRC
FID C 3 99
SNT TRC
FID C 3 145
SNT TRC
FID C 3 108
SNT TRC
FID C 3 113
SNT TRC
FID C 3 139
SNT TRC
FID C 11 49
SNT TRC
FID C 11 56
SNT TRC
FID C 11 90
SNT TRC
FID C 11 359
SNT TRC
FID C 11 363
SNT TRC
FID C 11 360
SNT TRC
FID C 11 85
SNT TRC
FID C 11 84
SNT VIA
FID C 3 556
FID C 7 172
FID C 8 357
FID C 10 896
FID C 11 2266
FID H 12 93
SNT VIA
FID C 2 539
FID C 3 602
FID C 7 300
FID C 8 485
FID C 10 1024
FID C 11 2394
FID H 12 221
SNT VIA
FID C 2 538
FID C 7 298
FID C 8 483
FID C 10 1022
FID C 11 2392
FID H 12 219
#NET 105
NET ANT3
SNT TOP T 144 0
FID C 7 18
FID C 8 208
FID C 10 18
FID C 11 1392
FID H 12 9
SNT TOP T 87 0
FID C 9 34
FID C 10 56
FID C 11 1430
SNT TOP T 140 0
FID C 9 10
FID C 10 32
FID C 11 1406
SNT TOP T 77 108
FID C 9 252
FID C 10 292
FID C 11 1660
SNT TOP T 4 1
FID C 9 31
FID C 10 53
FID C 11 1427
SNT TRC
FID C 2 211
SNT TRC
FID C 2 217
SNT TRC
FID C 2 212
SNT TRC
FID C 3 102
SNT TRC
FID C 3 103
SNT TRC
FID C 3 100
SNT TRC
FID C 11 50
SNT TRC
FID C 11 57
SNT TRC
FID C 11 108
SNT TRC
FID C 11 91
SNT TRC
FID C 11 87
SNT TRC
FID C 11 86
SNT TRC
FID C 11 348
SNT TRC
FID C 11 349
SNT TRC
FID C 11 352
SNT VIA
FID C 3 557
FID C 7 173
FID C 8 358
FID C 10 897
FID C 11 2267
FID H 12 94
SNT VIA
FID C 2 534
FID C 3 600
FID C 7 292
FID C 8 477
FID C 10 1016
FID C 11 2386
FID H 12 213
SNT VIA
FID C 2 535
FID C 7 294
FID C 8 479
FID C 10 1018
FID C 11 2388
FID H 12 215
#NET 106
NET ANT2
SNT TOP T 145 0
FID C 7 19
FID C 8 209
FID C 10 19
FID C 11 1393
FID H 12 10
SNT TOP T 89 0
FID C 9 35
FID C 10 57
FID C 11 1431
SNT TOP T 142 0
FID C 9 11
FID C 10 33
FID C 11 1407
SNT TOP T 77 106
FID C 9 247
FID C 10 286
FID C 11 1655
SNT TOP T 5 1
FID C 9 29
FID C 10 51
FID C 11 1425
SNT TRC
FID C 2 197
SNT TRC
FID C 3 104
SNT TRC
FID C 3 101
SNT TRC
FID C 11 51
SNT TRC
FID C 11 58
SNT TRC
FID C 11 92
SNT TRC
FID C 11 342
SNT TRC
FID C 11 343
SNT TRC
FID C 11 344
SNT TRC
FID C 11 345
SNT TRC
FID C 11 83
SNT TRC
FID C 11 82
SNT TRC
FID C 11 340
SNT VIA
FID C 3 558
FID C 7 174
FID C 8 359
FID C 10 898
FID C 11 2268
FID H 12 95
SNT VIA
FID C 2 530
FID C 3 592
FID C 7 280
FID C 8 465
FID C 10 1004
FID C 11 2374
FID H 12 201
SNT VIA
FID C 2 531
FID C 7 281
FID C 8 466
FID C 10 1005
FID C 11 2375
FID H 12 202
#NET 107
NET ANT1
SNT TOP T 146 0
FID C 7 20
FID C 8 210
FID C 10 20
FID C 11 1394
FID H 12 11
SNT TOP T 88 0
FID C 9 36
FID C 10 58
FID C 11 1432
SNT TOP T 141 0
FID C 9 12
FID C 10 34
FID C 11 1408
SNT TOP T 77 104
FID C 9 242
FID C 10 277
FID C 11 1650
SNT TOP T 6 1
FID C 9 32
FID C 10 54
FID C 11 1428
SNT TRC
FID C 3 105
SNT TRC
FID C 3 106
SNT TRC
FID C 11 52
SNT TRC
FID C 11 59
SNT TRC
FID C 11 93
SNT TRC
FID C 11 336
SNT TRC
FID C 11 337
SNT TRC
FID C 11 89
SNT TRC
FID C 11 88
SNT VIA
FID C 3 559
FID C 7 175
FID C 8 360
FID C 10 899
FID C 11 2269
FID H 12 96
SNT VIA
FID C 3 593
FID C 7 282
FID C 8 467
FID C 10 1006
FID C 11 2376
FID H 12 203
#NET 108
NET +3.3V_CLEAN
SNT TOP T 13 4
FID C 7 140
FID C 8 322
FID C 10 736
FID C 11 2102
FID H 12 61
SNT TOP T 17 1
FID C 9 600
FID C 10 650
FID C 11 2016
SNT TOP T 18 1
FID C 9 614
FID C 10 667
FID C 11 2033
SNT TOP T 21 1
FID C 9 633
FID C 10 686
FID C 11 2052
SNT TOP T 22 1
FID C 9 640
FID C 10 694
FID C 11 2060
SNT TOP T 23 1
FID C 9 644
FID C 10 698
FID C 11 2064
SNT TOP T 24 1
FID C 9 649
FID C 10 706
FID C 11 2072
SNT TOP T 25 1
FID C 9 653
FID C 10 710
FID C 11 2076
SNT TOP T 26 1
FID C 9 658
FID C 10 715
FID C 11 2081
SNT TOP T 27 1
FID C 9 647
FID C 10 701
FID C 11 2067
SNT TOP T 104 1
FID C 9 564
FID C 10 612
FID C 11 1978
SNT TOP T 105 1
FID C 9 575
FID C 10 623
FID C 11 1989
SNT TOP T 106 1
FID C 9 567
FID C 10 615
FID C 11 1981
SNT TOP T 20 1
FID C 9 627
FID C 10 680
FID C 11 2046
SNT TOP T 19 1
FID C 9 609
FID C 10 661
FID C 11 2027
SNT TOP T 83 1
FID C 9 631
FID C 10 684
FID C 11 2050
SNT TOP T 32 1
FID C 9 511
FID C 10 555
FID C 11 1923
SNT TOP T 38 8
FID C 9 510
FID C 10 554
FID C 11 1922
SNT TOP T 39 9
FID C 9 512
FID C 10 556
FID C 11 1924
SNT TOP T 12 1
FID C 9 344
FID C 10 384
FID C 11 1752
SNT TOP T 0 9
FID C 9 443
FID C 10 486
FID C 11 1854
SNT TOP T 0 5
FID C 9 434
FID C 10 477
FID C 11 1845
SNT TOP T 0 0
FID C 9 440
FID C 10 483
FID C 11 1851
SNT TRC
FID C 11 1081
SNT TRC
FID C 11 1067
SNT TRC
FID C 11 906
SNT TRC
FID C 11 930
SNT TRC
FID C 11 907
SNT TRC
FID C 11 905
SNT TRC
FID C 11 962
SNT TRC
FID C 11 956
SNT TRC
FID C 11 932
SNT TRC
FID C 11 1025
SNT TRC
FID C 11 1046
SNT TRC
FID C 11 1051
SNT TRC
FID C 11 1050
SNT TRC
FID C 11 1047
SNT TRC
FID C 11 913
SNT TRC
FID C 11 931
SNT TRC
FID C 11 829
SNT TRC
FID C 11 847
SNT TRC
FID C 11 925
SNT TRC
FID C 11 924
SNT TRC
FID C 11 914
SNT TRC
FID C 11 877
SNT TRC
FID C 11 1014
SNT TRC
FID C 11 1038
SNT TRC
FID C 11 944
SNT TRC
FID C 11 952
SNT TRC
FID C 11 963
SNT TRC
FID C 11 990
SNT TRC
FID C 11 1024
SNT TRC
FID C 11 1032
SNT TRC
FID C 11 1056
SNT TRC
FID C 11 1054
SNT TRC
FID C 11 1055
#NET 109
NET LED4
SNT TOP T 54 0
FID C 9 49
FID C 10 71
FID C 11 1445
SNT TOP T 77 74
FID C 9 468
FID C 10 512
FID C 11 1880
SNT TRC
FID C 2 151
SNT TRC
FID C 2 150
SNT TRC
FID C 2 149
SNT TRC
FID C 3 432
SNT TRC
FID C 3 170
SNT TRC
FID C 3 169
SNT TRC
FID C 11 707
SNT TRC
FID C 11 700
SNT TRC
FID C 11 677
SNT TRC
FID C 11 725
SNT TRC
FID C 11 124
SNT TRC
FID C 11 125
SNT TRC
FID C 11 140
SNT VIA
FID C 2 512
FID C 3 581
FID C 7 241
FID C 8 426
FID C 10 965
FID C 11 2335
FID H 12 162
SNT VIA
FID C 2 513
FID C 7 242
FID C 8 427
FID C 10 966
FID C 11 2336
FID H 12 163
SNT VIA
FID C 3 663
FID C 7 441
FID C 8 626
FID C 10 1165
FID C 11 2535
FID H 12 362
#NET 110
NET LED3
SNT TOP T 55 0
FID C 9 41
FID C 10 63
FID C 11 1437
SNT TOP T 77 76
FID C 9 467
FID C 10 511
FID C 11 1879
SNT TRC
FID C 2 148
SNT TRC
FID C 3 167
SNT TRC
FID C 11 698
SNT TRC
FID C 11 663
SNT TRC
FID C 11 664
SNT TRC
FID C 11 691
SNT TRC
FID C 11 110
SNT TRC
FID C 11 111
SNT TRC
FID C 11 120
SNT VIA
FID C 2 511
FID C 7 238
FID C 8 423
FID C 10 962
FID C 11 2332
FID H 12 159
SNT VIA
FID C 2 510
FID C 3 580
FID C 7 237
FID C 8 422
FID C 10 961
FID C 11 2331
FID H 12 158
SNT VIA
FID C 3 660
FID C 7 435
FID C 8 620
FID C 10 1159
FID C 11 2529
FID H 12 356
#NET 111
NET +12V_PCIE
SNT PLN S C 0.00
FID C 8 228
SNT PLN S C 0.00
FID C 11 1552
SNT TOP T 76 1
FID C 1 10
FID C 7 40
FID C 8 227
SNT TOP T 76 2
FID C 1 11
FID C 7 41
FID C 8 229
SNT TOP T 101 1
FID C 9 708
FID C 10 780
FID C 11 2146
SNT TOP T 76 32
FID C 9 149
FID C 10 179
FID C 11 1550
SNT TOP T 76 33
FID C 9 151
FID C 10 181
FID C 11 1553
SNT TOP T 76 34
FID C 9 161
FID C 10 191
FID C 11 1563
SNT TRC
FID C 2 137
SNT TRC
FID C 3 144
SNT TRC
FID C 8 42
SNT TRC
FID C 8 41
SNT TRC
FID C 8 44
SNT TRC
FID C 8 43
SNT TRC
FID C 11 1186
SNT TRC
FID C 11 229
SNT TRC
FID C 11 231
SNT TRC
FID C 11 225
SNT TRC
FID C 11 224
SNT TRC
FID C 11 230
SNT TRC
FID C 11 235
SNT TRC
FID C 11 241
SNT TRC
FID C 11 227
SNT VIA
FID C 3 703
FID C 7 550
FID C 8 735
FID C 10 1274
FID C 11 2644
FID H 12 471
SNT VIA
FID C 2 501
FID C 3 573
FID C 7 220
FID C 8 405
FID C 10 944
FID C 11 2314
FID H 12 141
SNT VIA
FID C 7 224
FID C 8 409
FID C 10 948
FID C 11 2318
FID H 12 145
SNT VIA
FID C 2 503
FID C 7 222
FID C 8 407
FID C 10 946
FID C 11 2316
FID H 12 143
SNT VIA
FID C 2 500
FID C 7 219
FID C 8 404
FID C 10 943
FID C 11 2313
FID H 12 140
SNT VIA
FID C 7 223
FID C 8 408
FID C 10 947
FID C 11 2317
FID H 12 144
SNT VIA
FID C 2 502
FID C 7 221
FID C 8 406
FID C 10 945
FID C 11 2315
FID H 12 142
SNT VIA
FID C 7 218
FID C 8 403
FID C 10 942
FID C 11 2312
FID H 12 139
#NET 112
NET +3.3V_PCIE
SNT PLN S C 0.00
FID C 8 239
SNT PLN S C 0.00
FID C 11 1575
SNT TOP T 76 8
FID C 1 17
FID C 7 50
FID C 8 238
SNT TOP T 76 9
FID C 1 18
FID C 7 51
FID C 8 240
SNT TOP T 76 39
FID C 9 168
FID C 10 201
FID C 11 1573
SNT TRC
FID C 8 54
SNT TRC
FID C 8 53
SNT TRC
FID C 8 50
SNT TRC
FID C 8 49
SNT TRC
FID C 8 51
SNT TRC
FID C 11 260
SNT TRC
FID C 11 261
SNT TRC
FID C 11 263
SNT TRC
FID C 11 262
SNT VIA
FID C 7 249
FID C 8 434
FID C 10 973
FID C 11 2343
FID H 12 170
SNT VIA
FID C 7 243
FID C 8 428
FID C 10 967
FID C 11 2337
FID H 12 164
SNT VIA
FID C 7 250
FID C 8 435
FID C 10 974
FID C 11 2344
FID H 12 171
SNT VIA
FID C 7 244
FID C 8 429
FID C 10 968
FID C 11 2338
FID H 12 165
SNT VIA
FID C 7 240
FID C 8 425
FID C 10 964
FID C 11 2334
FID H 12 161
SNT VIA
FID C 7 239
FID C 8 424
FID C 10 963
FID C 11 2333
FID H 12 160
#NET 113
NET PRSNT
SNT TOP T 62 0
FID C 9 267
FID C 10 307
FID C 11 1675
SNT TOP T 61 0
FID C 9 415
FID C 10 458
FID C 11 1826
SNT TOP T 76 0
FID C 1 9
FID C 7 39
FID C 8 226
SNT TRC
FID C 11 374
SNT TRC
FID C 11 259
SNT TRC
FID C 11 223
SNT TRC
FID C 8 40
SNT VIA
FID C 7 215
FID C 8 400
FID C 10 939
FID C 11 2309
FID H 12 136
#NET 114
NET PCIE_TX3_N
SNT TOP B 5 1
FID C 1 74
FID C 7 117
FID C 8 301
SNT TOP T 77 262
FID C 9 358
FID C 10 398
FID C 11 1766
SNT TRC
FID C 2 85
SNT TRC
FID C 2 374
SNT TRC
FID C 2 92
SNT TRC
FID C 2 87
SNT TRC
FID C 2 81
SNT TRC
FID C 2 362
SNT TRC
FID C 2 96
SNT TRC
FID C 2 373
SNT TRC
FID C 2 95
SNT TRC
FID C 2 352
SNT TRC
FID C 2 86
SNT TRC
FID C 2 361
SNT TRC
FID C 2 91
SNT TRC
FID C 2 323
SNT TRC
FID C 8 155
SNT TRC
FID C 8 156
SNT TRC
FID C 11 510
SNT TRC
FID C 2 57
SNT TRC
FID C 11 509
SNT TRC
FID C 11 37
SNT TRC
FID C 2 318
SNT TRC
FID C 2 317
SNT TRC
FID C 2 58
SNT TRC
FID C 2 80
SNT VIA
FID C 2 585
FID C 7 407
FID C 8 592
FID C 10 1131
FID C 11 2501
FID H 12 328
SNT VIA
FID C 2 570
FID C 7 373
FID C 8 558
FID C 10 1097
FID C 11 2467
FID H 12 294
#NET 115
NET PCIE_TX3_P
SNT TOP B 6 1
FID C 1 71
FID C 7 111
FID C 8 295
SNT TOP T 77 260
FID C 9 364
FID C 10 404
FID C 11 1772
SNT TRC
FID C 2 353
SNT TRC
FID C 2 94
SNT TRC
FID C 2 89
SNT TRC
FID C 8 150
SNT TRC
FID C 8 29
SNT TRC
FID C 8 151
SNT TRC
FID C 2 356
SNT TRC
FID C 2 372
SNT TRC
FID C 2 367
SNT TRC
FID C 2 90
SNT TRC
FID C 2 93
SNT TRC
FID C 2 366
SNT TRC
FID C 2 88
SNT TRC
FID C 2 360
SNT TRC
FID C 2 365
SNT TRC
FID C 2 364
SNT TRC
FID C 8 149
SNT TRC
FID C 8 28
SNT TRC
FID C 11 39
SNT TRC
FID C 2 334
SNT TRC
FID C 2 332
SNT TRC
FID C 2 333
SNT TRC
FID C 11 518
SNT TRC
FID C 2 62
SNT TRC
FID C 2 61
SNT TRC
FID C 2 83
SNT TRC
FID C 2 358
SNT TRC
FID C 2 355
SNT TRC
FID C 2 359
SNT TRC
FID C 2 84
SNT TRC
FID C 2 82
SNT TRC
FID C 2 354
SNT VIA
FID C 2 581
FID C 7 403
FID C 8 588
FID C 10 1127
FID C 11 2497
FID H 12 324
SNT VIA
FID C 2 572
FID C 7 380
FID C 8 565
FID C 10 1104
FID C 11 2474
FID H 12 301
#NET 116
NET PCIE_TX2_N
SNT TOP T 77 257
FID C 9 374
FID C 10 414
FID C 11 1782
SNT TOP B 7 1
FID C 1 65
FID C 7 105
FID C 8 289
SNT TRC
FID C 2 319
SNT TRC
FID C 2 56
SNT TRC
FID C 2 60
SNT TRC
FID C 2 322
SNT TRC
FID C 2 321
SNT TRC
FID C 2 72
SNT TRC
FID C 2 59
SNT TRC
FID C 2 320
SNT TRC
FID C 2 340
SNT TRC
FID C 11 535
SNT TRC
FID C 2 73
SNT TRC
FID C 11 40
SNT TRC
FID C 8 20
SNT TRC
FID C 8 136
SNT TRC
FID C 2 67
SNT TRC
FID C 2 337
SNT TRC
FID C 2 66
SNT TRC
FID C 2 64
SNT TRC
FID C 2 63
SNT TRC
FID C 2 335
SNT VIA
FID C 2 574
FID C 7 385
FID C 8 570
FID C 10 1109
FID C 11 2479
FID H 12 306
SNT VIA
FID C 2 573
FID C 7 383
FID C 8 568
FID C 10 1107
FID C 11 2477
FID H 12 304
#NET 117
NET PCIE_TX2_P
SNT TOP T 77 255
FID C 9 378
FID C 10 418
FID C 11 1786
SNT TOP B 8 1
FID C 1 62
FID C 7 102
FID C 8 286
SNT TRC
FID C 11 41
SNT TRC
FID C 2 348
SNT TRC
FID C 2 79
SNT TRC
FID C 2 346
SNT TRC
FID C 2 347
SNT TRC
FID C 11 540
SNT TRC
FID C 2 77
SNT TRC
FID C 2 76
SNT TRC
FID C 2 344
SNT TRC
FID C 2 345
SNT TRC
FID C 2 341
SNT TRC
FID C 2 78
SNT TRC
FID C 2 74
SNT TRC
FID C 2 343
SNT TRC
FID C 2 342
SNT TRC
FID C 2 75
SNT TRC
FID C 2 339
SNT TRC
FID C 2 70
SNT TRC
FID C 2 71
SNT TRC
FID C 2 338
SNT TRC
FID C 2 69
SNT TRC
FID C 2 68
SNT TRC
FID C 2 336
SNT TRC
FID C 2 65
SNT TRC
FID C 2 327
SNT TRC
FID C 2 325
SNT TRC
FID C 2 331
SNT TRC
FID C 2 324
SNT TRC
FID C 2 330
SNT TRC
FID C 8 19
SNT TRC
FID C 2 329
SNT TRC
FID C 2 328
SNT TRC
FID C 2 326
SNT TRC
FID C 8 16
SNT TRC
FID C 8 134
SNT VIA
FID C 2 575
FID C 7 390
FID C 8 575
FID C 10 1114
FID C 11 2484
FID H 12 311
SNT VIA
FID C 2 571
FID C 7 378
FID C 8 563
FID C 10 1102
FID C 11 2472
FID H 12 299
#NET 118
NET PCIE_TX1_N
SNT TOP T 77 269
FID C 9 335
FID C 10 375
FID C 11 1743
SNT TOP B 9 1
FID C 1 56
FID C 7 96
FID C 8 280
SNT TRC
FID C 11 485
SNT TRC
FID C 11 27
SNT TRC
FID C 2 50
SNT TRC
FID C 2 47
SNT TRC
FID C 2 305
SNT TRC
FID C 11 479
SNT TRC
FID C 2 311
SNT TRC
FID C 2 312
SNT TRC
FID C 2 49
SNT TRC
FID C 2 310
SNT TRC
FID C 2 53
SNT TRC
FID C 2 309
SNT TRC
FID C 2 52
SNT TRC
FID C 2 306
SNT TRC
FID C 2 307
SNT TRC
FID C 2 308
SNT TRC
FID C 2 48
SNT TRC
FID C 11 26
SNT TRC
FID C 2 54
SNT TRC
FID C 2 303
SNT TRC
FID C 2 301
SNT TRC
FID C 11 478
SNT TRC
FID C 2 302
SNT TRC
FID C 2 304
SNT TRC
FID C 2 44
SNT TRC
FID C 2 46
SNT TRC
FID C 2 45
SNT TRC
FID C 2 42
SNT TRC
FID C 8 116
SNT TRC
FID C 8 117
SNT TRC
FID C 2 295
SNT VIA
FID C 2 568
FID C 7 362
FID C 8 547
FID C 10 1086
FID C 11 2456
FID H 12 283
SNT VIA
FID C 2 564
FID C 7 354
FID C 8 539
FID C 10 1078
FID C 11 2448
FID H 12 275
#NET 119
NET PCIE_TX1_P
SNT TOP T 77 267
FID C 9 348
FID C 10 388
FID C 11 1756
SNT TOP B 10 1
FID C 1 53
FID C 7 93
FID C 8 277
SNT TRC
FID C 11 495
SNT TRC
FID C 2 314
SNT TRC
FID C 2 282
SNT TRC
FID C 2 287
SNT TRC
FID C 2 51
SNT TRC
FID C 2 37
SNT TRC
FID C 2 313
SNT TRC
FID C 2 55
SNT TRC
FID C 11 31
SNT TRC
FID C 2 316
SNT TRC
FID C 2 315
SNT TRC
FID C 8 113
SNT TRC
FID C 8 13
SNT VIA
FID C 2 569
FID C 7 365
FID C 8 550
FID C 10 1089
FID C 11 2459
FID H 12 286
SNT VIA
FID C 2 557
FID C 7 340
FID C 8 525
FID C 10 1064
FID C 11 2434
FID H 12 261
#NET 120
NET PCIE_TX0_N
SNT TOP T 77 274
FID C 9 318
FID C 10 358
FID C 11 1726
SNT TOP B 11 1
FID C 1 45
FID C 7 85
FID C 8 269
SNT TRC
FID C 2 27
SNT TRC
FID C 2 234
SNT TRC
FID C 2 25
SNT TRC
FID C 8 94
SNT TRC
FID C 2 233
SNT TRC
FID C 2 200
SNT TRC
FID C 2 229
SNT TRC
FID C 2 14
SNT TRC
FID C 8 95
SNT TRC
FID C 2 232
SNT TRC
FID C 11 448
SNT TRC
FID C 2 291
SNT TRC
FID C 2 288
SNT TRC
FID C 11 20
SNT TRC
FID C 2 289
SNT TRC
FID C 2 40
SNT TRC
FID C 2 38
SNT TRC
FID C 2 225
SNT TRC
FID C 2 224
SNT VIA
FID C 2 542
FID C 7 308
FID C 8 493
FID C 10 1032
FID C 11 2402
FID H 12 229
SNT VIA
FID C 2 560
FID C 7 347
FID C 8 532
FID C 10 1071
FID C 11 2441
FID H 12 268
#NET 121
NET PCIE_TX0_P
SNT TOP T 77 272
FID C 9 324
FID C 10 364
FID C 11 1732
SNT TOP B 12 1
FID C 1 38
FID C 7 78
FID C 8 262
SNT TRC
FID C 8 84
SNT TRC
FID C 8 85
SNT TRC
FID C 11 24
SNT TRC
FID C 2 297
SNT TRC
FID C 2 296
SNT TRC
FID C 11 464
SNT TRC
FID C 2 43
SNT TRC
FID C 2 41
SNT TRC
FID C 2 237
SNT TRC
FID C 2 230
SNT TRC
FID C 2 228
SNT TRC
FID C 8 89
SNT TRC
FID C 8 88
SNT TRC
FID C 2 227
SNT TRC
FID C 8 9
SNT TRC
FID C 8 86
SNT TRC
FID C 2 24
SNT TRC
FID C 2 219
SNT TRC
FID C 2 23
SNT TRC
FID C 2 26
SNT TRC
FID C 2 218
SNT TRC
FID C 2 203
SNT TRC
FID C 2 208
SNT TRC
FID C 2 18
SNT TRC
FID C 2 209
SNT TRC
FID C 2 204
SNT TRC
FID C 2 15
SNT TRC
FID C 2 21
SNT TRC
FID C 2 220
SNT TRC
FID C 2 210
SNT TRC
FID C 2 22
SNT TRC
FID C 2 207
SNT TRC
FID C 2 20
SNT TRC
FID C 2 206
SNT TRC
FID C 2 19
SNT VIA
FID C 2 565
FID C 7 355
FID C 8 540
FID C 10 1079
FID C 11 2449
FID H 12 276
SNT VIA
FID C 2 537
FID C 7 296
FID C 8 481
FID C 10 1020
FID C 11 2390
FID H 12 217
#NET 122
NET PCIE_CLK_P
SNT TOP T 77 279
FID C 9 308
FID C 10 348
FID C 11 1716
SNT TOP B 14 1
FID C 1 28
FID C 7 63
FID C 8 252
SNT TRC
FID C 2 215
SNT TRC
FID C 2 261
SNT TRC
FID C 11 429
SNT TRC
FID C 11 15
SNT TRC
FID C 11 14
SNT TRC
FID C 2 267
SNT TRC
FID C 11 414
SNT TRC
FID C 2 268
SNT TRC
FID C 2 266
SNT TRC
FID C 2 35
SNT TRC
FID C 2 33
SNT TRC
FID C 2 251
SNT TRC
FID C 2 29
SNT TRC
FID C 2 3
SNT TRC
FID C 2 183
SNT TRC
FID C 2 5
SNT TRC
FID C 2 2
SNT TRC
FID C 2 179
SNT TRC
FID C 2 184
SNT TRC
FID C 2 4
SNT TRC
FID C 2 10
SNT TRC
FID C 8 64
SNT TRC
FID C 8 3
SNT VIA
FID C 2 552
FID C 7 332
FID C 8 517
FID C 10 1056
FID C 11 2426
FID H 12 253
SNT VIA
FID C 2 526
FID C 7 271
FID C 8 456
FID C 10 995
FID C 11 2365
FID H 12 192
#NET 123
NET PCIE_CLK_N
SNT TOP T 77 281
FID C 9 302
FID C 10 342
FID C 11 1710
SNT TOP B 13 1
FID C 1 33
FID C 7 68
FID C 8 257
SNT TRC
FID C 11 416
SNT TRC
FID C 11 11
SNT TRC
FID C 11 408
SNT TRC
FID C 2 258
SNT TRC
FID C 11 8
SNT TRC
FID C 2 260
SNT TRC
FID C 2 34
SNT TRC
FID C 2 31
SNT TRC
FID C 2 250
SNT TRC
FID C 2 226
SNT TRC
FID C 2 222
SNT TRC
FID C 2 216
SNT TRC
FID C 2 16
SNT TRC
FID C 2 205
SNT TRC
FID C 2 214
SNT TRC
FID C 2 213
SNT TRC
FID C 2 187
SNT TRC
FID C 2 9
SNT TRC
FID C 2 17
SNT TRC
FID C 2 186
SNT TRC
FID C 2 8
SNT TRC
FID C 2 7
SNT TRC
FID C 2 6
SNT TRC
FID C 2 185
SNT TRC
FID C 2 201
SNT TRC
FID C 2 13
SNT TRC
FID C 2 12
SNT TRC
FID C 2 199
SNT TRC
FID C 2 198
SNT TRC
FID C 8 67
SNT TRC
FID C 2 11
SNT TRC
FID C 8 68
SNT VIA
FID C 2 548
FID C 7 324
FID C 8 509
FID C 10 1048
FID C 11 2418
FID H 12 245
SNT VIA
FID C 2 528
FID C 7 274
FID C 8 459
FID C 10 998
FID C 11 2368
FID H 12 195
#NET 124
NET PCIE_PERST
SNT TOP T 76 10
FID C 1 19
FID C 7 52
FID C 8 241
SNT TOP T 63 0
FID C 9 172
FID C 10 205
FID C 11 1578
SNT TOP T 77 184
FID C 9 119
FID C 10 149
FID C 11 1520
SNT TRC
FID C 8 55
SNT TRC
FID C 8 45
SNT TRC
FID C 8 47
SNT TRC
FID C 8 56
SNT TRC
FID C 8 46
SNT TRC
FID C 11 272
SNT TRC
FID C 11 248
SNT TRC
FID C 11 213
SNT TRC
FID C 11 265
SNT TRC
FID C 11 266
SNT TRC
FID C 11 275
SNT VIA
FID C 7 229
FID C 8 414
FID C 10 953
FID C 11 2323
FID H 12 150
#NET 125
NET PCIE_RX3_N
SNT TOP T 76 59
FID C 9 389
FID C 10 429
FID C 11 1797
SNT TOP T 77 268
FID C 9 336
FID C 10 376
FID C 11 1744
SNT TRC
FID C 3 374
SNT TRC
FID C 3 72
SNT TRC
FID C 3 367
SNT TRC
FID C 3 368
SNT TRC
FID C 3 79
SNT TRC
FID C 3 78
SNT TRC
FID C 3 80
SNT TRC
FID C 3 372
SNT TRC
FID C 3 371
SNT TRC
FID C 3 354
SNT TRC
FID C 3 355
SNT TRC
FID C 3 71
SNT TRC
FID C 3 87
SNT TRC
FID C 3 84
SNT TRC
FID C 3 379
SNT TRC
FID C 3 353
SNT TRC
FID C 11 45
SNT TRC
FID C 11 560
SNT TRC
FID C 11 44
SNT TRC
FID C 11 561
SNT TRC
FID C 3 335
SNT TRC
FID C 3 339
SNT TRC
FID C 3 58
SNT TRC
FID C 11 486
SNT TRC
FID C 11 25
SNT TRC
FID C 3 59
SNT TRC
FID C 3 325
SNT TRC
FID C 3 76
SNT TRC
FID C 3 351
SNT TRC
FID C 3 65
SNT VIA
FID C 3 641
FID C 7 398
FID C 8 583
FID C 10 1122
FID C 11 2492
FID H 12 319
SNT VIA
FID C 3 628
FID C 7 363
FID C 8 548
FID C 10 1087
FID C 11 2457
FID H 12 284
#NET 126
NET PCIE_RX3_P
SNT TOP T 77 266
FID C 9 349
FID C 10 389
FID C 11 1757
SNT TOP T 76 58
FID C 9 380
FID C 10 420
FID C 11 1788
SNT TRC
FID C 3 86
SNT TRC
FID C 3 378
SNT TRC
FID C 3 369
SNT TRC
FID C 3 85
SNT TRC
FID C 3 377
SNT TRC
FID C 3 376
SNT TRC
FID C 3 366
SNT TRC
FID C 3 365
SNT TRC
FID C 3 364
SNT TRC
FID C 3 370
SNT TRC
FID C 3 77
SNT TRC
FID C 3 83
SNT TRC
FID C 3 81
SNT TRC
FID C 3 362
SNT TRC
FID C 3 361
SNT TRC
FID C 3 363
SNT TRC
FID C 11 547
SNT TRC
FID C 11 555
SNT TRC
FID C 11 43
SNT TRC
FID C 11 42
SNT TRC
FID C 11 545
SNT TRC
FID C 11 546
SNT TRC
FID C 3 62
SNT TRC
FID C 3 67
SNT TRC
FID C 3 352
SNT TRC
FID C 3 341
SNT TRC
FID C 11 32
SNT TRC
FID C 3 340
SNT TRC
FID C 11 496
SNT TRC
FID C 3 63
SNT TRC
FID C 3 338
SNT TRC
FID C 3 75
SNT TRC
FID C 3 82
SNT TRC
FID C 3 360
SNT TRC
FID C 3 357
SNT TRC
FID C 3 358
SNT TRC
FID C 3 74
SNT TRC
FID C 3 359
SNT TRC
FID C 3 73
SNT VIA
FID C 3 630
FID C 7 366
FID C 8 551
FID C 10 1090
FID C 11 2460
FID H 12 287
SNT VIA
FID C 3 639
FID C 7 394
FID C 8 579
FID C 10 1118
FID C 11 2488
FID H 12 315
#NET 127
NET PCIE_RX2_N
SNT TOP T 77 263
FID C 9 357
FID C 10 397
FID C 11 1765
SNT TOP T 76 55
FID C 9 350
FID C 10 390
FID C 11 1758
SNT TRC
FID C 3 53
SNT TRC
FID C 3 323
SNT TRC
FID C 3 54
SNT TRC
FID C 3 50
SNT TRC
FID C 3 324
SNT TRC
FID C 11 498
SNT TRC
FID C 11 508
SNT TRC
FID C 3 345
SNT TRC
FID C 3 64
SNT TRC
FID C 3 69
SNT TRC
FID C 11 36
SNT TRC
FID C 3 343
SNT TRC
FID C 3 66
SNT TRC
FID C 11 33
SNT TRC
FID C 11 34
SNT TRC
FID C 11 35
SNT TRC
FID C 3 342
SNT VIA
FID C 3 632
FID C 7 372
FID C 8 557
FID C 10 1096
FID C 11 2466
FID H 12 293
SNT VIA
FID C 3 631
FID C 7 368
FID C 8 553
FID C 10 1092
FID C 11 2462
FID H 12 289
#NET 128
NET PCIE_RX2_P
SNT TOP T 77 261
FID C 9 363
FID C 10 403
FID C 11 1771
SNT TOP T 76 54
FID C 9 332
FID C 10 372
FID C 11 1740
SNT TRC
FID C 11 28
SNT TRC
FID C 11 488
SNT TRC
FID C 11 489
SNT TRC
FID C 3 336
SNT TRC
FID C 3 56
SNT TRC
FID C 3 326
SNT TRC
FID C 11 490
SNT TRC
FID C 11 29
SNT TRC
FID C 11 491
SNT TRC
FID C 3 327
SNT TRC
FID C 11 30
SNT TRC
FID C 11 38
SNT TRC
FID C 3 348
SNT TRC
FID C 3 70
SNT TRC
FID C 11 517
SNT TRC
FID C 3 346
SNT TRC
FID C 3 68
SNT TRC
FID C 3 337
SNT TRC
FID C 3 60
SNT TRC
FID C 3 61
SNT TRC
FID C 3 334
SNT TRC
FID C 3 333
SNT TRC
FID C 3 332
SNT TRC
FID C 3 331
SNT TRC
FID C 3 330
SNT TRC
FID C 3 55
SNT TRC
FID C 3 321
SNT TRC
FID C 3 320
SNT TRC
FID C 3 329
SNT TRC
FID C 3 57
SNT TRC
FID C 3 322
SNT TRC
FID C 3 52
SNT TRC
FID C 3 319
SNT TRC
FID C 3 51
SNT TRC
FID C 3 328
SNT TRC
FID C 11 483
SNT TRC
FID C 11 484
SNT TRC
FID C 11 482
SNT VIA
FID C 3 629
FID C 7 364
FID C 8 549
FID C 10 1088
FID C 11 2458
FID H 12 285
SNT VIA
FID C 3 636
FID C 7 379
FID C 8 564
FID C 10 1103
FID C 11 2473
FID H 12 300
#NET 129
NET PCIE_RX1_N
SNT TOP T 77 275
FID C 9 317
FID C 10 357
FID C 11 1725
SNT TOP T 76 51
FID C 9 299
FID C 10 339
FID C 11 1707
SNT TRC
FID C 3 254
SNT TRC
FID C 3 247
SNT TRC
FID C 3 27
SNT TRC
FID C 3 25
SNT TRC
FID C 3 20
SNT TRC
FID C 3 24
SNT TRC
FID C 3 257
SNT TRC
FID C 3 30
SNT TRC
FID C 3 263
SNT TRC
FID C 3 21
SNT TRC
FID C 3 26
SNT TRC
FID C 11 409
SNT TRC
FID C 3 33
SNT TRC
FID C 3 272
SNT TRC
FID C 3 267
SNT TRC
FID C 3 36
SNT TRC
FID C 3 258
SNT TRC
FID C 3 28
SNT TRC
FID C 3 40
SNT TRC
FID C 3 278
SNT TRC
FID C 3 309
SNT TRC
FID C 11 447
SNT TRC
FID C 11 19
SNT TRC
FID C 11 440
SNT TRC
FID C 11 18
SNT TRC
FID C 11 439
SNT TRC
FID C 11 17
SNT TRC
FID C 3 304
SNT TRC
FID C 3 48
SNT TRC
FID C 3 44
SNT TRC
FID C 3 285
SNT TRC
FID C 11 411
SNT TRC
FID C 11 10
SNT TRC
FID C 11 13
SNT TRC
FID C 11 9
SNT VIA
FID C 3 616
FID C 7 329
FID C 8 514
FID C 10 1053
FID C 11 2423
FID H 12 250
SNT VIA
FID C 3 622
FID C 7 341
FID C 8 526
FID C 10 1065
FID C 11 2435
FID H 12 262
#NET 130
NET PCIE_RX1_P
SNT TOP T 77 273
FID C 9 323
FID C 10 363
FID C 11 1731
SNT TOP T 76 50
FID C 9 290
FID C 10 330
FID C 11 1698
SNT TRC
FID C 3 23
SNT TRC
FID C 11 7
SNT TRC
FID C 11 463
SNT TRC
FID C 11 23
SNT TRC
FID C 11 22
SNT TRC
FID C 3 313
SNT TRC
FID C 11 451
SNT TRC
FID C 3 49
SNT TRC
FID C 3 312
SNT TRC
FID C 3 46
SNT TRC
FID C 3 293
SNT TRC
FID C 3 292
SNT TRC
FID C 3 39
SNT TRC
FID C 3 38
SNT TRC
FID C 3 279
SNT TRC
FID C 3 276
SNT TRC
FID C 3 275
SNT TRC
FID C 3 274
SNT TRC
FID C 3 43
SNT TRC
FID C 3 271
SNT TRC
FID C 3 32
SNT TRC
FID C 3 35
SNT TRC
FID C 3 34
SNT TRC
FID C 3 270
SNT TRC
FID C 3 269
SNT TRC
FID C 3 268
SNT TRC
FID C 3 264
SNT TRC
FID C 3 261
SNT TRC
FID C 3 29
SNT TRC
FID C 11 396
SNT TRC
FID C 11 6
SNT VIA
FID C 3 611
FID C 7 316
FID C 8 501
FID C 10 1040
FID C 11 2410
FID H 12 237
SNT VIA
FID C 3 625
FID C 7 350
FID C 8 535
FID C 10 1074
FID C 11 2444
FID H 12 271
#NET 131
NET PCIE_RX0_N
SNT TOP T 77 280
FID C 9 303
FID C 10 343
FID C 11 1711
SNT TOP T 76 46
FID C 9 246
FID C 10 285
FID C 11 1654
SNT TRC
FID C 11 12
SNT TRC
FID C 3 42
SNT TRC
FID C 3 289
SNT TRC
FID C 3 31
SNT TRC
FID C 11 417
SNT TRC
FID C 3 284
SNT TRC
FID C 3 245
SNT TRC
FID C 3 241
SNT TRC
FID C 3 19
SNT TRC
FID C 3 240
SNT TRC
FID C 3 17
SNT TRC
FID C 3 237
SNT TRC
FID C 3 234
SNT TRC
FID C 3 16
SNT TRC
FID C 3 230
SNT TRC
FID C 3 231
SNT TRC
FID C 3 15
SNT TRC
FID C 3 14
SNT TRC
FID C 3 228
SNT TRC
FID C 3 13
SNT TRC
FID C 3 221
SNT TRC
FID C 3 11
SNT TRC
FID C 3 12
SNT TRC
FID C 3 10
SNT TRC
FID C 3 9
SNT TRC
FID C 3 220
SNT TRC
FID C 3 7
SNT TRC
FID C 3 8
SNT TRC
FID C 3 217
SNT TRC
FID C 3 211
SNT TRC
FID C 3 5
SNT TRC
FID C 3 4
SNT TRC
FID C 3 212
SNT TRC
FID C 3 208
SNT TRC
FID C 11 3
SNT TRC
FID C 11 341
SNT TRC
FID C 11 2
SNT VIA
FID C 3 617
FID C 7 330
FID C 8 515
FID C 10 1054
FID C 11 2424
FID H 12 251
SNT VIA
FID C 3 599
FID C 7 291
FID C 8 476
FID C 10 1015
FID C 11 2385
FID H 12 212
#NET 132
NET PCIE_RX0_P
SNT TOP T 77 278
FID C 9 309
FID C 10 349
FID C 11 1717
SNT TOP T 76 45
FID C 9 235
FID C 10 270
FID C 11 1643
SNT TRC
FID C 3 18
SNT TRC
FID C 3 6
SNT TRC
FID C 3 22
SNT TRC
FID C 3 216
SNT TRC
FID C 3 243
SNT TRC
FID C 3 2
SNT TRC
FID C 3 251
SNT TRC
FID C 3 215
SNT TRC
FID C 3 250
SNT TRC
FID C 11 16
SNT TRC
FID C 3 301
SNT TRC
FID C 11 430
SNT TRC
FID C 3 300
SNT TRC
FID C 3 45
SNT TRC
FID C 3 296
SNT TRC
FID C 3 37
SNT TRC
FID C 3 196
SNT TRC
FID C 3 3
SNT TRC
FID C 3 200
SNT TRC
FID C 11 1
SNT TRC
FID C 11 328
SNT VIA
FID C 3 621
FID C 7 339
FID C 8 524
FID C 10 1063
FID C 11 2433
FID H 12 260
SNT VIA
FID C 3 594
FID C 7 284
FID C 8 469
FID C 10 1008
FID C 11 2378
FID H 12 205
#NET 133
NET LED1
SNT TOP T 57 0
FID C 9 13
FID C 10 35
FID C 11 1409
SNT TOP T 77 80
FID C 9 465
FID C 10 509
FID C 11 1877
SNT TRC
FID C 2 144
SNT TRC
FID C 3 161
SNT TRC
FID C 11 662
SNT TRC
FID C 11 665
SNT TRC
FID C 11 60
SNT TRC
FID C 11 61
SNT TRC
FID C 11 76
SNT VIA
FID C 2 507
FID C 7 233
FID C 8 418
FID C 10 957
FID C 11 2327
FID H 12 154
SNT VIA
FID C 3 659
FID C 7 434
FID C 8 619
FID C 10 1158
FID C 11 2528
FID H 12 355
SNT VIA
FID C 2 506
FID C 3 578
FID C 7 232
FID C 8 417
FID C 10 956
FID C 11 2326
FID H 12 153
#NET 134
NET LED2
SNT TOP T 56 0
FID C 9 25
FID C 10 47
FID C 11 1421
SNT TOP T 77 78
FID C 9 466
FID C 10 510
FID C 11 1878
SNT TRC
FID C 2 146
SNT TRC
FID C 2 145
SNT TRC
FID C 3 166
SNT TRC
FID C 3 431
SNT TRC
FID C 3 165
SNT TRC
FID C 11 684
SNT TRC
FID C 11 678
SNT TRC
FID C 11 673
SNT TRC
FID C 11 77
SNT TRC
FID C 11 78
SNT TRC
FID C 11 109
SNT VIA
FID C 2 509
FID C 7 235
FID C 8 420
FID C 10 959
FID C 11 2329
FID H 12 156
SNT VIA
FID C 3 662
FID C 7 439
FID C 8 624
FID C 10 1163
FID C 11 2533
FID H 12 360
SNT VIA
FID C 2 508
FID C 3 579
FID C 7 234
FID C 8 419
FID C 10 958
FID C 11 2328
FID H 12 155
#NET 135
NET GND
SNT TOP B 0 9
FID C 1 25
FID C 7 60
FID C 8 249
SNT TOP B 2 1
FID C 1 30
FID C 7 65
FID C 8 254
SNT TOP B 3 1
FID C 1 49
FID C 7 89
FID C 8 273
SNT TOP B 4 1
FID C 1 57
FID C 7 97
FID C 8 281
SNT TOP B 1 1
FID C 1 34
FID C 7 69
FID C 8 258
SNT TOP T 76 3
FID C 1 12
FID C 7 42
FID C 8 230
SNT TOP T 76 17
FID C 1 46
FID C 7 86
FID C 8 270
SNT TOP T 76 19
FID C 1 48
FID C 7 88
FID C 8 272
SNT TOP T 76 26
FID C 1 67
FID C 7 107
FID C 8 291
SNT TOP T 76 30
FID C 1 75
FID C 7 118
FID C 8 302
SNT TOP T 76 22
FID C 1 59
FID C 7 99
FID C 8 283
SNT TOP T 76 27
FID C 1 68
FID C 7 108
FID C 8 292
SNT TOP T 76 23
FID C 1 60
FID C 7 100
FID C 8 284
SNT TOP T 76 11
FID C 1 20
FID C 7 55
FID C 8 244
SNT TOP T 76 14
FID C 1 35
FID C 7 74
FID C 8 259
SNT TOP T 144 1
FID C 4 22
FID C 5 22
FID C 7 26
FID C 8 216
FID C 10 26
FID C 11 1400
FID H 12 17
SNT TOP T 144 2
FID C 4 21
FID C 5 21
FID C 7 25
FID C 8 215
FID C 10 25
FID C 11 1399
FID H 12 16
SNT TOP T 144 3
FID C 4 11
FID C 5 11
FID C 7 11
FID C 8 201
FID C 10 11
FID C 11 1385
FID H 12 2
SNT TOP T 144 4
FID C 4 12
FID C 5 12
FID C 7 12
FID C 8 202
FID C 10 12
FID C 11 1386
FID H 12 3
SNT TOP T 145 1
FID C 4 24
FID C 5 24
FID C 7 28
FID C 8 218
FID C 10 28
FID C 11 1402
FID H 12 19
SNT TOP T 145 2
FID C 4 23
FID C 5 23
FID C 7 27
FID C 8 217
FID C 10 27
FID C 11 1401
FID H 12 18
SNT TOP T 145 3
FID C 4 13
FID C 5 13
FID C 7 13
FID C 8 203
FID C 10 13
FID C 11 1387
FID H 12 4
SNT TOP T 145 4
FID C 4 14
FID C 5 14
FID C 7 14
FID C 8 204
FID C 10 14
FID C 11 1388
FID H 12 5
SNT TOP T 146 1
FID C 4 26
FID C 5 26
FID C 7 30
FID C 8 220
FID C 10 30
FID C 11 1404
FID H 12 21
SNT TOP T 146 2
FID C 4 25
FID C 5 25
FID C 7 29
FID C 8 219
FID C 10 29
FID C 11 1403
FID H 12 20
SNT TOP T 146 3
FID C 4 15
FID C 5 15
FID C 7 15
FID C 8 205
FID C 10 15
FID C 11 1389
FID H 12 6
SNT TOP T 146 4
FID C 4 16
FID C 5 16
FID C 7 16
FID C 8 206
FID C 10 16
FID C 11 1390
FID H 12 7
SNT TOP T 81 7
FID C 4 34
FID C 5 34
FID C 7 154
FID C 8 336
FID C 10 871
FID C 11 2237
FID H 12 75
SNT TOP T 81 6
FID C 4 33
FID C 5 33
FID C 7 152
FID C 8 334
FID C 10 859
FID C 11 2225
FID H 12 73
SNT TOP T 81 5
FID C 4 32
FID C 5 32
FID C 7 149
FID C 8 331
FID C 10 827
FID C 11 2193
FID H 12 70
SNT TOP T 143 1
FID C 4 20
FID C 5 20
FID C 7 24
FID C 8 214
FID C 10 24
FID C 11 1398
FID H 12 15
SNT TOP T 143 2
FID C 4 19
FID C 5 19
FID C 7 23
FID C 8 213
FID C 10 23
FID C 11 1397
FID H 12 14
SNT TOP T 143 3
FID C 4 9
FID C 5 9
FID C 7 9
FID C 8 199
FID C 10 9
FID C 11 1383
FID H 12 0
SNT TOP T 143 4
FID C 4 10
FID C 5 10
FID C 7 10
FID C 8 200
FID C 10 10
FID C 11 1384
FID H 12 1
SNT TOP T 82 2
FID C 4 30
FID C 5 30
FID C 7 146
FID C 8 328
FID C 10 747
FID C 11 2113
FID H 12 67
SNT TOP T 82 1
FID C 4 31
FID C 5 31
FID C 7 148
FID C 8 330
FID C 10 757
FID C 11 2123
FID H 12 69
SNT TOP T 13 5
FID C 4 28
FID C 5 28
FID C 7 138
FID C 8 320
FID C 10 730
FID C 11 2096
FID H 12 59
SNT TOP T 40 21
FID C 4 29
FID C 5 29
FID C 7 142
FID C 8 324
FID C 10 738
FID C 11 2104
FID H 12 63
SNT TOP T 40 23
FID C 4 27
FID C 5 27
FID C 7 128
FID C 8 310
FID C 10 652
FID C 11 2018
FID H 12 49
SNT TOP T 16 0
FID C 9 642
FID C 10 696
FID C 11 2062
SNT TOP T 17 0
FID C 9 599
FID C 10 649
FID C 11 2015
SNT TOP T 18 0
FID C 9 613
FID C 10 666
FID C 11 2032
SNT TOP T 21 0
FID C 9 634
FID C 10 687
FID C 11 2053
SNT TOP T 22 0
FID C 9 641
FID C 10 695
FID C 11 2061
SNT TOP T 23 0
FID C 9 645
FID C 10 699
FID C 11 2065
SNT TOP T 24 0
FID C 9 650
FID C 10 707
FID C 11 2073
SNT TOP T 25 0
FID C 9 654
FID C 10 711
FID C 11 2077
SNT TOP T 26 0
FID C 9 659
FID C 10 716
FID C 11 2082
SNT TOP T 27 0
FID C 9 639
FID C 10 693
FID C 11 2059
SNT TOP T 28 0
FID C 9 757
FID C 10 832
FID C 11 2198
SNT TOP T 29 0
FID C 9 760
FID C 10 835
FID C 11 2201
SNT TOP T 30 0
FID C 9 150
FID C 10 180
FID C 11 1551
SNT TOP T 31 0
FID C 9 108
FID C 10 138
FID C 11 1509
SNT TOP T 43 12
FID C 9 605
FID C 10 657
FID C 11 2023
SNT TOP T 43 4
FID C 9 579
FID C 10 627
FID C 11 1993
SNT TOP T 46 3
FID C 9 763
FID C 10 838
FID C 11 2204
SNT TOP T 49 0
FID C 9 655
FID C 10 712
FID C 11 2078
SNT TOP T 68 0
FID C 9 679
FID C 10 749
FID C 11 2115
SNT TOP T 69 0
FID C 9 800
FID C 10 880
FID C 11 2246
SNT TOP T 70 0
FID C 9 718
FID C 10 790
FID C 11 2156
SNT TOP T 71 0
FID C 9 783
FID C 10 858
FID C 11 2224
SNT TOP T 87 1
FID C 9 46
FID C 10 68
FID C 11 1442
SNT TOP T 88 1
FID C 9 48
FID C 10 70
FID C 11 1444
SNT TOP T 89 1
FID C 9 47
FID C 10 69
FID C 11 1443
SNT TOP T 97 0
FID C 9 444
FID C 10 487
FID C 11 1855
SNT TOP T 98 0
FID C 9 337
FID C 10 377
FID C 11 1745
SNT TOP T 99 0
FID C 9 371
FID C 10 411
FID C 11 1779
SNT TOP T 104 0
FID C 9 565
FID C 10 613
FID C 11 1979
SNT TOP T 105 0
FID C 9 574
FID C 10 622
FID C 11 1988
SNT TOP T 106 0
FID C 9 566
FID C 10 614
FID C 11 1980
SNT TOP T 107 1
FID C 9 563
FID C 10 611
FID C 11 1977
SNT TOP T 108 1
FID C 9 560
FID C 10 608
FID C 11 1974
SNT TOP T 109 1
FID C 9 330
FID C 10 370
FID C 11 1738
SNT TOP T 110 1
FID C 9 304
FID C 10 344
FID C 11 1712
SNT TOP T 111 1
FID C 9 171
FID C 10 204
FID C 11 1577
SNT TOP T 112 1
FID C 9 182
FID C 10 217
FID C 11 1590
SNT TOP T 113 1
FID C 9 755
FID C 10 830
FID C 11 2196
SNT TOP T 114 1
FID C 9 733
FID C 10 805
FID C 11 2171
SNT TOP T 115 0
FID C 9 637
FID C 10 691
FID C 11 2057
SNT TOP T 116 0
FID C 9 626
FID C 10 679
FID C 11 2045
SNT TOP T 118 0
FID C 9 685
FID C 10 755
FID C 11 2121
SNT TOP T 121 1
FID C 9 770
FID C 10 845
FID C 11 2211
SNT TOP T 122 1
FID C 9 769
FID C 10 844
FID C 11 2210
SNT TOP T 123 1
FID C 9 768
FID C 10 843
FID C 11 2209
SNT TOP T 124 1
FID C 9 767
FID C 10 842
FID C 11 2208
SNT TOP T 125 1
FID C 9 762
FID C 10 837
FID C 11 2203
SNT TOP T 126 1
FID C 9 761
FID C 10 836
FID C 11 2202
SNT TOP T 127 1
FID C 9 716
FID C 10 788
FID C 11 2154
SNT TOP T 128 1
FID C 9 715
FID C 10 787
FID C 11 2153
SNT TOP T 129 1
FID C 9 714
FID C 10 786
FID C 11 2152
SNT TOP T 130 1
FID C 9 717
FID C 10 789
FID C 11 2155
SNT TOP T 131 1
FID C 9 720
FID C 10 792
FID C 11 2158
SNT TOP T 132 1
FID C 9 698
FID C 10 770
FID C 11 2136
SNT TOP T 133 1
FID C 9 772
FID C 10 847
FID C 11 2213
SNT TOP T 134 1
FID C 9 706
FID C 10 778
FID C 11 2144
SNT TOP T 137 1
FID C 9 674
FID C 10 741
FID C 11 2107
SNT TOP T 138 1
FID C 9 675
FID C 10 744
FID C 11 2110
SNT TOP T 140 1
FID C 9 20
FID C 10 42
FID C 11 1416
SNT TOP T 140 2
FID C 9 19
FID C 10 41
FID C 11 1415
SNT TOP T 141 2
FID C 9 23
FID C 10 45
FID C 11 1419
SNT TOP T 141 1
FID C 9 24
FID C 10 46
FID C 11 1420
SNT TOP T 142 2
FID C 9 21
FID C 10 43
FID C 11 1417
SNT TOP T 142 1
FID C 9 22
FID C 10 44
FID C 11 1418
SNT TOP T 77 12
FID C 9 499
FID C 10 543
FID C 11 1911
SNT TOP T 77 22
FID C 9 494
FID C 10 538
FID C 11 1906
SNT TOP T 77 32
FID C 9 489
FID C 10 533
FID C 11 1901
SNT TOP T 77 42
FID C 9 484
FID C 10 528
FID C 11 1896
SNT TOP T 77 52
FID C 9 479
FID C 10 523
FID C 11 1891
SNT TOP T 77 62
FID C 9 474
FID C 10 518
FID C 11 1886
SNT TOP T 77 72
FID C 9 469
FID C 10 513
FID C 11 1881
SNT TOP T 77 13
FID C 9 555
FID C 10 603
FID C 11 1969
SNT TOP T 77 23
FID C 9 550
FID C 10 598
FID C 11 1964
SNT TOP T 77 33
FID C 9 545
FID C 10 593
FID C 11 1959
SNT TOP T 77 43
FID C 9 540
FID C 10 588
FID C 11 1954
SNT TOP T 77 53
FID C 9 535
FID C 10 583
FID C 11 1949
SNT TOP T 77 63
FID C 9 530
FID C 10 578
FID C 11 1944
SNT TOP T 77 73
FID C 9 525
FID C 10 573
FID C 11 1939
SNT TOP T 77 153
FID C 9 377
FID C 10 417
FID C 11 1785
SNT TOP T 77 143
FID C 9 352
FID C 10 392
FID C 11 1760
SNT TOP T 77 133
FID C 9 316
FID C 10 356
FID C 11 1724
SNT TOP T 77 123
FID C 9 292
FID C 10 332
FID C 11 1700
SNT TOP T 77 113
FID C 9 263
FID C 10 303
FID C 11 1671
SNT TOP T 77 103
FID C 9 239
FID C 10 274
FID C 11 1647
SNT TOP T 77 93
FID C 9 205
FID C 10 240
FID C 11 1613
SNT TOP T 77 152
FID C 9 376
FID C 10 416
FID C 11 1784
SNT TOP T 77 142
FID C 9 351
FID C 10 391
FID C 11 1759
SNT TOP T 77 132
FID C 9 315
FID C 10 355
FID C 11 1723
SNT TOP T 77 122
FID C 9 291
FID C 10 331
FID C 11 1699
SNT TOP T 77 112
FID C 9 262
FID C 10 302
FID C 11 1670
SNT TOP T 77 102
FID C 9 238
FID C 10 273
FID C 11 1646
SNT TOP T 77 92
FID C 9 204
FID C 10 239
FID C 11 1612
SNT TOP T 77 172
FID C 9 113
FID C 10 143
FID C 11 1514
SNT TOP T 77 182
FID C 9 118
FID C 10 148
FID C 11 1519
SNT TOP T 77 192
FID C 9 123
FID C 10 153
FID C 11 1524
SNT TOP T 77 202
FID C 9 128
FID C 10 158
FID C 11 1529
SNT TOP T 77 212
FID C 9 133
FID C 10 163
FID C 11 1534
SNT TOP T 77 222
FID C 9 138
FID C 10 168
FID C 11 1539
SNT TOP T 77 232
FID C 9 143
FID C 10 173
FID C 11 1544
SNT TOP T 77 173
FID C 9 61
FID C 10 87
FID C 11 1460
SNT TOP T 77 183
FID C 9 66
FID C 10 92
FID C 11 1465
SNT TOP T 77 193
FID C 9 71
FID C 10 97
FID C 11 1470
SNT TOP T 77 203
FID C 9 76
FID C 10 102
FID C 11 1475
SNT TOP T 77 213
FID C 9 81
FID C 10 107
FID C 11 1480
SNT TOP T 77 223
FID C 9 86
FID C 10 112
FID C 11 1485
SNT TOP T 77 233
FID C 9 91
FID C 10 117
FID C 11 1490
SNT TOP T 77 252
FID C 9 384
FID C 10 424
FID C 11 1792
SNT TOP T 77 258
FID C 9 369
FID C 10 409
FID C 11 1777
SNT TOP T 77 264
FID C 9 354
FID C 10 394
FID C 11 1762
SNT TOP T 77 270
FID C 9 329
FID C 10 369
FID C 11 1737
SNT TOP T 77 276
FID C 9 314
FID C 10 354
FID C 11 1722
SNT TOP T 77 282
FID C 9 298
FID C 10 338
FID C 11 1706
SNT TOP T 77 292
FID C 9 272
FID C 10 312
FID C 11 1680
SNT TOP T 77 302
FID C 9 245
FID C 10 280
FID C 11 1653
SNT TOP T 77 312
FID C 9 213
FID C 10 248
FID C 11 1621
SNT TOP T 77 253
FID C 9 383
FID C 10 423
FID C 11 1791
SNT TOP T 77 283
FID C 9 297
FID C 10 337
FID C 11 1705
SNT TOP T 77 293
FID C 9 271
FID C 10 311
FID C 11 1679
SNT TOP T 77 303
FID C 9 244
FID C 10 279
FID C 11 1652
SNT TOP T 77 313
FID C 9 212
FID C 10 247
FID C 11 1620
SNT TOP T 20 0
FID C 9 628
FID C 10 681
FID C 11 2047
SNT TOP T 19 0
FID C 9 610
FID C 10 662
FID C 11 2028
SNT TOP T 15 0
FID C 9 651
FID C 10 708
FID C 11 2074
SNT TOP T 86 1
FID C 9 45
FID C 10 67
FID C 11 1441
SNT TOP T 42 24
FID C 9 747
FID C 10 819
FID C 11 2185
SNT TOP T 42 1
FID C 9 740
FID C 10 812
FID C 11 2178
SNT TOP T 48 0
FID C 9 667
FID C 10 727
FID C 11 2093
SNT TOP T 44 9
FID C 9 448
FID C 10 492
FID C 11 1860
SNT TOP T 44 1
FID C 9 397
FID C 10 437
FID C 11 1805
SNT TOP T 38 3
FID C 9 453
FID C 10 497
FID C 11 1865
SNT TOP T 39 4
FID C 9 446
FID C 10 490
FID C 11 1858
SNT TOP T 45 3
FID C 9 713
FID C 10 785
FID C 11 2151
SNT TOP T 34 12
FID C 9 156
FID C 10 186
FID C 11 1558
SNT TOP T 34 4
FID C 9 100
FID C 10 126
FID C 11 1499
SNT TOP T 96 0
FID C 9 504
FID C 10 548
FID C 11 1916
SNT TOP T 139 1
FID C 9 18
FID C 10 40
FID C 11 1414
SNT TOP T 139 2
FID C 9 17
FID C 10 39
FID C 11 1413
SNT TOP T 80 10
FID C 9 584
FID C 10 633
FID C 11 1999
SNT TOP T 35 10
FID C 9 203
FID C 10 238
FID C 11 1611
SNT TOP T 120 0
FID C 9 794
FID C 10 874
FID C 11 2240
SNT TOP T 12 12
FID C 9 422
FID C 10 465
FID C 11 1833
SNT TOP T 14 0
FID C 9 666
FID C 10 724
FID C 11 2090
SNT TOP T 40 7
FID C 9 591
FID C 10 640
FID C 11 2006
SNT TOP T 40 8
FID C 9 619
FID C 10 672
FID C 11 2038
SNT TOP T 40 14
FID C 9 622
FID C 10 675
FID C 11 2041
SNT TOP T 41 9
FID C 9 219
FID C 10 254
FID C 11 1627
SNT TOP T 75 0
FID C 9 632
FID C 10 685
FID C 11 2051
SNT TOP T 0 8
FID C 9 442
FID C 10 485
FID C 11 1853
SNT TOP T 0 7
FID C 9 441
FID C 10 484
FID C 11 1852
SNT TOP T 0 2
FID C 9 432
FID C 10 475
FID C 11 1843
SNT TOP T 76 49
FID C 9 281
FID C 10 321
FID C 11 1689
SNT TOP T 76 47
FID C 9 257
FID C 10 297
FID C 11 1665
SNT TOP T 76 44
FID C 9 223
FID C 10 258
FID C 11 1631
SNT TOP T 76 56
FID C 9 360
FID C 10 400
FID C 11 1768
SNT TOP T 76 35
FID C 9 162
FID C 10 192
FID C 11 1564
SNT TOP T 76 38
FID C 9 167
FID C 10 197
FID C 11 1569
SNT TOP T 76 52
FID C 9 310
FID C 10 350
FID C 11 1718
SNT TOP T 76 53
FID C 9 320
FID C 10 360
FID C 11 1728
SNT TOP T 76 57
FID C 9 370
FID C 10 410
FID C 11 1778
SNT TOP T 76 60
FID C 9 402
FID C 10 442
FID C 11 1810
SNT TOP T 76 63
FID C 9 417
FID C 10 460
FID C 11 1828
SNT TRC
FID C 8 138
SNT TRC
FID C 8 139
SNT TRC
FID C 8 140
SNT TRC
FID C 8 24
SNT TRC
FID C 11 565
SNT TRC
FID C 11 46
SNT TRC
FID C 11 570
SNT TRC
FID C 11 569
SNT TRC
FID C 11 5
SNT TRC
FID C 8 5
SNT TRC
FID C 11 358
SNT TRC
FID C 11 357
SNT TRC
FID C 11 347
SNT TRC
FID C 8 80
SNT TRC
FID C 8 82
SNT TRC
FID C 11 585
SNT TRC
FID C 11 586
SNT TRC
FID C 11 405
SNT TRC
FID C 11 404
SNT TRC
FID C 11 420
SNT TRC
FID C 8 105
SNT TRC
FID C 11 421
SNT TRC
FID C 11 419
SNT TRC
FID C 11 457
SNT TRC
FID C 11 450
SNT TRC
FID C 11 460
SNT TRC
FID C 8 133
SNT TRC
FID C 11 339
SNT TRC
FID C 11 468
SNT TRC
FID C 11 471
SNT TRC
FID C 11 501
SNT TRC
FID C 11 502
SNT TRC
FID C 11 527
SNT TRC
FID C 11 528
SNT TRC
FID C 11 572
SNT TRC
FID C 11 571
SNT TRC
FID C 11 389
SNT TRC
FID C 11 388
SNT TRC
FID C 8 98
SNT TRC
FID C 8 163
SNT TRC
FID C 8 164
SNT TRC
FID C 3 428
SNT TRC
FID C 3 424
SNT TRC
FID C 3 411
SNT TRC
FID C 3 393
SNT TRC
FID C 3 405
SNT TRC
FID C 3 398
SNT TRC
FID C 3 412
SNT TRC
FID C 3 419
SNT TRC
FID C 3 408
SNT TRC
FID C 3 406
SNT TRC
FID C 3 407
SNT TRC
FID C 3 409
SNT TRC
FID C 3 410
SNT TRC
FID C 8 70
SNT TRC
FID C 8 66
SNT TRC
FID C 8 65
SNT TRC
FID C 8 60
SNT TRC
FID C 8 73
SNT TRC
FID C 8 78
SNT TRC
FID C 8 74
SNT TRC
FID C 8 79
SNT TRC
FID C 8 81
SNT TRC
FID C 8 108
SNT TRC
FID C 8 106
SNT TRC
FID C 8 72
SNT TRC
FID C 8 71
SNT TRC
FID C 8 77
SNT TRC
FID C 8 76
SNT TRC
FID C 8 109
SNT TRC
FID C 8 114
SNT TRC
FID C 8 119
SNT TRC
FID C 8 158
SNT TRC
FID C 8 147
SNT TRC
FID C 8 129
SNT TRC
FID C 8 57
SNT TRC
FID C 8 130
SNT TRC
FID C 8 159
SNT TRC
FID C 8 162
SNT TRC
FID C 8 160
SNT TRC
FID C 8 143
SNT TRC
FID C 8 141
SNT TRC
FID C 8 142
SNT TRC
FID C 8 125
SNT TRC
FID C 8 123
SNT TRC
FID C 8 146
SNT TRC
FID C 8 161
SNT TRC
FID C 8 104
SNT TRC
FID C 8 144
SNT TRC
FID C 8 124
SNT TRC
FID C 8 131
SNT TRC
FID C 8 145
SNT TRC
FID C 8 48
SNT TRC
FID C 11 66
SNT TRC
FID C 11 75
SNT TRC
FID C 11 74
SNT TRC
FID C 11 73
SNT TRC
FID C 11 72
SNT TRC
FID C 11 65
SNT TRC
FID C 11 71
SNT TRC
FID C 11 70
SNT TRC
FID C 11 69
SNT TRC
FID C 11 68
SNT TRC
FID C 11 67
SNT TRC
FID C 11 121
SNT TRC
FID C 11 115
SNT TRC
FID C 11 122
SNT TRC
FID C 11 116
SNT TRC
FID C 11 631
SNT TRC
FID C 11 632
SNT TRC
FID C 11 739
SNT TRC
FID C 11 747
SNT TRC
FID C 11 740
SNT TRC
FID C 11 474
SNT TRC
FID C 11 475
SNT TRC
FID C 11 480
SNT TRC
FID C 11 481
SNT TRC
FID C 11 487
SNT TRC
FID C 11 533
SNT TRC
FID C 11 532
SNT TRC
FID C 11 1044
SNT TRC
FID C 11 1043
SNT TRC
FID C 11 1042
SNT TRC
FID C 11 1040
SNT TRC
FID C 11 1039
SNT TRC
FID C 11 1006
SNT TRC
FID C 11 954
SNT TRC
FID C 11 957
SNT TRC
FID C 11 958
SNT TRC
FID C 11 868
SNT TRC
FID C 11 864
SNT TRC
FID C 11 866
SNT TRC
FID C 11 1036
SNT TRC
FID C 11 1079
SNT TRC
FID C 11 1084
SNT TRC
FID C 11 1231
SNT TRC
FID C 11 1217
SNT TRC
FID C 11 1229
SNT TRC
FID C 11 1216
SNT TRC
FID C 11 1215
SNT TRC
FID C 11 1214
SNT TRC
FID C 11 1221
SNT TRC
FID C 11 1220
SNT TRC
FID C 11 1178
SNT TRC
FID C 11 1126
SNT TRC
FID C 11 1130
SNT TRC
FID C 11 1228
SNT TRC
FID C 11 1199
SNT TRC
FID C 11 1313
SNT TRC
FID C 11 1322
SNT TRC
FID C 11 1378
SNT TRC
FID C 11 1375
SNT TRC
FID C 11 1381
SNT TRC
FID C 11 1318
SNT TRC
FID C 11 1335
SNT TRC
FID C 11 1347
SNT TRC
FID C 11 1351
SNT TRC
FID C 11 1298
SNT TRC
FID C 11 1302
SNT TRC
FID C 11 1301
SNT TRC
FID C 11 1305
SNT TRC
FID C 11 1300
SNT TRC
FID C 11 1304
SNT TRC
FID C 11 1299
SNT TRC
FID C 11 1303
SNT TRC
FID C 11 1289
SNT TRC
FID C 11 814
SNT TRC
FID C 11 338
SNT TRC
FID C 11 1110
SNT TRC
FID C 11 1109
SNT TRC
FID C 11 1114
SNT TRC
FID C 11 841
SNT TRC
FID C 11 840
SNT TRC
FID C 11 839
SNT TRC
FID C 11 821
SNT TRC
FID C 11 818
SNT TRC
FID C 11 824
SNT TRC
FID C 11 817
SNT TRC
FID C 11 882
SNT TRC
FID C 11 865
SNT TRC
FID C 11 863
SNT TRC
FID C 11 853
SNT TRC
FID C 11 852
SNT TRC
FID C 11 298
SNT TRC
FID C 11 297
SNT TRC
FID C 11 205
SNT TRC
FID C 11 209
SNT TRC
FID C 11 383
SNT TRC
FID C 11 382
SNT TRC
FID C 11 1034
SNT TRC
FID C 11 289
SNT TRC
FID C 11 284
SNT TRC
FID C 11 281
SNT TRC
FID C 11 288
SNT TRC
FID C 11 287
SNT TRC
FID C 11 687
SNT TRC
FID C 11 690
SNT TRC
FID C 11 178
SNT TRC
FID C 11 157
SNT TRC
FID C 11 335
SNT TRC
FID C 11 334
SNT TRC
FID C 11 333
SNT TRC
FID C 11 657
SNT TRC
FID C 11 701
SNT TRC
FID C 11 541
SNT TRC
FID C 11 542
SNT TRC
FID C 11 1314
SNT TRC
FID C 11 1311
SNT TRC
FID C 11 969
SNT TRC
FID C 11 968
SNT TRC
FID C 11 965
SNT TRC
FID C 11 964
SNT TRC
FID C 11 191
SNT TRC
FID C 11 194
SNT TRC
FID C 11 537
SNT TRC
FID C 11 539
SNT TRC
FID C 11 759
SNT TRC
FID C 11 757
SNT TRC
FID C 11 730
SNT TRC
FID C 11 842
SNT TRC
FID C 11 807
SNT TRC
FID C 11 129
SNT TRC
FID C 11 119
SNT TRC
FID C 11 407
SNT TRC
FID C 11 406
SNT TRC
FID C 11 444
SNT TRC
FID C 11 443
SNT TRC
FID C 11 548
SNT TRC
FID C 11 554
SNT TRC
FID C 11 179
SNT TRC
FID C 11 156
SNT TRC
FID C 11 364
SNT TRC
FID C 11 368
SNT TRC
FID C 11 553
SNT TRC
FID C 11 552
SNT TRC
FID C 11 293
SNT TRC
FID C 11 299
SNT TRC
FID C 11 192
SNT TRC
FID C 11 193
SNT TRC
FID C 11 189
SNT TRC
FID C 11 190
SNT TRC
FID C 11 675
SNT TRC
FID C 11 676
SNT TRC
FID C 11 679
SNT TRC
FID C 11 680
SNT TRC
FID C 11 708
SNT TRC
FID C 11 709
SNT TRC
FID C 11 711
SNT TRC
FID C 11 761
SNT TRC
FID C 11 776
SNT TRC
FID C 11 1048
SNT TRC
FID C 11 1031
SNT TRC
FID C 11 1033
SNT TRC
FID C 11 1261
SNT TRC
FID C 11 1262
SNT TRC
FID C 11 929
SNT TRC
FID C 11 919
SNT TRC
FID C 11 182
SNT TRC
FID C 11 160
SNT TRC
FID C 11 499
SNT TRC
FID C 11 798
SNT TRC
FID C 11 181
SNT TRC
FID C 11 168
SNT TRC
FID C 11 749
SNT TRC
FID C 11 733
SNT TRC
FID C 11 172
SNT TRC
FID C 11 171
SNT TRC
FID C 11 164
SNT TRC
FID C 11 155
SNT TRC
FID C 11 800
SNT TRC
FID C 11 332
SNT TRC
FID C 11 331
SNT TRC
FID C 11 1017
SNT TRC
FID C 11 424
SNT TRC
FID C 11 422
SNT TRC
FID C 11 438
SNT TRC
FID C 11 1263
SNT TRC
FID C 11 1291
SNT TRC
FID C 11 1293
SNT TRC
FID C 11 936
SNT TRC
FID C 11 935
SNT TRC
FID C 11 933
SNT TRC
FID C 11 308
SNT TRC
FID C 11 307
SNT TRC
FID C 11 197
SNT TRC
FID C 11 201
SNT TRC
FID C 11 834
SNT TRC
FID C 11 810
SNT TRC
FID C 11 123
SNT TRC
FID C 11 118
SNT TRC
FID C 11 117
SNT TRC
FID C 11 536
SNT TRC
FID C 11 538
SNT TRC
FID C 11 306
SNT TRC
FID C 11 305
SNT TRC
FID C 11 472
SNT TRC
FID C 11 987
SNT TRC
FID C 11 988
SNT TRC
FID C 11 989
SNT TRC
FID C 11 991
SNT TRC
FID C 11 180
SNT TRC
FID C 11 154
SNT TRC
FID C 11 786
SNT TRC
FID C 11 788
SNT TRC
FID C 11 789
SNT TRC
FID C 11 1015
SNT TRC
FID C 11 1010
SNT TRC
FID C 11 1012
SNT TRC
FID C 11 1013
SNT TRC
FID C 11 1009
SNT TRC
FID C 11 1011
SNT TRC
FID C 11 367
SNT TRC
FID C 11 366
SNT TRC
FID C 11 271
SNT TRC
FID C 11 186
SNT TRC
FID C 11 187
SNT TRC
FID C 11 681
SNT TRC
FID C 11 713
SNT TRC
FID C 11 714
SNT TRC
FID C 11 729
SNT TRC
FID C 11 833
SNT TRC
FID C 11 811
SNT TRC
FID C 11 1022
SNT TRC
FID C 11 1023
SNT TRC
FID C 11 671
SNT TRC
FID C 11 651
SNT TRC
FID C 11 163
SNT TRC
FID C 11 158
SNT TRC
FID C 11 880
SNT TRC
FID C 11 878
SNT TRC
FID C 11 858
SNT TRC
FID C 11 437
SNT TRC
FID C 11 436
SNT TRC
FID C 11 381
SNT TRC
FID C 11 199
SNT TRC
FID C 11 200
SNT TRC
FID C 11 500
SNT TRC
FID C 11 784
SNT TRC
FID C 11 785
SNT TRC
FID C 11 795
SNT TRC
FID C 11 221
SNT TRC
FID C 11 685
SNT TRC
FID C 11 686
SNT TRC
FID C 11 703
SNT TRC
FID C 11 732
SNT TRC
FID C 11 744
SNT TRC
FID C 11 1266
SNT TRC
FID C 11 1267
SNT TRC
FID C 11 1269
SNT TRC
FID C 11 1307
SNT TRC
FID C 11 1312
SNT TRC
FID C 11 1296
SNT TRC
FID C 11 1315
SNT TRC
FID C 11 1245
SNT TRC
FID C 11 1244
SNT TRC
FID C 11 1174
SNT TRC
FID C 11 1224
SNT TRC
FID C 11 792
SNT TRC
FID C 11 793
SNT TRC
FID C 11 797
SNT TRC
FID C 11 903
SNT TRC
FID C 11 904
SNT TRC
FID C 11 890
SNT TRC
FID C 11 974
SNT TRC
FID C 11 923
SNT TRC
FID C 11 922
SNT TRC
FID C 11 950
SNT TRC
FID C 11 977
SNT TRC
FID C 11 901
SNT TRC
FID C 11 1379
SNT TRC
FID C 11 1382
SNT TRC
FID C 11 1317
SNT TRC
FID C 11 1316
SNT TRC
FID C 11 943
SNT TRC
FID C 11 1049
SNT TRC
FID C 11 1053
SNT TRC
FID C 11 1052
SNT TRC
FID C 11 220
SNT TRC
FID C 11 204
SNT TRC
FID C 11 203
SNT TRC
FID C 11 301
SNT TRC
FID C 11 300
SNT TRC
FID C 11 302
SNT TRC
FID C 11 398
SNT TRC
FID C 11 395
SNT TRC
FID C 11 397
SNT TRC
FID C 11 399
SNT TRC
FID C 11 445
SNT TRC
FID C 11 446
SNT TRC
FID C 11 310
SNT TRC
FID C 11 311
SNT TRC
FID C 11 640
SNT TRC
FID C 11 630
SNT TRC
FID C 11 629
SNT TRC
FID C 11 613
SNT TRC
FID C 11 612
SNT TRC
FID C 11 1078
SNT TRC
FID C 11 587
SNT TRC
FID C 11 592
SNT TRC
FID C 11 1076
SNT TRC
FID C 11 1077
SNT TRC
FID C 11 198
SNT TRC
FID C 11 202
SNT TRC
FID C 11 159
SNT TRC
FID C 11 183
SNT TRC
FID C 11 972
SNT TRC
FID C 11 982
SNT TRC
FID C 11 647
SNT TRC
FID C 11 646
SNT TRC
FID C 11 252
SNT TRC
FID C 11 251
SNT TRC
FID C 11 504
SNT TRC
FID C 11 456
SNT TRC
FID C 11 505
SNT TRC
FID C 11 530
SNT TRC
FID C 11 531
SNT TRC
FID C 11 303
SNT TRC
FID C 11 257
SNT TRC
FID C 11 433
SNT TRC
FID C 11 454
SNT TRC
FID C 11 455
SNT TRC
FID C 11 431
SNT TRC
FID C 11 318
SNT TRC
FID C 11 513
SNT TRC
FID C 11 514
SNT TRC
FID C 11 256
SNT TRC
FID C 11 319
SNT TRC
FID C 11 522
SNT TRC
FID C 11 320
SNT TRC
FID C 11 529
SNT VIA
FID C 4 93
FID C 5 93
FID C 7 311
FID C 8 496
FID C 10 1035
FID C 11 2405
FID H 12 232
SNT VIA
FID C 4 36
FID C 5 36
FID C 7 157
FID C 8 342
FID C 10 881
FID C 11 2251
FID H 12 78
SNT VIA
FID C 4 92
FID C 5 92
FID C 7 310
FID C 8 495
FID C 10 1034
FID C 11 2404
FID H 12 231
SNT VIA
FID C 4 37
FID C 5 37
FID C 7 158
FID C 8 343
FID C 10 882
FID C 11 2252
FID H 12 79
SNT VIA
FID C 4 115
FID C 5 115
FID C 7 387
FID C 8 572
FID C 10 1111
FID C 11 2481
FID H 12 308
SNT VIA
FID C 4 120
FID C 5 120
FID C 7 401
FID C 8 586
FID C 10 1125
FID C 11 2495
FID H 12 322
SNT VIA
FID C 4 86
FID C 5 86
FID C 7 293
FID C 8 478
FID C 10 1017
FID C 11 2387
FID H 12 214
SNT VIA
FID C 4 97
FID C 5 97
FID C 7 327
FID C 8 512
FID C 10 1051
FID C 11 2421
FID H 12 248
SNT VIA
FID C 4 100
FID C 5 100
FID C 7 336
FID C 8 521
FID C 10 1060
FID C 11 2430
FID H 12 257
SNT VIA
FID C 4 111
FID C 5 111
FID C 7 375
FID C 8 560
FID C 10 1099
FID C 11 2469
FID H 12 296
SNT VIA
FID C 4 82
FID C 5 82
FID C 7 279
FID C 8 464
FID C 10 1003
FID C 11 2373
FID H 12 200
SNT VIA
FID C 4 76
FID C 5 76
FID C 7 266
FID C 8 451
FID C 10 990
FID C 11 2360
FID H 12 187
SNT VIA
FID C 4 90
FID C 5 90
FID C 7 306
FID C 8 491
FID C 10 1030
FID C 11 2400
FID H 12 227
SNT VIA
FID C 4 81
FID C 5 81
FID C 7 278
FID C 8 463
FID C 10 1002
FID C 11 2372
FID H 12 199
SNT VIA
FID C 4 105
FID C 5 105
FID C 7 358
FID C 8 543
FID C 10 1082
FID C 11 2452
FID H 12 279
SNT VIA
FID C 4 110
FID C 5 110
FID C 7 371
FID C 8 556
FID C 10 1095
FID C 11 2465
FID H 12 292
SNT VIA
FID C 4 112
FID C 5 112
FID C 7 382
FID C 8 567
FID C 10 1106
FID C 11 2476
FID H 12 303
SNT VIA
FID C 4 94
FID C 5 94
FID C 7 312
FID C 8 497
FID C 10 1036
FID C 11 2406
FID H 12 233
SNT VIA
FID C 4 121
FID C 5 121
FID C 7 410
FID C 8 595
FID C 10 1134
FID C 11 2504
FID H 12 331
SNT VIA
FID C 4 39
FID C 5 39
FID C 7 160
FID C 8 345
FID C 10 884
FID C 11 2254
FID H 12 81
SNT VIA
FID C 4 44
FID C 5 44
FID C 7 165
FID C 8 350
FID C 10 889
FID C 11 2259
FID H 12 86
SNT VIA
FID C 4 43
FID C 5 43
FID C 7 164
FID C 8 349
FID C 10 888
FID C 11 2258
FID H 12 85
SNT VIA
FID C 4 42
FID C 5 42
FID C 7 163
FID C 8 348
FID C 10 887
FID C 11 2257
FID H 12 84
SNT VIA
FID C 4 38
FID C 5 38
FID C 7 159
FID C 8 344
FID C 10 883
FID C 11 2253
FID H 12 80
SNT VIA
FID C 4 41
FID C 5 41
FID C 7 162
FID C 8 347
FID C 10 886
FID C 11 2256
FID H 12 83
SNT VIA
FID C 4 45
FID C 5 45
FID C 7 166
FID C 8 351
FID C 10 890
FID C 11 2260
FID H 12 87
SNT VIA
FID C 4 40
FID C 5 40
FID C 7 161
FID C 8 346
FID C 10 885
FID C 11 2255
FID H 12 82
SNT VIA
FID C 4 49
FID C 5 49
FID C 7 178
FID C 8 363
FID C 10 902
FID C 11 2272
FID H 12 99
SNT VIA
FID C 4 47
FID C 5 47
FID C 7 176
FID C 8 361
FID C 10 900
FID C 11 2270
FID H 12 97
SNT VIA
FID C 4 123
FID C 5 123
FID C 7 421
FID C 8 606
FID C 10 1145
FID C 11 2515
FID H 12 342
SNT VIA
FID C 4 132
FID C 5 132
FID C 7 454
FID C 8 639
FID C 10 1178
FID C 11 2548
FID H 12 375
SNT VIA
FID C 4 107
FID C 5 107
FID C 7 360
FID C 8 545
FID C 10 1084
FID C 11 2454
FID H 12 281
SNT VIA
FID C 4 113
FID C 5 113
FID C 7 384
FID C 8 569
FID C 10 1108
FID C 11 2478
FID H 12 305
SNT VIA
FID C 4 168
FID C 5 168
FID C 7 531
FID C 8 716
FID C 10 1255
FID C 11 2625
FID H 12 452
SNT VIA
FID C 4 161
FID C 5 161
FID C 7 523
FID C 8 708
FID C 10 1247
FID C 11 2617
FID H 12 444
SNT VIA
FID C 4 156
FID C 5 156
FID C 7 514
FID C 8 699
FID C 10 1238
FID C 11 2608
FID H 12 435
SNT VIA
FID C 4 147
FID C 5 147
FID C 7 485
FID C 8 670
FID C 10 1209
FID C 11 2579
FID H 12 406
SNT VIA
FID C 4 167
FID C 5 167
FID C 7 530
FID C 8 715
FID C 10 1254
FID C 11 2624
FID H 12 451
SNT VIA
FID C 4 170
FID C 5 170
FID C 7 536
FID C 8 721
FID C 10 1260
FID C 11 2630
FID H 12 457
SNT VIA
FID C 4 177
FID C 5 177
FID C 7 556
FID C 8 741
FID C 10 1280
FID C 11 2650
FID H 12 477
SNT VIA
FID C 4 183
FID C 5 183
FID C 7 562
FID C 8 747
FID C 10 1286
FID C 11 2656
FID H 12 483
SNT VIA
FID C 4 181
FID C 5 181
FID C 7 560
FID C 8 745
FID C 10 1284
FID C 11 2654
FID H 12 481
SNT VIA
FID C 4 179
FID C 5 179
FID C 7 558
FID C 8 743
FID C 10 1282
FID C 11 2652
FID H 12 479
SNT VIA
FID C 4 180
FID C 5 180
FID C 7 559
FID C 8 744
FID C 10 1283
FID C 11 2653
FID H 12 480
SNT VIA
FID C 4 182
FID C 5 182
FID C 7 561
FID C 8 746
FID C 10 1285
FID C 11 2655
FID H 12 482
SNT VIA
FID C 4 176
FID C 5 176
FID C 7 547
FID C 8 732
FID C 10 1271
FID C 11 2641
FID H 12 468
SNT VIA
FID C 4 173
FID C 5 173
FID C 7 544
FID C 8 729
FID C 10 1268
FID C 11 2638
FID H 12 465
SNT VIA
FID C 4 174
FID C 5 174
FID C 7 545
FID C 8 730
FID C 10 1269
FID C 11 2639
FID H 12 466
SNT VIA
FID C 4 178
FID C 5 178
FID C 7 557
FID C 8 742
FID C 10 1281
FID C 11 2651
FID H 12 478
SNT VIA
FID C 4 191
FID C 5 191
FID C 7 577
FID C 8 762
FID C 10 1301
FID C 11 2671
FID H 12 498
SNT VIA
FID C 4 198
FID C 5 198
FID C 7 585
FID C 8 770
FID C 10 1309
FID C 11 2679
FID H 12 506
SNT VIA
FID C 4 197
FID C 5 197
FID C 7 583
FID C 8 768
FID C 10 1307
FID C 11 2677
FID H 12 504
SNT VIA
FID C 4 196
FID C 5 196
FID C 7 582
FID C 8 767
FID C 10 1306
FID C 11 2676
FID H 12 503
SNT VIA
FID C 4 187
FID C 5 187
FID C 7 573
FID C 8 758
FID C 10 1297
FID C 11 2667
FID H 12 494
SNT VIA
FID C 4 190
FID C 5 190
FID C 7 576
FID C 8 761
FID C 10 1300
FID C 11 2670
FID H 12 497
SNT VIA
FID C 4 189
FID C 5 189
FID C 7 575
FID C 8 760
FID C 10 1299
FID C 11 2669
FID H 12 496
SNT VIA
FID C 4 188
FID C 5 188
FID C 7 574
FID C 8 759
FID C 10 1298
FID C 11 2668
FID H 12 495
SNT VIA
FID C 4 186
FID C 5 186
FID C 7 572
FID C 8 757
FID C 10 1296
FID C 11 2666
FID H 12 493
SNT VIA
FID C 4 139
FID C 5 139
FID C 7 468
FID C 8 653
FID C 10 1192
FID C 11 2562
FID H 12 389
SNT VIA
FID C 4 171
FID C 5 171
FID C 7 541
FID C 8 726
FID C 10 1265
FID C 11 2635
FID H 12 462
SNT VIA
FID C 4 172
FID C 5 172
FID C 7 542
FID C 8 727
FID C 10 1266
FID C 11 2636
FID H 12 463
SNT VIA
FID C 4 141
FID C 5 141
FID C 7 475
FID C 8 660
FID C 10 1199
FID C 11 2569
FID H 12 396
SNT VIA
FID C 4 146
FID C 5 146
FID C 7 483
FID C 8 668
FID C 10 1207
FID C 11 2577
FID H 12 404
SNT VIA
FID C 4 149
FID C 5 149
FID C 7 496
FID C 8 681
FID C 10 1220
FID C 11 2590
FID H 12 417
SNT VIA
FID C 4 74
FID C 5 74
FID C 7 263
FID C 8 448
FID C 10 987
FID C 11 2357
FID H 12 184
SNT VIA
FID C 4 67
FID C 5 67
FID C 7 210
FID C 8 395
FID C 10 934
FID C 11 2304
FID H 12 131
SNT VIA
FID C 4 91
FID C 5 91
FID C 7 307
FID C 8 492
FID C 10 1031
FID C 11 2401
FID H 12 228
SNT VIA
FID C 4 73
FID C 5 73
FID C 7 259
FID C 8 444
FID C 10 983
FID C 11 2353
FID H 12 180
SNT VIA
FID C 4 52
FID C 5 52
FID C 7 194
FID C 8 379
FID C 10 918
FID C 11 2288
FID H 12 115
SNT VIA
FID C 4 83
FID C 5 83
FID C 7 283
FID C 8 468
FID C 10 1007
FID C 11 2377
FID H 12 204
SNT VIA
FID C 3 657
FID C 4 126
FID C 5 126
FID C 7 432
FID C 8 617
FID C 10 1156
FID C 11 2526
FID H 12 353
SNT VIA
FID C 4 117
FID C 5 117
FID C 7 389
FID C 8 574
FID C 10 1113
FID C 11 2483
FID H 12 310
SNT VIA
FID C 4 195
FID C 5 195
FID C 7 581
FID C 8 766
FID C 10 1305
FID C 11 2675
FID H 12 502
SNT VIA
FID C 4 157
FID C 5 157
FID C 7 515
FID C 8 700
FID C 10 1239
FID C 11 2609
FID H 12 436
SNT VIA
FID C 4 61
FID C 5 61
FID C 7 203
FID C 8 388
FID C 10 927
FID C 11 2297
FID H 12 124
SNT VIA
FID C 4 116
FID C 5 116
FID C 7 388
FID C 8 573
FID C 10 1112
FID C 11 2482
FID H 12 309
SNT VIA
FID C 4 133
FID C 5 133
FID C 7 457
FID C 8 642
FID C 10 1181
FID C 11 2551
FID H 12 378
SNT VIA
FID C 4 142
FID C 5 142
FID C 7 476
FID C 8 661
FID C 10 1200
FID C 11 2570
FID H 12 397
SNT VIA
FID C 4 50
FID C 5 50
FID C 7 179
FID C 8 364
FID C 10 903
FID C 11 2273
FID H 12 100
SNT VIA
FID C 4 98
FID C 5 98
FID C 7 328
FID C 8 513
FID C 10 1052
FID C 11 2422
FID H 12 249
SNT VIA
FID C 4 103
FID C 5 103
FID C 7 348
FID C 8 533
FID C 10 1072
FID C 11 2442
FID H 12 269
SNT VIA
FID C 4 135
FID C 5 135
FID C 7 461
FID C 8 646
FID C 10 1185
FID C 11 2555
FID H 12 382
SNT VIA
FID C 4 118
FID C 5 118
FID C 7 393
FID C 8 578
FID C 10 1117
FID C 11 2487
FID H 12 314
SNT VIA
FID C 4 51
FID C 5 51
FID C 7 193
FID C 8 378
FID C 10 917
FID C 11 2287
FID H 12 114
SNT VIA
FID C 4 88
FID C 5 88
FID C 7 299
FID C 8 484
FID C 10 1023
FID C 11 2393
FID H 12 220
SNT VIA
FID C 4 119
FID C 5 119
FID C 7 397
FID C 8 582
FID C 10 1121
FID C 11 2491
FID H 12 318
SNT VIA
FID C 4 72
FID C 5 72
FID C 7 256
FID C 8 441
FID C 10 980
FID C 11 2350
FID H 12 177
SNT VIA
FID C 4 62
FID C 5 62
FID C 7 204
FID C 8 389
FID C 10 928
FID C 11 2298
FID H 12 125
SNT VIA
FID C 4 60
FID C 5 60
FID C 7 202
FID C 8 387
FID C 10 926
FID C 11 2296
FID H 12 123
SNT VIA
FID C 4 128
FID C 5 128
FID C 7 440
FID C 8 625
FID C 10 1164
FID C 11 2534
FID H 12 361
SNT VIA
FID C 4 134
FID C 5 134
FID C 7 459
FID C 8 644
FID C 10 1183
FID C 11 2553
FID H 12 380
SNT VIA
FID C 4 165
FID C 5 165
FID C 7 528
FID C 8 713
FID C 10 1252
FID C 11 2622
FID H 12 449
SNT VIA
FID C 4 185
FID C 5 185
FID C 7 569
FID C 8 754
FID C 10 1293
FID C 11 2663
FID H 12 490
SNT VIA
FID C 4 153
FID C 5 153
FID C 7 508
FID C 8 693
FID C 10 1232
FID C 11 2602
FID H 12 429
SNT VIA
FID C 4 56
FID C 5 56
FID C 7 198
FID C 8 383
FID C 10 922
FID C 11 2292
FID H 12 119
SNT VIA
FID C 4 108
FID C 5 108
FID C 7 369
FID C 8 554
FID C 10 1093
FID C 11 2463
FID H 12 290
SNT VIA
FID C 4 140
FID C 5 140
FID C 7 471
FID C 8 656
FID C 10 1195
FID C 11 2565
FID H 12 392
SNT VIA
FID C 4 58
FID C 5 58
FID C 7 200
FID C 8 385
FID C 10 924
FID C 11 2294
FID H 12 121
SNT VIA
FID C 4 184
FID C 5 184
FID C 7 568
FID C 8 753
FID C 10 1292
FID C 11 2662
FID H 12 489
SNT VIA
FID C 4 136
FID C 5 136
FID C 7 462
FID C 8 647
FID C 10 1186
FID C 11 2556
FID H 12 383
SNT VIA
FID C 4 54
FID C 5 54
FID C 7 196
FID C 8 381
FID C 10 920
FID C 11 2290
FID H 12 117
SNT VIA
FID C 4 145
FID C 5 145
FID C 7 481
FID C 8 666
FID C 10 1205
FID C 11 2575
FID H 12 402
SNT VIA
FID C 4 80
FID C 5 80
FID C 7 277
FID C 8 462
FID C 10 1001
FID C 11 2371
FID H 12 198
SNT VIA
FID C 4 163
FID C 5 163
FID C 7 525
FID C 8 710
FID C 10 1249
FID C 11 2619
FID H 12 446
SNT VIA
FID C 4 102
FID C 5 102
FID C 7 345
FID C 8 530
FID C 10 1069
FID C 11 2439
FID H 12 266
SNT VIA
FID C 4 155
FID C 5 155
FID C 7 513
FID C 8 698
FID C 10 1237
FID C 11 2607
FID H 12 434
SNT VIA
FID C 4 63
FID C 5 63
FID C 7 206
FID C 8 391
FID C 10 930
FID C 11 2300
FID H 12 127
SNT VIA
FID C 4 130
FID C 5 130
FID C 7 443
FID C 8 628
FID C 10 1167
FID C 11 2537
FID H 12 364
SNT VIA
FID C 4 143
FID C 5 143
FID C 7 478
FID C 8 663
FID C 10 1202
FID C 11 2572
FID H 12 399
SNT VIA
FID C 4 48
FID C 5 48
FID C 7 177
FID C 8 362
FID C 10 901
FID C 11 2271
FID H 12 98
SNT VIA
FID C 4 114
FID C 5 114
FID C 7 386
FID C 8 571
FID C 10 1110
FID C 11 2480
FID H 12 307
SNT VIA
FID C 4 77
FID C 5 77
FID C 7 267
FID C 8 452
FID C 10 991
FID C 11 2361
FID H 12 188
SNT VIA
FID C 4 106
FID C 5 106
FID C 7 359
FID C 8 544
FID C 10 1083
FID C 11 2453
FID H 12 280
SNT VIA
FID C 4 160
FID C 5 160
FID C 7 521
FID C 8 706
FID C 10 1245
FID C 11 2615
FID H 12 442
SNT VIA
FID C 4 192
FID C 5 192
FID C 7 578
FID C 8 763
FID C 10 1302
FID C 11 2672
FID H 12 499
SNT VIA
FID C 4 53
FID C 5 53
FID C 7 195
FID C 8 380
FID C 10 919
FID C 11 2289
FID H 12 116
SNT VIA
FID C 4 138
FID C 5 138
FID C 7 467
FID C 8 652
FID C 10 1191
FID C 11 2561
FID H 12 388
SNT VIA
FID C 4 162
FID C 5 162
FID C 7 524
FID C 8 709
FID C 10 1248
FID C 11 2618
FID H 12 445
SNT VIA
FID C 4 89
FID C 5 89
FID C 7 301
FID C 8 486
FID C 10 1025
FID C 11 2395
FID H 12 222
SNT VIA
FID C 4 71
FID C 5 71
FID C 7 246
FID C 8 431
FID C 10 970
FID C 11 2340
FID H 12 167
SNT VIA
FID C 4 59
FID C 5 59
FID C 7 201
FID C 8 386
FID C 10 925
FID C 11 2295
FID H 12 122
SNT VIA
FID C 4 129
FID C 5 129
FID C 7 442
FID C 8 627
FID C 10 1166
FID C 11 2536
FID H 12 363
SNT VIA
FID C 4 144
FID C 5 144
FID C 7 479
FID C 8 664
FID C 10 1203
FID C 11 2573
FID H 12 400
SNT VIA
FID C 4 164
FID C 5 164
FID C 7 527
FID C 8 712
FID C 10 1251
FID C 11 2621
FID H 12 448
SNT VIA
FID C 4 127
FID C 5 127
FID C 7 438
FID C 8 623
FID C 10 1162
FID C 11 2532
FID H 12 359
SNT VIA
FID C 4 55
FID C 5 55
FID C 7 197
FID C 8 382
FID C 10 921
FID C 11 2291
FID H 12 118
SNT VIA
FID C 4 148
FID C 5 148
FID C 7 492
FID C 8 677
FID C 10 1216
FID C 11 2586
FID H 12 413
SNT VIA
FID C 4 101
FID C 5 101
FID C 7 342
FID C 8 527
FID C 10 1066
FID C 11 2436
FID H 12 263
SNT VIA
FID C 4 65
FID C 5 65
FID C 7 208
FID C 8 393
FID C 10 932
FID C 11 2302
FID H 12 129
SNT VIA
FID C 4 109
FID C 5 109
FID C 7 370
FID C 8 555
FID C 10 1094
FID C 11 2464
FID H 12 291
SNT VIA
FID C 4 137
FID C 5 137
FID C 7 466
FID C 8 651
FID C 10 1190
FID C 11 2560
FID H 12 387
SNT VIA
FID C 4 131
FID C 5 131
FID C 7 444
FID C 8 629
FID C 10 1168
FID C 11 2538
FID H 12 365
SNT VIA
FID C 4 166
FID C 5 166
FID C 7 529
FID C 8 714
FID C 10 1253
FID C 11 2623
FID H 12 450
SNT VIA
FID C 4 194
FID C 5 194
FID C 7 580
FID C 8 765
FID C 10 1304
FID C 11 2674
FID H 12 501
SNT VIA
FID C 4 175
FID C 5 175
FID C 7 546
FID C 8 731
FID C 10 1270
FID C 11 2640
FID H 12 467
SNT VIA
FID C 4 150
FID C 5 150
FID C 7 501
FID C 8 686
FID C 10 1225
FID C 11 2595
FID H 12 422
SNT VIA
FID C 4 152
FID C 5 152
FID C 7 505
FID C 8 690
FID C 10 1229
FID C 11 2599
FID H 12 426
SNT VIA
FID C 4 159
FID C 5 159
FID C 7 517
FID C 8 702
FID C 10 1241
FID C 11 2611
FID H 12 438
SNT VIA
FID C 4 151
FID C 5 151
FID C 7 502
FID C 8 687
FID C 10 1226
FID C 11 2596
FID H 12 423
SNT VIA
FID C 4 199
FID C 5 199
FID C 7 586
FID C 8 771
FID C 10 1310
FID C 11 2680
FID H 12 507
SNT VIA
FID C 4 193
FID C 5 193
FID C 7 579
FID C 8 764
FID C 10 1303
FID C 11 2673
FID H 12 500
SNT VIA
FID C 4 154
FID C 5 154
FID C 7 512
FID C 8 697
FID C 10 1236
FID C 11 2606
FID H 12 433
SNT VIA
FID C 4 169
FID C 5 169
FID C 7 532
FID C 8 717
FID C 10 1256
FID C 11 2626
FID H 12 453
SNT VIA
FID C 4 68
FID C 5 68
FID C 7 214
FID C 8 399
FID C 10 938
FID C 11 2308
FID H 12 135
SNT VIA
FID C 4 66
FID C 5 66
FID C 7 209
FID C 8 394
FID C 10 933
FID C 11 2303
FID H 12 130
SNT VIA
FID C 4 46
FID C 5 46
FID C 7 167
FID C 8 352
FID C 10 891
FID C 11 2261
FID H 12 88
SNT VIA
FID C 4 87
FID C 5 87
FID C 7 297
FID C 8 482
FID C 10 1021
FID C 11 2391
FID H 12 218
SNT VIA
FID C 4 78
FID C 5 78
FID C 7 268
FID C 8 453
FID C 10 992
FID C 11 2362
FID H 12 189
SNT VIA
FID C 4 95
FID C 5 95
FID C 7 320
FID C 8 505
FID C 10 1044
FID C 11 2414
FID H 12 241
SNT VIA
FID C 4 96
FID C 5 96
FID C 7 321
FID C 8 506
FID C 10 1045
FID C 11 2415
FID H 12 242
SNT VIA
FID C 4 104
FID C 5 104
FID C 7 349
FID C 8 534
FID C 10 1073
FID C 11 2443
FID H 12 270
SNT VIA
FID C 4 99
FID C 5 99
FID C 7 334
FID C 8 519
FID C 10 1058
FID C 11 2428
FID H 12 255
SNT VIA
FID C 4 79
FID C 5 79
FID C 7 269
FID C 8 454
FID C 10 993
FID C 11 2363
FID H 12 190
SNT VIA
FID C 4 84
FID C 5 84
FID C 7 285
FID C 8 470
FID C 10 1009
FID C 11 2379
FID H 12 206
SNT VIA
FID C 4 85
FID C 5 85
FID C 7 288
FID C 8 473
FID C 10 1012
FID C 11 2382
FID H 12 209
SNT VIA
FID C 3 654
FID C 4 124
FID C 5 124
FID C 7 423
FID C 8 608
FID C 10 1147
FID C 11 2517
FID H 12 344
SNT VIA
FID C 3 647
FID C 4 122
FID C 5 122
FID C 7 411
FID C 8 596
FID C 10 1135
FID C 11 2505
FID H 12 332
SNT VIA
FID C 4 64
FID C 5 64
FID C 7 207
FID C 8 392
FID C 10 931
FID C 11 2301
FID H 12 128
SNT VIA
FID C 4 57
FID C 5 57
FID C 7 199
FID C 8 384
FID C 10 923
FID C 11 2293
FID H 12 120
SNT VIA
FID C 4 158
FID C 5 158
FID C 7 516
FID C 8 701
FID C 10 1240
FID C 11 2610
FID H 12 437
SNT VIA
FID C 4 125
FID C 5 125
FID C 7 427
FID C 8 612
FID C 10 1151
FID C 11 2521
FID H 12 348
SNT VIA
FID C 4 75
FID C 5 75
FID C 7 265
FID C 8 450
FID C 10 989
FID C 11 2359
FID H 12 186
SNT VIA
FID C 4 69
FID C 5 69
FID C 7 231
FID C 8 416
FID C 10 955
FID C 11 2325
FID H 12 152
SNT VIA
FID C 4 70
FID C 5 70
FID C 7 236
FID C 8 421
FID C 10 960
FID C 11 2330
FID H 12 157
#NET 136
NET FPGA_TMS
SNT TOP T 65 0
FID C 9 426
FID C 10 469
FID C 11 1837
SNT TOP T 97 2
FID C 9 436
FID C 10 479
FID C 11 1847
SNT TOP T 77 243
FID C 9 96
FID C 10 122
FID C 11 1495
SNT TRC
FID C 2 124
SNT TRC
FID C 2 127
SNT TRC
FID C 2 125
SNT TRC
FID C 3 129
SNT TRC
FID C 3 295
SNT TRC
FID C 3 172
SNT TRC
FID C 3 131
SNT TRC
FID C 3 280
SNT TRC
FID C 3 174
SNT TRC
FID C 11 620
SNT TRC
FID C 11 596
SNT TRC
FID C 11 619
SNT TRC
FID C 11 621
SNT TRC
FID C 11 622
SNT TRC
FID C 11 162
SNT TRC
FID C 11 161
SNT VIA
FID C 2 494
FID C 3 568
FID C 7 191
FID C 8 376
FID C 10 915
FID C 11 2285
FID H 12 112
SNT VIA
FID C 3 651
FID C 7 418
FID C 8 603
FID C 10 1142
FID C 11 2512
FID H 12 339
SNT VIA
FID C 2 495
FID C 7 192
FID C 8 377
FID C 10 916
FID C 11 2286
FID H 12 113
#NET 137
NET +3.3V
SNT TOP B 0 3
FID C 1 22
FID C 7 57
FID C 8 246
SNT TOP B 2 0
FID C 1 29
FID C 7 64
FID C 8 253
SNT TOP B 1 0
FID C 1 21
FID C 7 56
FID C 8 245
SNT TOP T 36 1
FID C 9 687
FID C 10 759
FID C 11 2125
SNT TOP T 52 1
FID C 9 671
FID C 10 733
FID C 11 2099
SNT TOP T 53 1
FID C 9 663
FID C 10 720
FID C 11 2086
SNT TOP T 63 1
FID C 9 173
FID C 10 206
FID C 11 1579
SNT TOP T 84 0
FID C 9 656
FID C 10 713
FID C 11 2079
SNT TOP T 91 1
FID C 9 44
FID C 10 66
FID C 11 1440
SNT TOP T 92 1
FID C 9 28
FID C 10 50
FID C 11 1424
SNT TOP T 93 1
FID C 9 16
FID C 10 38
FID C 11 1412
SNT TOP T 94 1
FID C 9 517
FID C 10 563
FID C 11 1931
SNT TOP T 95 1
FID C 9 518
FID C 10 564
FID C 11 1932
SNT TOP T 97 1
FID C 9 433
FID C 10 476
FID C 11 1844
SNT TOP T 98 1
FID C 9 319
FID C 10 359
FID C 11 1727
SNT TOP T 99 1
FID C 9 359
FID C 10 399
FID C 11 1767
SNT TOP T 111 0
FID C 9 170
FID C 10 203
FID C 11 1576
SNT TOP T 112 0
FID C 9 181
FID C 10 216
FID C 11 1589
SNT TOP T 113 0
FID C 9 756
FID C 10 831
FID C 11 2197
SNT TOP T 114 0
FID C 9 742
FID C 10 814
FID C 11 2180
SNT TOP T 127 0
FID C 9 704
FID C 10 776
FID C 11 2142
SNT TOP T 128 0
FID C 9 703
FID C 10 775
FID C 11 2141
SNT TOP T 129 0
FID C 9 702
FID C 10 774
FID C 11 2140
SNT TOP T 130 0
FID C 9 705
FID C 10 777
FID C 11 2143
SNT TOP T 131 0
FID C 9 719
FID C 10 791
FID C 11 2157
SNT TOP T 132 0
FID C 9 697
FID C 10 769
FID C 11 2135
SNT TOP T 90 1
FID C 9 52
FID C 10 74
FID C 11 1448
SNT TOP T 78 0
FID C 9 778
FID C 10 853
FID C 11 2219
SNT TOP T 42 27
FID C 9 744
FID C 10 816
FID C 11 2182
SNT TOP T 42 2
FID C 9 737
FID C 10 809
FID C 11 2175
SNT TOP T 44 5
FID C 9 429
FID C 10 472
FID C 11 1840
SNT TOP T 44 3
FID C 9 413
FID C 10 456
FID C 11 1824
SNT TOP T 96 1
FID C 9 455
FID C 10 499
FID C 11 1867
SNT TOP T 41 3
FID C 9 222
FID C 10 257
FID C 11 1630
SNT TOP T 100 1
FID C 9 648
FID C 10 705
FID C 11 2071
SNT TRC
FID C 8 52
SNT TRC
FID C 8 120
SNT TRC
FID C 3 107
SNT TRC
FID C 3 111
SNT TRC
FID C 3 120
SNT TRC
FID C 3 177
SNT TRC
FID C 3 157
SNT TRC
FID C 3 176
SNT TRC
FID C 3 130
SNT TRC
FID C 3 123
SNT TRC
FID C 3 156
SNT TRC
FID C 8 192
SNT TRC
FID C 8 190
SNT TRC
FID C 8 171
SNT TRC
FID C 8 132
SNT TRC
FID C 8 153
SNT TRC
FID C 8 152
SNT TRC
FID C 8 121
SNT TRC
FID C 8 122
SNT TRC
FID C 8 167
SNT TRC
FID C 8 168
SNT TRC
FID C 8 188
SNT TRC
FID C 8 189
SNT TRC
FID C 8 191
SNT TRC
FID C 11 1252
SNT TRC
FID C 11 1254
SNT TRC
FID C 11 1255
SNT TRC
FID C 11 1277
SNT TRC
FID C 11 1278
SNT TRC
FID C 11 1282
SNT TRC
FID C 11 1259
SNT TRC
FID C 11 1257
SNT TRC
FID C 11 1256
SNT TRC
FID C 11 1253
SNT TRC
FID C 11 1195
SNT TRC
FID C 11 1196
SNT TRC
FID C 11 1197
SNT TRC
FID C 11 578
SNT TRC
FID C 11 512
SNT TRC
FID C 11 497
SNT TRC
FID C 11 467
SNT TRC
FID C 11 453
SNT TRC
FID C 11 452
SNT TRC
FID C 11 599
SNT TRC
FID C 11 598
SNT TRC
FID C 11 603
SNT TRC
FID C 11 602
SNT TRC
FID C 11 64
SNT TRC
FID C 11 81
SNT TRC
FID C 11 114
SNT TRC
FID C 11 270
SNT TRC
FID C 11 1184
SNT TRC
FID C 11 1066
SNT TRC
FID C 11 1064
SNT TRC
FID C 11 1062
SNT TRC
FID C 11 1061
SNT TRC
FID C 11 1098
SNT TRC
FID C 11 1099
SNT TRC
FID C 11 1045
SNT TRC
FID C 11 130
SNT TRC
FID C 11 128
SNT TRC
FID C 11 279
SNT TRC
FID C 11 269
SNT TRC
FID C 11 312
SNT TRC
FID C 11 282
SNT TRC
FID C 11 280
SNT TRC
FID C 11 267
SNT TRC
FID C 11 268
SNT TRC
FID C 11 1069
SNT TRC
FID C 11 1093
SNT TRC
FID C 11 1094
SNT TRC
FID C 11 1095
SNT TRC
FID C 11 1100
SNT TRC
FID C 11 1101
SNT TRC
FID C 11 1270
SNT TRC
FID C 11 1273
SNT TRC
FID C 11 1320
SNT TRC
FID C 11 1334
SNT TRC
FID C 11 1275
SNT TRC
FID C 11 1276
SNT TRC
FID C 11 1290
SNT TRC
FID C 11 1141
SNT TRC
FID C 11 1156
SNT TRC
FID C 11 1161
SNT TRC
FID C 11 1172
SNT TRC
FID C 11 1177
SNT TRC
FID C 11 1171
SNT TRC
FID C 11 1173
SNT TRC
FID C 11 1326
SNT TRC
FID C 11 1223
SNT TRC
FID C 11 1250
SNT TRC
FID C 11 1271
SNT TRC
FID C 11 1097
SNT TRC
FID C 11 276
SNT TRC
FID C 11 1068
SNT TRC
FID C 11 1060
SNT TRC
FID C 11 1030
SNT TRC
FID C 11 813
SNT TRC
FID C 11 961
SNT TRC
FID C 11 937
SNT TRC
FID C 11 1027
SNT TRC
FID C 11 1028
SNT TRC
FID C 11 1029
SNT TRC
FID C 11 753
SNT TRC
FID C 11 614
SNT TRC
FID C 11 752
SNT TRC
FID C 11 751
SNT TRC
FID C 11 754
SNT TRC
FID C 11 782
SNT TRC
FID C 11 769
SNT TRC
FID C 11 755
SNT TRC
FID C 11 781
SNT TRC
FID C 11 706
SNT TRC
FID C 11 705
SNT TRC
FID C 11 717
SNT VIA
FID C 7 549
FID C 8 734
FID C 10 1273
FID C 11 2643
FID H 12 470
SNT VIA
FID C 7 538
FID C 8 723
FID C 10 1262
FID C 11 2632
FID H 12 459
SNT VIA
FID C 3 560
FID C 7 180
FID C 8 365
FID C 10 904
FID C 11 2274
FID H 12 101
SNT VIA
FID C 7 245
FID C 8 430
FID C 10 969
FID C 11 2339
FID H 12 166
SNT VIA
FID C 7 357
FID C 8 542
FID C 10 1081
FID C 11 2451
FID H 12 278
SNT VIA
FID C 7 415
FID C 8 600
FID C 10 1139
FID C 11 2509
FID H 12 336
SNT VIA
FID C 7 455
FID C 8 640
FID C 10 1179
FID C 11 2549
FID H 12 376
SNT VIA
FID C 3 609
FID C 7 314
FID C 8 499
FID C 10 1038
FID C 11 2408
FID H 12 235
SNT VIA
FID C 7 533
FID C 8 718
FID C 10 1257
FID C 11 2627
FID H 12 454
SNT VIA
FID C 7 248
FID C 8 433
FID C 10 972
FID C 11 2342
FID H 12 169
#NET 138
NET UART1_RXD
SNT TOP T 43 0
FID C 9 583
FID C 10 631
FID C 11 1997
SNT TOP T 60 0
FID C 9 571
FID C 10 619
FID C 11 1985
SNT TOP T 77 160
FID C 9 398
FID C 10 438
FID C 11 1806
SNT TRC
FID C 2 375
SNT TRC
FID C 2 381
SNT TRC
FID C 2 380
SNT TRC
FID C 2 382
SNT TRC
FID C 2 378
SNT TRC
FID C 2 379
SNT TRC
FID C 2 383
SNT TRC
FID C 2 377
SNT TRC
FID C 3 383
SNT TRC
FID C 3 384
SNT TRC
FID C 3 385
SNT TRC
FID C 11 856
SNT TRC
FID C 11 831
SNT TRC
FID C 11 828
SNT TRC
FID C 11 823
SNT TRC
FID C 11 827
SNT TRC
FID C 11 567
SNT TRC
FID C 11 568
SNT VIA
FID C 3 676
FID C 7 474
FID C 8 659
FID C 10 1198
FID C 11 2568
FID H 12 395
SNT VIA
FID C 2 584
FID C 3 645
FID C 7 406
FID C 8 591
FID C 10 1130
FID C 11 2500
FID H 12 327
SNT VIA
FID C 2 582
FID C 7 404
FID C 8 589
FID C 10 1128
FID C 11 2498
FID H 12 325
#NET 139
NET UART1_TXD
SNT TOP T 43 3
FID C 9 580
FID C 10 628
FID C 11 1994
SNT TOP T 59 0
FID C 9 570
FID C 10 618
FID C 11 1984
SNT TOP T 77 154
FID C 9 381
FID C 10 421
FID C 11 1789
SNT TRC
FID C 2 368
SNT TRC
FID C 2 363
SNT TRC
FID C 2 357
SNT TRC
FID C 2 369
SNT TRC
FID C 2 370
SNT TRC
FID C 2 371
SNT TRC
FID C 2 376
SNT TRC
FID C 3 381
SNT TRC
FID C 11 855
SNT TRC
FID C 11 830
SNT TRC
FID C 11 826
SNT TRC
FID C 11 822
SNT TRC
FID C 11 825
SNT TRC
FID C 11 550
SNT TRC
FID C 11 559
SNT TRC
FID C 11 549
SNT VIA
FID C 3 675
FID C 7 473
FID C 8 658
FID C 10 1197
FID C 11 2567
FID H 12 394
SNT VIA
FID C 2 583
FID C 3 644
FID C 7 405
FID C 8 590
FID C 10 1129
FID C 11 2499
FID H 12 326
SNT VIA
FID C 2 580
FID C 7 399
FID C 8 584
FID C 10 1123
FID C 11 2493
FID H 12 320
#NET 140
NET FPGA_TDO
SNT TOP T 66 0
FID C 9 410
FID C 10 453
FID C 11 1821
SNT TOP T 98 2
FID C 9 325
FID C 10 365
FID C 11 1733
SNT TOP T 77 242
FID C 9 148
FID C 10 178
FID C 11 1549
SNT TRC
FID C 2 134
SNT TRC
FID C 3 310
SNT TRC
FID C 3 138
SNT TRC
FID C 3 137
SNT TRC
FID C 11 576
SNT TRC
FID C 11 575
SNT TRC
FID C 11 441
SNT TRC
FID C 11 442
SNT TRC
FID C 11 206
SNT TRC
FID C 11 208
SNT TRC
FID C 11 207
SNT TRC
FID C 11 503
SNT TRC
FID C 11 466
SNT TRC
FID C 11 494
SNT VIA
FID C 3 624
FID C 7 346
FID C 8 531
FID C 10 1070
FID C 11 2440
FID H 12 267
SNT VIA
FID C 2 498
FID C 3 569
FID C 7 212
FID C 8 397
FID C 10 936
FID C 11 2306
FID H 12 133
SNT VIA
FID C 2 497
FID C 7 211
FID C 8 396
FID C 10 935
FID C 11 2305
FID H 12 132
#NET 141
NET FPGA_TCK
SNT TOP T 67 0
FID C 9 394
FID C 10 434
FID C 11 1802
SNT TOP T 99 2
FID C 9 365
FID C 10 405
FID C 11 1773
SNT TOP T 77 240
FID C 9 147
FID C 10 177
FID C 11 1548
SNT TRC
FID C 2 139
SNT TRC
FID C 3 150
SNT TRC
FID C 3 171
SNT TRC
FID C 3 236
SNT TRC
FID C 3 186
SNT TRC
FID C 3 182
SNT TRC
FID C 3 175
SNT TRC
FID C 3 242
SNT TRC
FID C 11 521
SNT TRC
FID C 11 523
SNT TRC
FID C 11 219
SNT TRC
FID C 11 245
SNT TRC
FID C 11 506
SNT TRC
FID C 11 519
SNT TRC
FID C 11 520
SNT VIA
FID C 2 505
FID C 3 575
FID C 7 227
FID C 8 412
FID C 10 951
FID C 11 2321
FID H 12 148
SNT VIA
FID C 2 504
FID C 7 226
FID C 8 411
FID C 10 950
FID C 11 2320
FID H 12 147
SNT VIA
FID C 3 633
FID C 7 374
FID C 8 559
FID C 10 1098
FID C 11 2468
FID H 12 295
#NET 142
NET +12V
SNT TOP T 46 1
FID C 9 765
FID C 10 840
FID C 11 2206
SNT TOP T 73 1
FID C 9 695
FID C 10 767
FID C 11 2133
SNT TOP T 74 1
FID C 9 785
FID C 10 862
FID C 11 2228
SNT TOP T 133 0
FID C 9 771
FID C 10 846
FID C 11 2212
SNT TOP T 134 0
FID C 9 707
FID C 10 779
FID C 11 2145
SNT TOP T 137 0
FID C 9 673
FID C 10 740
FID C 11 2106
SNT TOP T 138 0
FID C 9 676
FID C 10 745
FID C 11 2111
SNT TOP T 45 1
FID C 9 711
FID C 10 783
FID C 11 2149
SNT TOP T 85 1
FID C 9 681
FID C 10 751
FID C 11 2117
SNT TRC
FID C 8 195
SNT TRC
FID C 8 193
SNT TRC
FID C 8 196
SNT TRC
FID C 8 197
SNT TRC
FID C 8 198
SNT TRC
FID C 11 1240
SNT TRC
FID C 11 1241
SNT TRC
FID C 11 1123
SNT TRC
FID C 11 1124
SNT TRC
FID C 11 1187
SNT TRC
FID C 11 1182
SNT TRC
FID C 11 1180
SNT TRC
FID C 11 1181
SNT TRC
FID C 11 1167
SNT TRC
FID C 11 1169
SNT TRC
FID C 11 1176
SNT TRC
FID C 11 1179
SNT TRC
FID C 11 1288
SNT TRC
FID C 11 1297
SNT TRC
FID C 11 1357
SNT TRC
FID C 11 1343
SNT TRC
FID C 11 1353
SNT TRC
FID C 11 1348
SNT TRC
FID C 11 1323
SNT TRC
FID C 11 1324
SNT TRC
FID C 11 1340
SNT TRC
FID C 11 1345
SNT TRC
FID C 11 1346
SNT TRC
FID C 11 1319
SNT TRC
FID C 11 1336
SNT TRC
FID C 11 1344
SNT TRC
FID C 11 1119
SNT TRC
FID C 11 1122
SNT TRC
FID C 11 1185
SNT TRC
FID C 11 1354
SNT TRC
FID C 11 1105
SNT TRC
FID C 11 1107
SNT TRC
FID C 11 1106
SNT TRC
FID C 11 1116
SNT TRC
FID C 11 1108
SNT TRC
FID C 11 1117
SNT VIA
FID C 7 564
FID C 8 749
FID C 10 1288
FID C 11 2658
FID H 12 485
SNT VIA
FID C 7 543
FID C 8 728
FID C 10 1267
FID C 11 2637
FID H 12 464
#NET 143
NET KEY2
SNT TOP T 50 0
FID C 9 672
FID C 10 734
FID C 11 2100
SNT TOP T 77 70
FID C 9 470
FID C 10 514
FID C 11 1882
SNT TRC
FID C 2 424
SNT TRC
FID C 2 428
SNT TRC
FID C 2 427
SNT TRC
FID C 2 425
SNT TRC
FID C 2 430
SNT TRC
FID C 2 429
SNT TRC
FID C 2 426
SNT TRC
FID C 3 452
SNT TRC
FID C 3 453
SNT TRC
FID C 11 1096
SNT TRC
FID C 11 731
SNT TRC
FID C 11 738
SNT TRC
FID C 11 758
SNT VIA
FID C 2 610
FID C 3 668
FID C 7 452
FID C 8 637
FID C 10 1176
FID C 11 2546
FID H 12 373
SNT VIA
FID C 2 612
FID C 7 458
FID C 8 643
FID C 10 1182
FID C 11 2552
FID H 12 379
SNT VIA
FID C 3 699
FID C 7 537
FID C 8 722
FID C 10 1261
FID C 11 2631
FID H 12 458
#NET 144
NET KEY1
SNT TOP T 51 0
FID C 9 664
FID C 10 721
FID C 11 2087
SNT TOP T 77 186
FID C 9 120
FID C 10 150
FID C 11 1521
SNT TRC
FID C 2 135
SNT TRC
FID C 2 133
SNT TRC
FID C 3 518
SNT TRC
FID C 3 140
SNT TRC
FID C 3 511
SNT TRC
FID C 3 173
SNT TRC
FID C 3 164
SNT TRC
FID C 3 168
SNT TRC
FID C 3 158
SNT TRC
FID C 11 1065
SNT TRC
FID C 11 1063
SNT TRC
FID C 11 195
SNT TRC
FID C 11 196
SNT TRC
FID C 11 211
SNT VIA
FID C 2 499
FID C 3 570
FID C 7 213
FID C 8 398
FID C 10 937
FID C 11 2307
FID H 12 134
SNT VIA
FID C 3 697
FID C 7 534
FID C 8 719
FID C 10 1258
FID C 11 2628
FID H 12 455
SNT VIA
FID C 2 496
FID C 7 205
FID C 8 390
FID C 10 929
FID C 11 2299
FID H 12 126
#NET 145
NET +5.0V
SNT TOP B 0 2
FID C 1 40
FID C 7 80
FID C 8 264
SNT TOP B 3 0
FID C 1 50
FID C 7 90
FID C 8 274
SNT TOP B 4 0
FID C 1 58
FID C 7 98
FID C 8 282
SNT TOP T 40 24
FID C 7 127
FID C 8 309
FID C 10 651
FID C 11 2017
FID H 12 48
SNT TOP T 30 1
FID C 9 160
FID C 10 190
FID C 11 1562
SNT TOP T 31 1
FID C 9 105
FID C 10 133
FID C 11 1504
SNT TOP T 33 0
FID C 9 164
FID C 10 194
FID C 11 1566
SNT TOP T 43 11
FID C 9 604
FID C 10 656
FID C 11 2022
SNT TOP T 58 0
FID C 9 635
FID C 10 688
FID C 11 2054
SNT TOP T 72 0
FID C 9 791
FID C 10 868
FID C 11 2234
SNT TOP T 79 0
FID C 9 700
FID C 10 772
FID C 11 2138
SNT TOP T 107 0
FID C 9 572
FID C 10 620
FID C 11 1986
SNT TOP T 108 0
FID C 9 573
FID C 10 621
FID C 11 1987
SNT TOP T 109 0
FID C 9 331
FID C 10 371
FID C 11 1739
SNT TOP T 110 0
FID C 9 305
FID C 10 345
FID C 11 1713
SNT TOP T 115 1
FID C 9 636
FID C 10 690
FID C 11 2056
SNT TOP T 116 1
FID C 9 625
FID C 10 678
FID C 11 2044
SNT TOP T 121 0
FID C 9 776
FID C 10 851
FID C 11 2217
SNT TOP T 122 0
FID C 9 775
FID C 10 850
FID C 11 2216
SNT TOP T 123 0
FID C 9 774
FID C 10 849
FID C 11 2215
SNT TOP T 124 0
FID C 9 773
FID C 10 848
FID C 11 2214
SNT TOP T 125 0
FID C 9 780
FID C 10 855
FID C 11 2221
SNT TOP T 126 0
FID C 9 779
FID C 10 854
FID C 11 2220
SNT TOP T 77 4
FID C 9 503
FID C 10 547
FID C 11 1915
SNT TOP T 77 6
FID C 9 502
FID C 10 546
FID C 11 1914
SNT TOP T 77 8
FID C 9 501
FID C 10 545
FID C 11 1913
SNT TOP T 77 10
FID C 9 500
FID C 10 544
FID C 11 1912
SNT TOP T 77 5
FID C 9 559
FID C 10 607
FID C 11 1973
SNT TOP T 77 7
FID C 9 558
FID C 10 606
FID C 11 1972
SNT TOP T 77 9
FID C 9 557
FID C 10 605
FID C 11 1971
SNT TOP T 77 11
FID C 9 556
FID C 10 604
FID C 11 1970
SNT TOP T 34 11
FID C 9 155
FID C 10 185
FID C 11 1557
SNT TOP T 41 2
FID C 9 276
FID C 10 316
FID C 11 1684
SNT TRC
FID C 8 194
SNT TRC
FID C 8 187
SNT TRC
FID C 8 128
SNT TRC
FID C 8 185
SNT TRC
FID C 8 181
SNT TRC
FID C 8 172
SNT TRC
FID C 8 173
SNT TRC
FID C 8 180
SNT TRC
FID C 8 169
SNT TRC
FID C 8 170
SNT TRC
FID C 8 174
SNT TRC
FID C 8 176
SNT TRC
FID C 8 179
SNT TRC
FID C 8 178
SNT TRC
FID C 8 175
SNT TRC
FID C 8 111
SNT TRC
FID C 8 91
SNT TRC
FID C 8 107
SNT TRC
FID C 8 110
SNT TRC
FID C 8 177
SNT TRC
FID C 8 126
SNT TRC
FID C 8 183
SNT TRC
FID C 8 127
SNT TRC
FID C 8 166
SNT TRC
FID C 8 165
SNT TRC
FID C 11 1338
SNT TRC
FID C 11 1327
SNT TRC
FID C 11 1328
SNT TRC
FID C 11 1339
SNT TRC
FID C 11 1329
SNT TRC
FID C 11 1330
SNT TRC
FID C 11 1331
SNT TRC
FID C 11 1363
SNT TRC
FID C 11 1332
SNT TRC
FID C 11 1369
SNT TRC
FID C 11 1372
SNT TRC
FID C 11 1368
SNT TRC
FID C 11 1370
SNT TRC
FID C 11 955
SNT TRC
FID C 11 920
SNT TRC
FID C 11 918
SNT TRC
FID C 11 1003
SNT TRC
FID C 11 960
SNT TRC
FID C 11 959
SNT TRC
FID C 11 992
SNT TRC
FID C 11 993
SNT TRC
FID C 11 994
SNT TRC
FID C 11 997
SNT TRC
FID C 11 1004
SNT TRC
FID C 11 1021
SNT TRC
FID C 11 1005
SNT TRC
FID C 11 423
SNT TRC
FID C 11 425
SNT TRC
FID C 11 432
SNT TRC
FID C 11 377
SNT TRC
FID C 11 400
SNT TRC
FID C 11 418
SNT TRC
FID C 11 492
SNT TRC
FID C 11 477
SNT TRC
FID C 11 473
SNT TRC
FID C 11 737
SNT TRC
FID C 11 736
SNT TRC
FID C 11 756
SNT TRC
FID C 11 763
SNT TRC
FID C 11 791
SNT TRC
FID C 11 775
SNT TRC
FID C 11 774
SNT TRC
FID C 11 771
SNT TRC
FID C 11 777
SNT TRC
FID C 11 772
SNT TRC
FID C 11 144
SNT TRC
FID C 11 153
SNT TRC
FID C 11 238
SNT TRC
FID C 11 845
SNT TRC
FID C 11 773
SNT TRC
FID C 11 766
SNT TRC
FID C 11 790
SNT TRC
FID C 11 787
SNT TRC
FID C 11 734
SNT TRC
FID C 11 760
SNT TRC
FID C 11 735
SNT TRC
FID C 11 765
SNT TRC
FID C 11 176
SNT TRC
FID C 11 177
SNT TRC
FID C 11 185
SNT TRC
FID C 11 236
SNT TRC
FID C 11 237
SNT TRC
FID C 11 243
SNT TRC
FID C 11 250
SNT TRC
FID C 11 234
SNT TRC
FID C 11 242
SNT TRC
FID C 11 249
SNT TRC
FID C 11 1325
SNT TRC
FID C 11 1337
SNT TRC
FID C 11 1192
SNT TRC
FID C 11 1193
SNT TRC
FID C 11 1219
SNT TRC
FID C 11 837
SNT TRC
FID C 11 838
SNT TRC
FID C 11 848
SNT TRC
FID C 11 884
SNT TRC
FID C 11 915
SNT TRC
FID C 11 846
SNT TRC
FID C 11 255
SNT TRC
FID C 11 239
SNT TRC
FID C 11 240
SNT TRC
FID C 11 254
SNT VIA
FID C 7 584
FID C 8 769
FID C 10 1308
FID C 11 2678
FID H 12 505
SNT VIA
FID C 7 526
FID C 8 711
FID C 10 1250
FID C 11 2620
FID H 12 447
SNT VIA
FID C 7 463
FID C 8 648
FID C 10 1187
FID C 11 2557
FID H 12 384
SNT VIA
FID C 7 367
FID C 8 552
FID C 10 1091
FID C 11 2461
FID H 12 288
SNT VIA
FID C 7 187
FID C 8 372
FID C 10 911
FID C 11 2281
FID H 12 108
SNT VIA
FID C 7 464
FID C 8 649
FID C 10 1188
FID C 11 2558
FID H 12 385
#NET 146
NET FPGA_TDI
SNT TOP T 77 241
FID C 9 95
FID C 10 121
FID C 11 1494
SNT TOP T 64 0
FID C 9 449
FID C 10 493
FID C 11 1861
SNT TOP T 96 2
FID C 9 460
FID C 10 504
FID C 11 1872
SNT TRC
FID C 2 120
SNT TRC
FID C 2 118
SNT TRC
FID C 2 122
SNT TRC
FID C 2 121
SNT TRC
FID C 2 119
SNT TRC
FID C 2 123
SNT TRC
FID C 3 303
SNT TRC
FID C 3 302
SNT TRC
FID C 3 153
SNT TRC
FID C 3 146
SNT TRC
FID C 3 125
SNT TRC
FID C 11 716
SNT TRC
FID C 11 718
SNT TRC
FID C 11 147
SNT TRC
FID C 11 715
SNT TRC
FID C 11 695
SNT TRC
FID C 11 694
SNT TRC
FID C 11 653
SNT TRC
FID C 11 696
SNT VIA
FID C 2 492
FID C 3 565
FID C 7 186
FID C 8 371
FID C 10 910
FID C 11 2280
FID H 12 107
SNT VIA
FID C 3 664
FID C 7 445
FID C 8 630
FID C 10 1169
FID C 11 2539
FID H 12 366
SNT VIA
FID C 2 493
FID C 7 189
FID C 8 374
FID C 10 913
FID C 11 2283
FID H 12 110
# PKG 0
PKG 39-30-1060 0.1653543 -0.434056 -0.7674208 0.125 0.0492126
CT
OB 0.125 -0.7674208 I
OS -0.434056 -0.7674208
OS -0.434056 0.0174208
OS 0.125 0.0174208
OS 0.125 -0.7674208
OE
CE
PIN 0 T -0.3307087 -0.503937 0 U U
CR -0.3307087 -0.503937 0.025
PIN 0 T 0 -0.503937 0 U U
CR 0 -0.503937 0.025
PIN 1 T 0 -0.2165354 0 U U
CR 0 -0.2165354 0.0492126
PIN 2 T -0.1653543 -0.2165354 0 U U
CR -0.1653543 -0.2165354 0.0492126
PIN 3 T -0.3307087 -0.2165354 0 U U
CR -0.3307087 -0.2165354 0.0492126
PIN 4 T 0 0 0 U U
CR 0 0 0.0492126
PIN 5 T -0.1653543 0 0 U U
CR -0.1653543 0 0.0492126
PIN 6 T -0.3307087 0 0 U U
CR -0.3307087 0 0.0492126
#
# PKG 1
PKG 3PINV-100 0.1 -0.0275 -0.0275 0.2275 0.0275
RC -0.0275 -0.0275 0.255 0.055
PIN 1 T 0 0 0 U U
CT
OB -0.0275 0.0275 I
OS 0.0275 0.0275
OS 0.0275 -0.0275
OS -0.0275 -0.0275
OS -0.0275 0.0275
OE
CE
PIN 2 T 0.1 0 0 U U
CR 0.1 0 0.0275
PIN 3 T 0.2 0 0 U U
CR 0.2 0 0.0275
#
# PKG 2
PKG ALINX_FPGA 0.01968 -1.02183 -0.85118 1.07354 0.84922
RC -1.02183 -0.85118 2.09537 1.7004
PIN 1 T 1.00951 0.78675 0 U U
CT
OB 0.950455 0.845805 I
OS 1.068565 0.845805
OS 1.068565 0.727695
OS 0.950455 0.727695
OS 0.950455 0.845805
OE
CE
PIN 1 T -0.95549 -0.78325 0 U U
CT
OB -1.014545 -0.724195 I
OS -0.896435 -0.724195
OS -0.896435 -0.842305
OS -1.014545 -0.842305
OS -1.014545 -0.724195
OE
CE
PIN 1 T -0.95649 0.78675 0 U U
CT
OB -1.015545 0.845805 I
OS -0.897435 0.845805
OS -0.897435 0.727695
OS -1.015545 0.727695
OS -1.015545 0.845805
OE
CE
PIN 1 T 1.00951 -0.78325 0 U U
CT
OB 0.950455 -0.724195 I
OS 1.068565 -0.724195
OS 1.068565 -0.842305
OS 0.950455 -0.842305
OS 0.950455 -0.724195
OE
CE
PIN 1-1 S 0.88359 0.38781 0 U U
CT
OB 0.85308 0.39273 I
OS 0.9141 0.39273
OS 0.9141 0.38289
OS 0.85308 0.38289
OS 0.85308 0.39273
OE
CE
PIN 1-2 S 1.04303 0.38781 0 U U
CT
OB 1.01252 0.39273 I
OS 1.07354 0.39273
OS 1.07354 0.38289
OS 1.01252 0.38289
OS 1.01252 0.39273
OE
CE
PIN 1-3 S 0.88359 0.36812 0 U U
CT
OB 0.85308 0.37304 I
OS 0.9141 0.37304
OS 0.9141 0.3632
OS 0.85308 0.3632
OS 0.85308 0.37304
OE
CE
PIN 1-4 S 1.04303 0.36812 0 U U
CT
OB 1.01252 0.37304 I
OS 1.07354 0.37304
OS 1.07354 0.3632
OS 1.01252 0.3632
OS 1.01252 0.37304
OE
CE
PIN 1-5 S 0.88359 0.34844 0 U U
CT
OB 0.85308 0.35336 I
OS 0.9141 0.35336
OS 0.9141 0.34352
OS 0.85308 0.34352
OS 0.85308 0.35336
OE
CE
PIN 1-6 S 1.04303 0.34844 0 U U
CT
OB 1.01252 0.35336 I
OS 1.07354 0.35336
OS 1.07354 0.34352
OS 1.01252 0.34352
OS 1.01252 0.35336
OE
CE
PIN 1-7 S 0.88359 0.32875 0 U U
CT
OB 0.85308 0.33367 I
OS 0.9141 0.33367
OS 0.9141 0.32383
OS 0.85308 0.32383
OS 0.85308 0.33367
OE
CE
PIN 1-8 S 1.04303 0.32875 0 U U
CT
OB 1.01252 0.33367 I
OS 1.07354 0.33367
OS 1.07354 0.32383
OS 1.01252 0.32383
OS 1.01252 0.33367
OE
CE
PIN 1-9 S 0.88359 0.30907 0 U U
CT
OB 0.85308 0.31399 I
OS 0.9141 0.31399
OS 0.9141 0.30415
OS 0.85308 0.30415
OS 0.85308 0.31399
OE
CE
PIN 1-10 S 1.04303 0.30907 0 U U
CT
OB 1.01252 0.31399 I
OS 1.07354 0.31399
OS 1.07354 0.30415
OS 1.01252 0.30415
OS 1.01252 0.31399
OE
CE
PIN 1-11 S 0.88359 0.28938 0 U U
CT
OB 0.85308 0.2943 I
OS 0.9141 0.2943
OS 0.9141 0.28446
OS 0.85308 0.28446
OS 0.85308 0.2943
OE
CE
PIN 1-12 S 1.04303 0.28938 0 U U
CT
OB 1.01252 0.2943 I
OS 1.07354 0.2943
OS 1.07354 0.28446
OS 1.01252 0.28446
OS 1.01252 0.2943
OE
CE
PIN 1-13 S 0.88359 0.2697 0 U U
CT
OB 0.85308 0.27462 I
OS 0.9141 0.27462
OS 0.9141 0.26478
OS 0.85308 0.26478
OS 0.85308 0.27462
OE
CE
PIN 1-14 S 1.04303 0.2697 0 U U
CT
OB 1.01252 0.27462 I
OS 1.07354 0.27462
OS 1.07354 0.26478
OS 1.01252 0.26478
OS 1.01252 0.27462
OE
CE
PIN 1-15 S 0.88359 0.25001 0 U U
CT
OB 0.85308 0.25493 I
OS 0.9141 0.25493
OS 0.9141 0.24509
OS 0.85308 0.24509
OS 0.85308 0.25493
OE
CE
PIN 1-16 S 1.04303 0.25001 0 U U
CT
OB 1.01252 0.25493 I
OS 1.07354 0.25493
OS 1.07354 0.24509
OS 1.01252 0.24509
OS 1.01252 0.25493
OE
CE
PIN 1-17 S 0.88359 0.23033 0 U U
CT
OB 0.85308 0.23525 I
OS 0.9141 0.23525
OS 0.9141 0.22541
OS 0.85308 0.22541
OS 0.85308 0.23525
OE
CE
PIN 1-18 S 1.04303 0.23033 0 U U
CT
OB 1.01252 0.23525 I
OS 1.07354 0.23525
OS 1.07354 0.22541
OS 1.01252 0.22541
OS 1.01252 0.23525
OE
CE
PIN 1-19 S 0.88359 0.21064 0 U U
CT
OB 0.85308 0.21556 I
OS 0.9141 0.21556
OS 0.9141 0.20572
OS 0.85308 0.20572
OS 0.85308 0.21556
OE
CE
PIN 1-20 S 1.04303 0.21064 0 U U
CT
OB 1.01252 0.21556 I
OS 1.07354 0.21556
OS 1.07354 0.20572
OS 1.01252 0.20572
OS 1.01252 0.21556
OE
CE
PIN 1-21 S 0.88359 0.19096 0 U U
CT
OB 0.85308 0.19588 I
OS 0.9141 0.19588
OS 0.9141 0.18604
OS 0.85308 0.18604
OS 0.85308 0.19588
OE
CE
PIN 1-22 S 1.04303 0.19096 0 U U
CT
OB 1.01252 0.19588 I
OS 1.07354 0.19588
OS 1.07354 0.18604
OS 1.01252 0.18604
OS 1.01252 0.19588
OE
CE
PIN 1-23 S 0.88359 0.17127 0 U U
CT
OB 0.85308 0.17619 I
OS 0.9141 0.17619
OS 0.9141 0.16635
OS 0.85308 0.16635
OS 0.85308 0.17619
OE
CE
PIN 1-24 S 1.04303 0.17127 0 U U
CT
OB 1.01252 0.17619 I
OS 1.07354 0.17619
OS 1.07354 0.16635
OS 1.01252 0.16635
OS 1.01252 0.17619
OE
CE
PIN 1-25 S 0.88359 0.15159 0 U U
CT
OB 0.85308 0.15651 I
OS 0.9141 0.15651
OS 0.9141 0.14667
OS 0.85308 0.14667
OS 0.85308 0.15651
OE
CE
PIN 1-26 S 1.04303 0.15159 0 U U
CT
OB 1.01252 0.15651 I
OS 1.07354 0.15651
OS 1.07354 0.14667
OS 1.01252 0.14667
OS 1.01252 0.15651
OE
CE
PIN 1-27 S 0.88359 0.1319 0 U U
CT
OB 0.85308 0.13682 I
OS 0.9141 0.13682
OS 0.9141 0.12698
OS 0.85308 0.12698
OS 0.85308 0.13682
OE
CE
PIN 1-28 S 1.04303 0.1319 0 U U
CT
OB 1.01252 0.13682 I
OS 1.07354 0.13682
OS 1.07354 0.12698
OS 1.01252 0.12698
OS 1.01252 0.13682
OE
CE
PIN 1-29 S 0.88359 0.11222 0 U U
CT
OB 0.85308 0.11714 I
OS 0.9141 0.11714
OS 0.9141 0.1073
OS 0.85308 0.1073
OS 0.85308 0.11714
OE
CE
PIN 1-30 S 1.04303 0.11222 0 U U
CT
OB 1.01252 0.11714 I
OS 1.07354 0.11714
OS 1.07354 0.1073
OS 1.01252 0.1073
OS 1.01252 0.11714
OE
CE
PIN 1-31 S 0.88359 0.09253 0 U U
CT
OB 0.85308 0.09745 I
OS 0.9141 0.09745
OS 0.9141 0.08761
OS 0.85308 0.08761
OS 0.85308 0.09745
OE
CE
PIN 1-32 S 1.04303 0.09253 0 U U
CT
OB 1.01252 0.09745 I
OS 1.07354 0.09745
OS 1.07354 0.08761
OS 1.01252 0.08761
OS 1.01252 0.09745
OE
CE
PIN 1-33 S 0.88359 0.07285 0 U U
CT
OB 0.85308 0.07777 I
OS 0.9141 0.07777
OS 0.9141 0.06793
OS 0.85308 0.06793
OS 0.85308 0.07777
OE
CE
PIN 1-34 S 1.04303 0.07285 0 U U
CT
OB 1.01252 0.07777 I
OS 1.07354 0.07777
OS 1.07354 0.06793
OS 1.01252 0.06793
OS 1.01252 0.07777
OE
CE
PIN 1-35 S 0.88359 0.05316 0 U U
CT
OB 0.85308 0.05808 I
OS 0.9141 0.05808
OS 0.9141 0.04824
OS 0.85308 0.04824
OS 0.85308 0.05808
OE
CE
PIN 1-36 S 1.04303 0.05316 0 U U
CT
OB 1.01252 0.05808 I
OS 1.07354 0.05808
OS 1.07354 0.04824
OS 1.01252 0.04824
OS 1.01252 0.05808
OE
CE
PIN 1-37 S 0.88359 0.03348 0 U U
CT
OB 0.85308 0.0384 I
OS 0.9141 0.0384
OS 0.9141 0.02856
OS 0.85308 0.02856
OS 0.85308 0.0384
OE
CE
PIN 1-38 S 1.04303 0.03348 0 U U
CT
OB 1.01252 0.0384 I
OS 1.07354 0.0384
OS 1.07354 0.02856
OS 1.01252 0.02856
OS 1.01252 0.0384
OE
CE
PIN 1-39 S 0.88359 0.01379 0 U U
CT
OB 0.85308 0.01871 I
OS 0.9141 0.01871
OS 0.9141 0.00887
OS 0.85308 0.00887
OS 0.85308 0.01871
OE
CE
PIN 1-40 S 1.04303 0.01379 0 U U
CT
OB 1.01252 0.01871 I
OS 1.07354 0.01871
OS 1.07354 0.00887
OS 1.01252 0.00887
OS 1.01252 0.01871
OE
CE
PIN 1-41 S 0.88359 -0.00589 0 U U
CT
OB 0.85308 -0.00097 I
OS 0.9141 -0.00097
OS 0.9141 -0.01081
OS 0.85308 -0.01081
OS 0.85308 -0.00097
OE
CE
PIN 1-42 S 1.04303 -0.00589 0 U U
CT
OB 1.01252 -0.00097 I
OS 1.07354 -0.00097
OS 1.07354 -0.01081
OS 1.01252 -0.01081
OS 1.01252 -0.00097
OE
CE
PIN 1-43 S 0.88359 -0.02558 0 U U
CT
OB 0.85308 -0.02066 I
OS 0.9141 -0.02066
OS 0.9141 -0.0305
OS 0.85308 -0.0305
OS 0.85308 -0.02066
OE
CE
PIN 1-44 S 1.04303 -0.02558 0 U U
CT
OB 1.01252 -0.02066 I
OS 1.07354 -0.02066
OS 1.07354 -0.0305
OS 1.01252 -0.0305
OS 1.01252 -0.02066
OE
CE
PIN 1-45 S 0.88359 -0.04526 0 U U
CT
OB 0.85308 -0.04034 I
OS 0.9141 -0.04034
OS 0.9141 -0.05018
OS 0.85308 -0.05018
OS 0.85308 -0.04034
OE
CE
PIN 1-46 S 1.04303 -0.04526 0 U U
CT
OB 1.01252 -0.04034 I
OS 1.07354 -0.04034
OS 1.07354 -0.05018
OS 1.01252 -0.05018
OS 1.01252 -0.04034
OE
CE
PIN 1-47 S 0.88359 -0.06495 0 U U
CT
OB 0.85308 -0.06003 I
OS 0.9141 -0.06003
OS 0.9141 -0.06987
OS 0.85308 -0.06987
OS 0.85308 -0.06003
OE
CE
PIN 1-48 S 1.04303 -0.06495 0 U U
CT
OB 1.01252 -0.06003 I
OS 1.07354 -0.06003
OS 1.07354 -0.06987
OS 1.01252 -0.06987
OS 1.01252 -0.06003
OE
CE
PIN 1-49 S 0.88359 -0.08463 0 U U
CT
OB 0.85308 -0.07971 I
OS 0.9141 -0.07971
OS 0.9141 -0.08955
OS 0.85308 -0.08955
OS 0.85308 -0.07971
OE
CE
PIN 1-50 S 1.04303 -0.08463 0 U U
CT
OB 1.01252 -0.07971 I
OS 1.07354 -0.07971
OS 1.07354 -0.08955
OS 1.01252 -0.08955
OS 1.01252 -0.07971
OE
CE
PIN 1-51 S 0.88359 -0.10432 0 U U
CT
OB 0.85308 -0.0994 I
OS 0.9141 -0.0994
OS 0.9141 -0.10924
OS 0.85308 -0.10924
OS 0.85308 -0.0994
OE
CE
PIN 1-52 S 1.04303 -0.10432 0 U U
CT
OB 1.01252 -0.0994 I
OS 1.07354 -0.0994
OS 1.07354 -0.10924
OS 1.01252 -0.10924
OS 1.01252 -0.0994
OE
CE
PIN 1-53 S 0.88359 -0.124 0 U U
CT
OB 0.85308 -0.11908 I
OS 0.9141 -0.11908
OS 0.9141 -0.12892
OS 0.85308 -0.12892
OS 0.85308 -0.11908
OE
CE
PIN 1-54 S 1.04303 -0.124 0 U U
CT
OB 1.01252 -0.11908 I
OS 1.07354 -0.11908
OS 1.07354 -0.12892
OS 1.01252 -0.12892
OS 1.01252 -0.11908
OE
CE
PIN 1-55 S 0.88359 -0.14369 0 U U
CT
OB 0.85308 -0.13877 I
OS 0.9141 -0.13877
OS 0.9141 -0.14861
OS 0.85308 -0.14861
OS 0.85308 -0.13877
OE
CE
PIN 1-56 S 1.04303 -0.14369 0 U U
CT
OB 1.01252 -0.13877 I
OS 1.07354 -0.13877
OS 1.07354 -0.14861
OS 1.01252 -0.14861
OS 1.01252 -0.13877
OE
CE
PIN 1-57 S 0.88359 -0.16337 0 U U
CT
OB 0.85308 -0.15845 I
OS 0.9141 -0.15845
OS 0.9141 -0.16829
OS 0.85308 -0.16829
OS 0.85308 -0.15845
OE
CE
PIN 1-58 S 1.04303 -0.16337 0 U U
CT
OB 1.01252 -0.15845 I
OS 1.07354 -0.15845
OS 1.07354 -0.16829
OS 1.01252 -0.16829
OS 1.01252 -0.15845
OE
CE
PIN 1-59 S 0.88359 -0.18306 0 U U
CT
OB 0.85308 -0.17814 I
OS 0.9141 -0.17814
OS 0.9141 -0.18798
OS 0.85308 -0.18798
OS 0.85308 -0.17814
OE
CE
PIN 1-60 S 1.04303 -0.18306 0 U U
CT
OB 1.01252 -0.17814 I
OS 1.07354 -0.17814
OS 1.07354 -0.18798
OS 1.01252 -0.18798
OS 1.01252 -0.17814
OE
CE
PIN 1-61 S 0.88359 -0.20274 0 U U
CT
OB 0.85308 -0.19782 I
OS 0.9141 -0.19782
OS 0.9141 -0.20766
OS 0.85308 -0.20766
OS 0.85308 -0.19782
OE
CE
PIN 1-62 S 1.04303 -0.20274 0 U U
CT
OB 1.01252 -0.19782 I
OS 1.07354 -0.19782
OS 1.07354 -0.20766
OS 1.01252 -0.20766
OS 1.01252 -0.19782
OE
CE
PIN 1-63 S 0.88359 -0.22243 0 U U
CT
OB 0.85308 -0.21751 I
OS 0.9141 -0.21751
OS 0.9141 -0.22735
OS 0.85308 -0.22735
OS 0.85308 -0.21751
OE
CE
PIN 1-64 S 1.04303 -0.22243 0 U U
CT
OB 1.01252 -0.21751 I
OS 1.07354 -0.21751
OS 1.07354 -0.22735
OS 1.01252 -0.22735
OS 1.01252 -0.21751
OE
CE
PIN 1-65 S 0.88359 -0.24211 0 U U
CT
OB 0.85308 -0.23719 I
OS 0.9141 -0.23719
OS 0.9141 -0.24703
OS 0.85308 -0.24703
OS 0.85308 -0.23719
OE
CE
PIN 1-66 S 1.04303 -0.24211 0 U U
CT
OB 1.01252 -0.23719 I
OS 1.07354 -0.23719
OS 1.07354 -0.24703
OS 1.01252 -0.24703
OS 1.01252 -0.23719
OE
CE
PIN 1-67 S 0.88359 -0.2618 0 U U
CT
OB 0.85308 -0.25688 I
OS 0.9141 -0.25688
OS 0.9141 -0.26672
OS 0.85308 -0.26672
OS 0.85308 -0.25688
OE
CE
PIN 1-68 S 1.04303 -0.2618 0 U U
CT
OB 1.01252 -0.25688 I
OS 1.07354 -0.25688
OS 1.07354 -0.26672
OS 1.01252 -0.26672
OS 1.01252 -0.25688
OE
CE
PIN 1-69 S 0.88359 -0.28148 0 U U
CT
OB 0.85308 -0.27656 I
OS 0.9141 -0.27656
OS 0.9141 -0.2864
OS 0.85308 -0.2864
OS 0.85308 -0.27656
OE
CE
PIN 1-70 S 1.04303 -0.28148 0 U U
CT
OB 1.01252 -0.27656 I
OS 1.07354 -0.27656
OS 1.07354 -0.2864
OS 1.01252 -0.2864
OS 1.01252 -0.27656
OE
CE
PIN 1-71 S 0.88359 -0.30117 0 U U
CT
OB 0.85308 -0.29625 I
OS 0.9141 -0.29625
OS 0.9141 -0.30609
OS 0.85308 -0.30609
OS 0.85308 -0.29625
OE
CE
PIN 1-72 S 1.04303 -0.30117 0 U U
CT
OB 1.01252 -0.29625 I
OS 1.07354 -0.29625
OS 1.07354 -0.30609
OS 1.01252 -0.30609
OS 1.01252 -0.29625
OE
CE
PIN 1-73 S 0.88359 -0.32085 0 U U
CT
OB 0.85308 -0.31593 I
OS 0.9141 -0.31593
OS 0.9141 -0.32577
OS 0.85308 -0.32577
OS 0.85308 -0.31593
OE
CE
PIN 1-74 S 1.04303 -0.32085 0 U U
CT
OB 1.01252 -0.31593 I
OS 1.07354 -0.31593
OS 1.07354 -0.32577
OS 1.01252 -0.32577
OS 1.01252 -0.31593
OE
CE
PIN 1-75 S 0.88359 -0.34054 0 U U
CT
OB 0.85308 -0.33562 I
OS 0.9141 -0.33562
OS 0.9141 -0.34546
OS 0.85308 -0.34546
OS 0.85308 -0.33562
OE
CE
PIN 1-76 S 1.04303 -0.34054 0 U U
CT
OB 1.01252 -0.33562 I
OS 1.07354 -0.33562
OS 1.07354 -0.34546
OS 1.01252 -0.34546
OS 1.01252 -0.33562
OE
CE
PIN 1-77 S 0.88359 -0.36022 0 U U
CT
OB 0.85308 -0.3553 I
OS 0.9141 -0.3553
OS 0.9141 -0.36514
OS 0.85308 -0.36514
OS 0.85308 -0.3553
OE
CE
PIN 1-78 S 1.04303 -0.36022 0 U U
CT
OB 1.01252 -0.3553 I
OS 1.07354 -0.3553
OS 1.07354 -0.36514
OS 1.01252 -0.36514
OS 1.01252 -0.3553
OE
CE
PIN 1-79 S 0.88359 -0.37991 0 U U
CT
OB 0.85308 -0.37499 I
OS 0.9141 -0.37499
OS 0.9141 -0.38483
OS 0.85308 -0.38483
OS 0.85308 -0.37499
OE
CE
PIN 1-80 S 1.04303 -0.37991 0 U U
CT
OB 1.01252 -0.37499 I
OS 1.07354 -0.37499
OS 1.07354 -0.38483
OS 1.01252 -0.38483
OS 1.01252 -0.37499
OE
CE
PIN 2-1 S -0.39546 0.65927 0 U U
CT
OB -0.40038 0.68978 I
OS -0.39054 0.68978
OS -0.39054 0.62876
OS -0.40038 0.62876
OS -0.40038 0.68978
OE
CE
PIN 2-2 S -0.39546 0.81871 0 U U
CT
OB -0.40038 0.84922 I
OS -0.39054 0.84922
OS -0.39054 0.7882
OS -0.40038 0.7882
OS -0.40038 0.84922
OE
CE
PIN 2-3 S -0.37577 0.65927 0 U U
CT
OB -0.38069 0.68978 I
OS -0.37085 0.68978
OS -0.37085 0.62876
OS -0.38069 0.62876
OS -0.38069 0.68978
OE
CE
PIN 2-4 S -0.37577 0.81871 0 U U
CT
OB -0.38069 0.84922 I
OS -0.37085 0.84922
OS -0.37085 0.7882
OS -0.38069 0.7882
OS -0.38069 0.84922
OE
CE
PIN 2-5 S -0.35609 0.65927 0 U U
CT
OB -0.36101 0.68978 I
OS -0.35117 0.68978
OS -0.35117 0.62876
OS -0.36101 0.62876
OS -0.36101 0.68978
OE
CE
PIN 2-6 S -0.35609 0.81871 0 U U
CT
OB -0.36101 0.84922 I
OS -0.35117 0.84922
OS -0.35117 0.7882
OS -0.36101 0.7882
OS -0.36101 0.84922
OE
CE
PIN 2-7 S -0.3364 0.65927 0 U U
CT
OB -0.34132 0.68978 I
OS -0.33148 0.68978
OS -0.33148 0.62876
OS -0.34132 0.62876
OS -0.34132 0.68978
OE
CE
PIN 2-8 S -0.3364 0.81871 0 U U
CT
OB -0.34132 0.84922 I
OS -0.33148 0.84922
OS -0.33148 0.7882
OS -0.34132 0.7882
OS -0.34132 0.84922
OE
CE
PIN 2-9 S -0.31672 0.65927 0 U U
CT
OB -0.32164 0.68978 I
OS -0.3118 0.68978
OS -0.3118 0.62876
OS -0.32164 0.62876
OS -0.32164 0.68978
OE
CE
PIN 2-10 S -0.31672 0.81871 0 U U
CT
OB -0.32164 0.84922 I
OS -0.3118 0.84922
OS -0.3118 0.7882
OS -0.32164 0.7882
OS -0.32164 0.84922
OE
CE
PIN 2-11 S -0.29703 0.65927 0 U U
CT
OB -0.30195 0.68978 I
OS -0.29211 0.68978
OS -0.29211 0.62876
OS -0.30195 0.62876
OS -0.30195 0.68978
OE
CE
PIN 2-12 S -0.29703 0.81871 0 U U
CT
OB -0.30195 0.84922 I
OS -0.29211 0.84922
OS -0.29211 0.7882
OS -0.30195 0.7882
OS -0.30195 0.84922
OE
CE
PIN 2-13 S -0.27735 0.65927 0 U U
CT
OB -0.28227 0.68978 I
OS -0.27243 0.68978
OS -0.27243 0.62876
OS -0.28227 0.62876
OS -0.28227 0.68978
OE
CE
PIN 2-14 S -0.27735 0.81871 0 U U
CT
OB -0.28227 0.84922 I
OS -0.27243 0.84922
OS -0.27243 0.7882
OS -0.28227 0.7882
OS -0.28227 0.84922
OE
CE
PIN 2-15 S -0.25766 0.65927 0 U U
CT
OB -0.26258 0.68978 I
OS -0.25274 0.68978
OS -0.25274 0.62876
OS -0.26258 0.62876
OS -0.26258 0.68978
OE
CE
PIN 2-16 S -0.25766 0.81871 0 U U
CT
OB -0.26258 0.84922 I
OS -0.25274 0.84922
OS -0.25274 0.7882
OS -0.26258 0.7882
OS -0.26258 0.84922
OE
CE
PIN 2-17 S -0.23798 0.65927 0 U U
CT
OB -0.2429 0.68978 I
OS -0.23306 0.68978
OS -0.23306 0.62876
OS -0.2429 0.62876
OS -0.2429 0.68978
OE
CE
PIN 2-18 S -0.23798 0.81871 0 U U
CT
OB -0.2429 0.84922 I
OS -0.23306 0.84922
OS -0.23306 0.7882
OS -0.2429 0.7882
OS -0.2429 0.84922
OE
CE
PIN 2-19 S -0.21829 0.65927 0 U U
CT
OB -0.22321 0.68978 I
OS -0.21337 0.68978
OS -0.21337 0.62876
OS -0.22321 0.62876
OS -0.22321 0.68978
OE
CE
PIN 2-20 S -0.21829 0.81871 0 U U
CT
OB -0.22321 0.84922 I
OS -0.21337 0.84922
OS -0.21337 0.7882
OS -0.22321 0.7882
OS -0.22321 0.84922
OE
CE
PIN 2-21 S -0.19861 0.65927 0 U U
CT
OB -0.20353 0.68978 I
OS -0.19369 0.68978
OS -0.19369 0.62876
OS -0.20353 0.62876
OS -0.20353 0.68978
OE
CE
PIN 2-22 S -0.19861 0.81871 0 U U
CT
OB -0.20353 0.84922 I
OS -0.19369 0.84922
OS -0.19369 0.7882
OS -0.20353 0.7882
OS -0.20353 0.84922
OE
CE
PIN 2-23 S -0.17892 0.65927 0 U U
CT
OB -0.18384 0.68978 I
OS -0.174 0.68978
OS -0.174 0.62876
OS -0.18384 0.62876
OS -0.18384 0.68978
OE
CE
PIN 2-24 S -0.17892 0.81871 0 U U
CT
OB -0.18384 0.84922 I
OS -0.174 0.84922
OS -0.174 0.7882
OS -0.18384 0.7882
OS -0.18384 0.84922
OE
CE
PIN 2-25 S -0.15924 0.65927 0 U U
CT
OB -0.16416 0.68978 I
OS -0.15432 0.68978
OS -0.15432 0.62876
OS -0.16416 0.62876
OS -0.16416 0.68978
OE
CE
PIN 2-26 S -0.15924 0.81871 0 U U
CT
OB -0.16416 0.84922 I
OS -0.15432 0.84922
OS -0.15432 0.7882
OS -0.16416 0.7882
OS -0.16416 0.84922
OE
CE
PIN 2-27 S -0.13955 0.65927 0 U U
CT
OB -0.14447 0.68978 I
OS -0.13463 0.68978
OS -0.13463 0.62876
OS -0.14447 0.62876
OS -0.14447 0.68978
OE
CE
PIN 2-28 S -0.13955 0.81871 0 U U
CT
OB -0.14447 0.84922 I
OS -0.13463 0.84922
OS -0.13463 0.7882
OS -0.14447 0.7882
OS -0.14447 0.84922
OE
CE
PIN 2-29 S -0.11987 0.65927 0 U U
CT
OB -0.12479 0.68978 I
OS -0.11495 0.68978
OS -0.11495 0.62876
OS -0.12479 0.62876
OS -0.12479 0.68978
OE
CE
PIN 2-30 S -0.11987 0.81871 0 U U
CT
OB -0.12479 0.84922 I
OS -0.11495 0.84922
OS -0.11495 0.7882
OS -0.12479 0.7882
OS -0.12479 0.84922
OE
CE
PIN 2-31 S -0.10018 0.65927 0 U U
CT
OB -0.1051 0.68978 I
OS -0.09526 0.68978
OS -0.09526 0.62876
OS -0.1051 0.62876
OS -0.1051 0.68978
OE
CE
PIN 2-32 S -0.10018 0.81871 0 U U
CT
OB -0.1051 0.84922 I
OS -0.09526 0.84922
OS -0.09526 0.7882
OS -0.1051 0.7882
OS -0.1051 0.84922
OE
CE
PIN 2-33 S -0.0805 0.65927 0 U U
CT
OB -0.08542 0.68978 I
OS -0.07558 0.68978
OS -0.07558 0.62876
OS -0.08542 0.62876
OS -0.08542 0.68978
OE
CE
PIN 2-34 S -0.0805 0.81871 0 U U
CT
OB -0.08542 0.84922 I
OS -0.07558 0.84922
OS -0.07558 0.7882
OS -0.08542 0.7882
OS -0.08542 0.84922
OE
CE
PIN 2-35 S -0.06081 0.65927 0 U U
CT
OB -0.06573 0.68978 I
OS -0.05589 0.68978
OS -0.05589 0.62876
OS -0.06573 0.62876
OS -0.06573 0.68978
OE
CE
PIN 2-36 S -0.06081 0.81871 0 U U
CT
OB -0.06573 0.84922 I
OS -0.05589 0.84922
OS -0.05589 0.7882
OS -0.06573 0.7882
OS -0.06573 0.84922
OE
CE
PIN 2-37 S -0.04113 0.65927 0 U U
CT
OB -0.04605 0.68978 I
OS -0.03621 0.68978
OS -0.03621 0.62876
OS -0.04605 0.62876
OS -0.04605 0.68978
OE
CE
PIN 2-38 S -0.04113 0.81871 0 U U
CT
OB -0.04605 0.84922 I
OS -0.03621 0.84922
OS -0.03621 0.7882
OS -0.04605 0.7882
OS -0.04605 0.84922
OE
CE
PIN 2-39 S -0.02144 0.65927 0 U U
CT
OB -0.02636 0.68978 I
OS -0.01652 0.68978
OS -0.01652 0.62876
OS -0.02636 0.62876
OS -0.02636 0.68978
OE
CE
PIN 2-40 S -0.02144 0.81871 0 U U
CT
OB -0.02636 0.84922 I
OS -0.01652 0.84922
OS -0.01652 0.7882
OS -0.02636 0.7882
OS -0.02636 0.84922
OE
CE
PIN 2-41 S -0.00176 0.65927 0 U U
CT
OB -0.00668 0.68978 I
OS 0.00316 0.68978
OS 0.00316 0.62876
OS -0.00668 0.62876
OS -0.00668 0.68978
OE
CE
PIN 2-42 S -0.00176 0.81871 0 U U
CT
OB -0.00668 0.84922 I
OS 0.00316 0.84922
OS 0.00316 0.7882
OS -0.00668 0.7882
OS -0.00668 0.84922
OE
CE
PIN 2-43 S 0.01793 0.65927 0 U U
CT
OB 0.01301 0.68978 I
OS 0.02285 0.68978
OS 0.02285 0.62876
OS 0.01301 0.62876
OS 0.01301 0.68978
OE
CE
PIN 2-44 S 0.01793 0.81871 0 U U
CT
OB 0.01301 0.84922 I
OS 0.02285 0.84922
OS 0.02285 0.7882
OS 0.01301 0.7882
OS 0.01301 0.84922
OE
CE
PIN 2-45 S 0.03761 0.65927 0 U U
CT
OB 0.03269 0.68978 I
OS 0.04253 0.68978
OS 0.04253 0.62876
OS 0.03269 0.62876
OS 0.03269 0.68978
OE
CE
PIN 2-46 S 0.03761 0.81871 0 U U
CT
OB 0.03269 0.84922 I
OS 0.04253 0.84922
OS 0.04253 0.7882
OS 0.03269 0.7882
OS 0.03269 0.84922
OE
CE
PIN 2-47 S 0.0573 0.65927 0 U U
CT
OB 0.05238 0.68978 I
OS 0.06222 0.68978
OS 0.06222 0.62876
OS 0.05238 0.62876
OS 0.05238 0.68978
OE
CE
PIN 2-48 S 0.0573 0.81871 0 U U
CT
OB 0.05238 0.84922 I
OS 0.06222 0.84922
OS 0.06222 0.7882
OS 0.05238 0.7882
OS 0.05238 0.84922
OE
CE
PIN 2-49 S 0.07698 0.65927 0 U U
CT
OB 0.07206 0.68978 I
OS 0.0819 0.68978
OS 0.0819 0.62876
OS 0.07206 0.62876
OS 0.07206 0.68978
OE
CE
PIN 2-50 S 0.07698 0.81871 0 U U
CT
OB 0.07206 0.84922 I
OS 0.0819 0.84922
OS 0.0819 0.7882
OS 0.07206 0.7882
OS 0.07206 0.84922
OE
CE
PIN 2-51 S 0.09667 0.65927 0 U U
CT
OB 0.09175 0.68978 I
OS 0.10159 0.68978
OS 0.10159 0.62876
OS 0.09175 0.62876
OS 0.09175 0.68978
OE
CE
PIN 2-52 S 0.09667 0.81871 0 U U
CT
OB 0.09175 0.84922 I
OS 0.10159 0.84922
OS 0.10159 0.7882
OS 0.09175 0.7882
OS 0.09175 0.84922
OE
CE
PIN 2-53 S 0.11635 0.65927 0 U U
CT
OB 0.11143 0.68978 I
OS 0.12127 0.68978
OS 0.12127 0.62876
OS 0.11143 0.62876
OS 0.11143 0.68978
OE
CE
PIN 2-54 S 0.11635 0.81871 0 U U
CT
OB 0.11143 0.84922 I
OS 0.12127 0.84922
OS 0.12127 0.7882
OS 0.11143 0.7882
OS 0.11143 0.84922
OE
CE
PIN 2-55 S 0.13604 0.65927 0 U U
CT
OB 0.13112 0.68978 I
OS 0.14096 0.68978
OS 0.14096 0.62876
OS 0.13112 0.62876
OS 0.13112 0.68978
OE
CE
PIN 2-56 S 0.13604 0.81871 0 U U
CT
OB 0.13112 0.84922 I
OS 0.14096 0.84922
OS 0.14096 0.7882
OS 0.13112 0.7882
OS 0.13112 0.84922
OE
CE
PIN 2-57 S 0.15572 0.65927 0 U U
CT
OB 0.1508 0.68978 I
OS 0.16064 0.68978
OS 0.16064 0.62876
OS 0.1508 0.62876
OS 0.1508 0.68978
OE
CE
PIN 2-58 S 0.15572 0.81871 0 U U
CT
OB 0.1508 0.84922 I
OS 0.16064 0.84922
OS 0.16064 0.7882
OS 0.1508 0.7882
OS 0.1508 0.84922
OE
CE
PIN 2-59 S 0.17541 0.65927 0 U U
CT
OB 0.17049 0.68978 I
OS 0.18033 0.68978
OS 0.18033 0.62876
OS 0.17049 0.62876
OS 0.17049 0.68978
OE
CE
PIN 2-60 S 0.17541 0.81871 0 U U
CT
OB 0.17049 0.84922 I
OS 0.18033 0.84922
OS 0.18033 0.7882
OS 0.17049 0.7882
OS 0.17049 0.84922
OE
CE
PIN 2-61 S 0.19509 0.65927 0 U U
CT
OB 0.19017 0.68978 I
OS 0.20001 0.68978
OS 0.20001 0.62876
OS 0.19017 0.62876
OS 0.19017 0.68978
OE
CE
PIN 2-62 S 0.19509 0.81871 0 U U
CT
OB 0.19017 0.84922 I
OS 0.20001 0.84922
OS 0.20001 0.7882
OS 0.19017 0.7882
OS 0.19017 0.84922
OE
CE
PIN 2-63 S 0.21478 0.65927 0 U U
CT
OB 0.20986 0.68978 I
OS 0.2197 0.68978
OS 0.2197 0.62876
OS 0.20986 0.62876
OS 0.20986 0.68978
OE
CE
PIN 2-64 S 0.21478 0.81871 0 U U
CT
OB 0.20986 0.84922 I
OS 0.2197 0.84922
OS 0.2197 0.7882
OS 0.20986 0.7882
OS 0.20986 0.84922
OE
CE
PIN 2-65 S 0.23446 0.65927 0 U U
CT
OB 0.22954 0.68978 I
OS 0.23938 0.68978
OS 0.23938 0.62876
OS 0.22954 0.62876
OS 0.22954 0.68978
OE
CE
PIN 2-66 S 0.23446 0.81871 0 U U
CT
OB 0.22954 0.84922 I
OS 0.23938 0.84922
OS 0.23938 0.7882
OS 0.22954 0.7882
OS 0.22954 0.84922
OE
CE
PIN 2-67 S 0.25415 0.65927 0 U U
CT
OB 0.24923 0.68978 I
OS 0.25907 0.68978
OS 0.25907 0.62876
OS 0.24923 0.62876
OS 0.24923 0.68978
OE
CE
PIN 2-68 S 0.25415 0.81871 0 U U
CT
OB 0.24923 0.84922 I
OS 0.25907 0.84922
OS 0.25907 0.7882
OS 0.24923 0.7882
OS 0.24923 0.84922
OE
CE
PIN 2-69 S 0.27383 0.65927 0 U U
CT
OB 0.26891 0.68978 I
OS 0.27875 0.68978
OS 0.27875 0.62876
OS 0.26891 0.62876
OS 0.26891 0.68978
OE
CE
PIN 2-70 S 0.27383 0.81871 0 U U
CT
OB 0.26891 0.84922 I
OS 0.27875 0.84922
OS 0.27875 0.7882
OS 0.26891 0.7882
OS 0.26891 0.84922
OE
CE
PIN 2-71 S 0.29352 0.65927 0 U U
CT
OB 0.2886 0.68978 I
OS 0.29844 0.68978
OS 0.29844 0.62876
OS 0.2886 0.62876
OS 0.2886 0.68978
OE
CE
PIN 2-72 S 0.29352 0.81871 0 U U
CT
OB 0.2886 0.84922 I
OS 0.29844 0.84922
OS 0.29844 0.7882
OS 0.2886 0.7882
OS 0.2886 0.84922
OE
CE
PIN 2-73 S 0.3132 0.65927 0 U U
CT
OB 0.30828 0.68978 I
OS 0.31812 0.68978
OS 0.31812 0.62876
OS 0.30828 0.62876
OS 0.30828 0.68978
OE
CE
PIN 2-74 S 0.3132 0.81871 0 U U
CT
OB 0.30828 0.84922 I
OS 0.31812 0.84922
OS 0.31812 0.7882
OS 0.30828 0.7882
OS 0.30828 0.84922
OE
CE
PIN 2-75 S 0.33289 0.65927 0 U U
CT
OB 0.32797 0.68978 I
OS 0.33781 0.68978
OS 0.33781 0.62876
OS 0.32797 0.62876
OS 0.32797 0.68978
OE
CE
PIN 2-76 S 0.33289 0.81871 0 U U
CT
OB 0.32797 0.84922 I
OS 0.33781 0.84922
OS 0.33781 0.7882
OS 0.32797 0.7882
OS 0.32797 0.84922
OE
CE
PIN 2-77 S 0.35257 0.65927 0 U U
CT
OB 0.34765 0.68978 I
OS 0.35749 0.68978
OS 0.35749 0.62876
OS 0.34765 0.62876
OS 0.34765 0.68978
OE
CE
PIN 2-78 S 0.35257 0.81871 0 U U
CT
OB 0.34765 0.84922 I
OS 0.35749 0.84922
OS 0.35749 0.7882
OS 0.34765 0.7882
OS 0.34765 0.84922
OE
CE
PIN 2-79 S 0.37226 0.65927 0 U U
CT
OB 0.36734 0.68978 I
OS 0.37718 0.68978
OS 0.37718 0.62876
OS 0.36734 0.62876
OS 0.36734 0.68978
OE
CE
PIN 2-80 S 0.37226 0.81871 0 U U
CT
OB 0.36734 0.84922 I
OS 0.37718 0.84922
OS 0.37718 0.7882
OS 0.36734 0.7882
OS 0.36734 0.84922
OE
CE
PIN 3-1 S -0.83188 -0.37987 0 U U
CT
OB -0.86239 -0.37495 I
OS -0.80137 -0.37495
OS -0.80137 -0.38479
OS -0.86239 -0.38479
OS -0.86239 -0.37495
OE
CE
PIN 3-2 S -0.99132 -0.37987 0 U U
CT
OB -1.02183 -0.37495 I
OS -0.96081 -0.37495
OS -0.96081 -0.38479
OS -1.02183 -0.38479
OS -1.02183 -0.37495
OE
CE
PIN 3-3 S -0.83188 -0.36018 0 U U
CT
OB -0.86239 -0.35526 I
OS -0.80137 -0.35526
OS -0.80137 -0.3651
OS -0.86239 -0.3651
OS -0.86239 -0.35526
OE
CE
PIN 3-4 S -0.99132 -0.36018 0 U U
CT
OB -1.02183 -0.35526 I
OS -0.96081 -0.35526
OS -0.96081 -0.3651
OS -1.02183 -0.3651
OS -1.02183 -0.35526
OE
CE
PIN 3-5 S -0.83188 -0.3405 0 U U
CT
OB -0.86239 -0.33558 I
OS -0.80137 -0.33558
OS -0.80137 -0.34542
OS -0.86239 -0.34542
OS -0.86239 -0.33558
OE
CE
PIN 3-6 S -0.99132 -0.3405 0 U U
CT
OB -1.02183 -0.33558 I
OS -0.96081 -0.33558
OS -0.96081 -0.34542
OS -1.02183 -0.34542
OS -1.02183 -0.33558
OE
CE
PIN 3-7 S -0.83188 -0.32081 0 U U
CT
OB -0.86239 -0.31589 I
OS -0.80137 -0.31589
OS -0.80137 -0.32573
OS -0.86239 -0.32573
OS -0.86239 -0.31589
OE
CE
PIN 3-8 S -0.99132 -0.32081 0 U U
CT
OB -1.02183 -0.31589 I
OS -0.96081 -0.31589
OS -0.96081 -0.32573
OS -1.02183 -0.32573
OS -1.02183 -0.31589
OE
CE
PIN 3-9 S -0.83188 -0.30113 0 U U
CT
OB -0.86239 -0.29621 I
OS -0.80137 -0.29621
OS -0.80137 -0.30605
OS -0.86239 -0.30605
OS -0.86239 -0.29621
OE
CE
PIN 3-10 S -0.99132 -0.30113 0 U U
CT
OB -1.02183 -0.29621 I
OS -0.96081 -0.29621
OS -0.96081 -0.30605
OS -1.02183 -0.30605
OS -1.02183 -0.29621
OE
CE
PIN 3-11 S -0.83188 -0.28144 0 U U
CT
OB -0.86239 -0.27652 I
OS -0.80137 -0.27652
OS -0.80137 -0.28636
OS -0.86239 -0.28636
OS -0.86239 -0.27652
OE
CE
PIN 3-12 S -0.99132 -0.28144 0 U U
CT
OB -1.02183 -0.27652 I
OS -0.96081 -0.27652
OS -0.96081 -0.28636
OS -1.02183 -0.28636
OS -1.02183 -0.27652
OE
CE
PIN 3-13 S -0.83188 -0.26176 0 U U
CT
OB -0.86239 -0.25684 I
OS -0.80137 -0.25684
OS -0.80137 -0.26668
OS -0.86239 -0.26668
OS -0.86239 -0.25684
OE
CE
PIN 3-14 S -0.99132 -0.26176 0 U U
CT
OB -1.02183 -0.25684 I
OS -0.96081 -0.25684
OS -0.96081 -0.26668
OS -1.02183 -0.26668
OS -1.02183 -0.25684
OE
CE
PIN 3-15 S -0.83188 -0.24207 0 U U
CT
OB -0.86239 -0.23715 I
OS -0.80137 -0.23715
OS -0.80137 -0.24699
OS -0.86239 -0.24699
OS -0.86239 -0.23715
OE
CE
PIN 3-16 S -0.99132 -0.24207 0 U U
CT
OB -1.02183 -0.23715 I
OS -0.96081 -0.23715
OS -0.96081 -0.24699
OS -1.02183 -0.24699
OS -1.02183 -0.23715
OE
CE
PIN 3-17 S -0.83188 -0.22239 0 U U
CT
OB -0.86239 -0.21747 I
OS -0.80137 -0.21747
OS -0.80137 -0.22731
OS -0.86239 -0.22731
OS -0.86239 -0.21747
OE
CE
PIN 3-18 S -0.99132 -0.22239 0 U U
CT
OB -1.02183 -0.21747 I
OS -0.96081 -0.21747
OS -0.96081 -0.22731
OS -1.02183 -0.22731
OS -1.02183 -0.21747
OE
CE
PIN 3-19 S -0.83188 -0.2027 0 U U
CT
OB -0.86239 -0.19778 I
OS -0.80137 -0.19778
OS -0.80137 -0.20762
OS -0.86239 -0.20762
OS -0.86239 -0.19778
OE
CE
PIN 3-20 S -0.99132 -0.2027 0 U U
CT
OB -1.02183 -0.19778 I
OS -0.96081 -0.19778
OS -0.96081 -0.20762
OS -1.02183 -0.20762
OS -1.02183 -0.19778
OE
CE
PIN 3-21 S -0.83188 -0.18302 0 U U
CT
OB -0.86239 -0.1781 I
OS -0.80137 -0.1781
OS -0.80137 -0.18794
OS -0.86239 -0.18794
OS -0.86239 -0.1781
OE
CE
PIN 3-22 S -0.99132 -0.18302 0 U U
CT
OB -1.02183 -0.1781 I
OS -0.96081 -0.1781
OS -0.96081 -0.18794
OS -1.02183 -0.18794
OS -1.02183 -0.1781
OE
CE
PIN 3-23 S -0.83188 -0.16333 0 U U
CT
OB -0.86239 -0.15841 I
OS -0.80137 -0.15841
OS -0.80137 -0.16825
OS -0.86239 -0.16825
OS -0.86239 -0.15841
OE
CE
PIN 3-24 S -0.99132 -0.16333 0 U U
CT
OB -1.02183 -0.15841 I
OS -0.96081 -0.15841
OS -0.96081 -0.16825
OS -1.02183 -0.16825
OS -1.02183 -0.15841
OE
CE
PIN 3-25 S -0.83188 -0.14365 0 U U
CT
OB -0.86239 -0.13873 I
OS -0.80137 -0.13873
OS -0.80137 -0.14857
OS -0.86239 -0.14857
OS -0.86239 -0.13873
OE
CE
PIN 3-26 S -0.99132 -0.14365 0 U U
CT
OB -1.02183 -0.13873 I
OS -0.96081 -0.13873
OS -0.96081 -0.14857
OS -1.02183 -0.14857
OS -1.02183 -0.13873
OE
CE
PIN 3-27 S -0.83188 -0.12396 0 U U
CT
OB -0.86239 -0.11904 I
OS -0.80137 -0.11904
OS -0.80137 -0.12888
OS -0.86239 -0.12888
OS -0.86239 -0.11904
OE
CE
PIN 3-28 S -0.99132 -0.12396 0 U U
CT
OB -1.02183 -0.11904 I
OS -0.96081 -0.11904
OS -0.96081 -0.12888
OS -1.02183 -0.12888
OS -1.02183 -0.11904
OE
CE
PIN 3-29 S -0.83188 -0.10428 0 U U
CT
OB -0.86239 -0.09936 I
OS -0.80137 -0.09936
OS -0.80137 -0.1092
OS -0.86239 -0.1092
OS -0.86239 -0.09936
OE
CE
PIN 3-30 S -0.99132 -0.10428 0 U U
CT
OB -1.02183 -0.09936 I
OS -0.96081 -0.09936
OS -0.96081 -0.1092
OS -1.02183 -0.1092
OS -1.02183 -0.09936
OE
CE
PIN 3-31 S -0.83188 -0.08459 0 U U
CT
OB -0.86239 -0.07967 I
OS -0.80137 -0.07967
OS -0.80137 -0.08951
OS -0.86239 -0.08951
OS -0.86239 -0.07967
OE
CE
PIN 3-32 S -0.99132 -0.08459 0 U U
CT
OB -1.02183 -0.07967 I
OS -0.96081 -0.07967
OS -0.96081 -0.08951
OS -1.02183 -0.08951
OS -1.02183 -0.07967
OE
CE
PIN 3-33 S -0.83188 -0.06491 0 U U
CT
OB -0.86239 -0.05999 I
OS -0.80137 -0.05999
OS -0.80137 -0.06983
OS -0.86239 -0.06983
OS -0.86239 -0.05999
OE
CE
PIN 3-34 S -0.99132 -0.06491 0 U U
CT
OB -1.02183 -0.05999 I
OS -0.96081 -0.05999
OS -0.96081 -0.06983
OS -1.02183 -0.06983
OS -1.02183 -0.05999
OE
CE
PIN 3-35 S -0.83188 -0.04522 0 U U
CT
OB -0.86239 -0.0403 I
OS -0.80137 -0.0403
OS -0.80137 -0.05014
OS -0.86239 -0.05014
OS -0.86239 -0.0403
OE
CE
PIN 3-36 S -0.99132 -0.04522 0 U U
CT
OB -1.02183 -0.0403 I
OS -0.96081 -0.0403
OS -0.96081 -0.05014
OS -1.02183 -0.05014
OS -1.02183 -0.0403
OE
CE
PIN 3-37 S -0.83188 -0.02554 0 U U
CT
OB -0.86239 -0.02062 I
OS -0.80137 -0.02062
OS -0.80137 -0.03046
OS -0.86239 -0.03046
OS -0.86239 -0.02062
OE
CE
PIN 3-38 S -0.99132 -0.02554 0 U U
CT
OB -1.02183 -0.02062 I
OS -0.96081 -0.02062
OS -0.96081 -0.03046
OS -1.02183 -0.03046
OS -1.02183 -0.02062
OE
CE
PIN 3-39 S -0.83188 -0.00585 0 U U
CT
OB -0.86239 -0.00093 I
OS -0.80137 -0.00093
OS -0.80137 -0.01077
OS -0.86239 -0.01077
OS -0.86239 -0.00093
OE
CE
PIN 3-40 S -0.99132 -0.00585 0 U U
CT
OB -1.02183 -0.00093 I
OS -0.96081 -0.00093
OS -0.96081 -0.01077
OS -1.02183 -0.01077
OS -1.02183 -0.00093
OE
CE
PIN 3-41 S -0.83188 0.01383 0 U U
CT
OB -0.86239 0.01875 I
OS -0.80137 0.01875
OS -0.80137 0.00891
OS -0.86239 0.00891
OS -0.86239 0.01875
OE
CE
PIN 3-42 S -0.99132 0.01383 0 U U
CT
OB -1.02183 0.01875 I
OS -0.96081 0.01875
OS -0.96081 0.00891
OS -1.02183 0.00891
OS -1.02183 0.01875
OE
CE
PIN 3-43 S -0.83188 0.03352 0 U U
CT
OB -0.86239 0.03844 I
OS -0.80137 0.03844
OS -0.80137 0.0286
OS -0.86239 0.0286
OS -0.86239 0.03844
OE
CE
PIN 3-44 S -0.99132 0.03352 0 U U
CT
OB -1.02183 0.03844 I
OS -0.96081 0.03844
OS -0.96081 0.0286
OS -1.02183 0.0286
OS -1.02183 0.03844
OE
CE
PIN 3-45 S -0.83188 0.0532 0 U U
CT
OB -0.86239 0.05812 I
OS -0.80137 0.05812
OS -0.80137 0.04828
OS -0.86239 0.04828
OS -0.86239 0.05812
OE
CE
PIN 3-46 S -0.99132 0.0532 0 U U
CT
OB -1.02183 0.05812 I
OS -0.96081 0.05812
OS -0.96081 0.04828
OS -1.02183 0.04828
OS -1.02183 0.05812
OE
CE
PIN 3-47 S -0.83188 0.07289 0 U U
CT
OB -0.86239 0.07781 I
OS -0.80137 0.07781
OS -0.80137 0.06797
OS -0.86239 0.06797
OS -0.86239 0.07781
OE
CE
PIN 3-48 S -0.99132 0.07289 0 U U
CT
OB -1.02183 0.07781 I
OS -0.96081 0.07781
OS -0.96081 0.06797
OS -1.02183 0.06797
OS -1.02183 0.07781
OE
CE
PIN 3-49 S -0.83188 0.09257 0 U U
CT
OB -0.86239 0.09749 I
OS -0.80137 0.09749
OS -0.80137 0.08765
OS -0.86239 0.08765
OS -0.86239 0.09749
OE
CE
PIN 3-50 S -0.99132 0.09257 0 U U
CT
OB -1.02183 0.09749 I
OS -0.96081 0.09749
OS -0.96081 0.08765
OS -1.02183 0.08765
OS -1.02183 0.09749
OE
CE
PIN 3-51 S -0.83188 0.11226 0 U U
CT
OB -0.86239 0.11718 I
OS -0.80137 0.11718
OS -0.80137 0.10734
OS -0.86239 0.10734
OS -0.86239 0.11718
OE
CE
PIN 3-52 S -0.99132 0.11226 0 U U
CT
OB -1.02183 0.11718 I
OS -0.96081 0.11718
OS -0.96081 0.10734
OS -1.02183 0.10734
OS -1.02183 0.11718
OE
CE
PIN 3-53 S -0.83188 0.13194 0 U U
CT
OB -0.86239 0.13686 I
OS -0.80137 0.13686
OS -0.80137 0.12702
OS -0.86239 0.12702
OS -0.86239 0.13686
OE
CE
PIN 3-54 S -0.99132 0.13194 0 U U
CT
OB -1.02183 0.13686 I
OS -0.96081 0.13686
OS -0.96081 0.12702
OS -1.02183 0.12702
OS -1.02183 0.13686
OE
CE
PIN 3-55 S -0.83188 0.15163 0 U U
CT
OB -0.86239 0.15655 I
OS -0.80137 0.15655
OS -0.80137 0.14671
OS -0.86239 0.14671
OS -0.86239 0.15655
OE
CE
PIN 3-56 S -0.99132 0.15163 0 U U
CT
OB -1.02183 0.15655 I
OS -0.96081 0.15655
OS -0.96081 0.14671
OS -1.02183 0.14671
OS -1.02183 0.15655
OE
CE
PIN 3-57 S -0.83188 0.17131 0 U U
CT
OB -0.86239 0.17623 I
OS -0.80137 0.17623
OS -0.80137 0.16639
OS -0.86239 0.16639
OS -0.86239 0.17623
OE
CE
PIN 3-58 S -0.99132 0.17131 0 U U
CT
OB -1.02183 0.17623 I
OS -0.96081 0.17623
OS -0.96081 0.16639
OS -1.02183 0.16639
OS -1.02183 0.17623
OE
CE
PIN 3-59 S -0.83188 0.191 0 U U
CT
OB -0.86239 0.19592 I
OS -0.80137 0.19592
OS -0.80137 0.18608
OS -0.86239 0.18608
OS -0.86239 0.19592
OE
CE
PIN 3-60 S -0.99132 0.191 0 U U
CT
OB -1.02183 0.19592 I
OS -0.96081 0.19592
OS -0.96081 0.18608
OS -1.02183 0.18608
OS -1.02183 0.19592
OE
CE
PIN 3-61 S -0.83188 0.21068 0 U U
CT
OB -0.86239 0.2156 I
OS -0.80137 0.2156
OS -0.80137 0.20576
OS -0.86239 0.20576
OS -0.86239 0.2156
OE
CE
PIN 3-62 S -0.99132 0.21068 0 U U
CT
OB -1.02183 0.2156 I
OS -0.96081 0.2156
OS -0.96081 0.20576
OS -1.02183 0.20576
OS -1.02183 0.2156
OE
CE
PIN 3-63 S -0.83188 0.23037 0 U U
CT
OB -0.86239 0.23529 I
OS -0.80137 0.23529
OS -0.80137 0.22545
OS -0.86239 0.22545
OS -0.86239 0.23529
OE
CE
PIN 3-64 S -0.99132 0.23037 0 U U
CT
OB -1.02183 0.23529 I
OS -0.96081 0.23529
OS -0.96081 0.22545
OS -1.02183 0.22545
OS -1.02183 0.23529
OE
CE
PIN 3-65 S -0.83188 0.25005 0 U U
CT
OB -0.86239 0.25497 I
OS -0.80137 0.25497
OS -0.80137 0.24513
OS -0.86239 0.24513
OS -0.86239 0.25497
OE
CE
PIN 3-66 S -0.99132 0.25005 0 U U
CT
OB -1.02183 0.25497 I
OS -0.96081 0.25497
OS -0.96081 0.24513
OS -1.02183 0.24513
OS -1.02183 0.25497
OE
CE
PIN 3-67 S -0.83188 0.26974 0 U U
CT
OB -0.86239 0.27466 I
OS -0.80137 0.27466
OS -0.80137 0.26482
OS -0.86239 0.26482
OS -0.86239 0.27466
OE
CE
PIN 3-68 S -0.99132 0.26974 0 U U
CT
OB -1.02183 0.27466 I
OS -0.96081 0.27466
OS -0.96081 0.26482
OS -1.02183 0.26482
OS -1.02183 0.27466
OE
CE
PIN 3-69 S -0.83188 0.28942 0 U U
CT
OB -0.86239 0.29434 I
OS -0.80137 0.29434
OS -0.80137 0.2845
OS -0.86239 0.2845
OS -0.86239 0.29434
OE
CE
PIN 3-70 S -0.99132 0.28942 0 U U
CT
OB -1.02183 0.29434 I
OS -0.96081 0.29434
OS -0.96081 0.2845
OS -1.02183 0.2845
OS -1.02183 0.29434
OE
CE
PIN 3-71 S -0.83188 0.30911 0 U U
CT
OB -0.86239 0.31403 I
OS -0.80137 0.31403
OS -0.80137 0.30419
OS -0.86239 0.30419
OS -0.86239 0.31403
OE
CE
PIN 3-72 S -0.99132 0.30911 0 U U
CT
OB -1.02183 0.31403 I
OS -0.96081 0.31403
OS -0.96081 0.30419
OS -1.02183 0.30419
OS -1.02183 0.31403
OE
CE
PIN 3-73 S -0.83188 0.32879 0 U U
CT
OB -0.86239 0.33371 I
OS -0.80137 0.33371
OS -0.80137 0.32387
OS -0.86239 0.32387
OS -0.86239 0.33371
OE
CE
PIN 3-74 S -0.99132 0.32879 0 U U
CT
OB -1.02183 0.33371 I
OS -0.96081 0.33371
OS -0.96081 0.32387
OS -1.02183 0.32387
OS -1.02183 0.33371
OE
CE
PIN 3-75 S -0.83188 0.34848 0 U U
CT
OB -0.86239 0.3534 I
OS -0.80137 0.3534
OS -0.80137 0.34356
OS -0.86239 0.34356
OS -0.86239 0.3534
OE
CE
PIN 3-76 S -0.99132 0.34848 0 U U
CT
OB -1.02183 0.3534 I
OS -0.96081 0.3534
OS -0.96081 0.34356
OS -1.02183 0.34356
OS -1.02183 0.3534
OE
CE
PIN 3-77 S -0.83188 0.36816 0 U U
CT
OB -0.86239 0.37308 I
OS -0.80137 0.37308
OS -0.80137 0.36324
OS -0.86239 0.36324
OS -0.86239 0.37308
OE
CE
PIN 3-78 S -0.99132 0.36816 0 U U
CT
OB -1.02183 0.37308 I
OS -0.96081 0.37308
OS -0.96081 0.36324
OS -1.02183 0.36324
OS -1.02183 0.37308
OE
CE
PIN 3-79 S -0.83188 0.38785 0 U U
CT
OB -0.86239 0.39277 I
OS -0.80137 0.39277
OS -0.80137 0.38293
OS -0.86239 0.38293
OS -0.86239 0.39277
OE
CE
PIN 3-80 S -0.99132 0.38785 0 U U
CT
OB -1.02183 0.39277 I
OS -0.96081 0.39277
OS -0.96081 0.38293
OS -1.02183 0.38293
OS -1.02183 0.39277
OE
CE
PIN 4-1 S 0.37227 -0.66123 0 U U
CT
OB 0.36735 -0.63072 I
OS 0.37719 -0.63072
OS 0.37719 -0.69174
OS 0.36735 -0.69174
OS 0.36735 -0.63072
OE
CE
PIN 4-2 S 0.37227 -0.82067 0 U U
CT
OB 0.36735 -0.79016 I
OS 0.37719 -0.79016
OS 0.37719 -0.85118
OS 0.36735 -0.85118
OS 0.36735 -0.79016
OE
CE
PIN 4-3 S 0.35258 -0.66123 0 U U
CT
OB 0.34766 -0.63072 I
OS 0.3575 -0.63072
OS 0.3575 -0.69174
OS 0.34766 -0.69174
OS 0.34766 -0.63072
OE
CE
PIN 4-4 S 0.35258 -0.82067 0 U U
CT
OB 0.34766 -0.79016 I
OS 0.3575 -0.79016
OS 0.3575 -0.85118
OS 0.34766 -0.85118
OS 0.34766 -0.79016
OE
CE
PIN 4-5 S 0.3329 -0.66123 0 U U
CT
OB 0.32798 -0.63072 I
OS 0.33782 -0.63072
OS 0.33782 -0.69174
OS 0.32798 -0.69174
OS 0.32798 -0.63072
OE
CE
PIN 4-6 S 0.3329 -0.82067 0 U U
CT
OB 0.32798 -0.79016 I
OS 0.33782 -0.79016
OS 0.33782 -0.85118
OS 0.32798 -0.85118
OS 0.32798 -0.79016
OE
CE
PIN 4-7 S 0.31321 -0.66123 0 U U
CT
OB 0.30829 -0.63072 I
OS 0.31813 -0.63072
OS 0.31813 -0.69174
OS 0.30829 -0.69174
OS 0.30829 -0.63072
OE
CE
PIN 4-8 S 0.31321 -0.82067 0 U U
CT
OB 0.30829 -0.79016 I
OS 0.31813 -0.79016
OS 0.31813 -0.85118
OS 0.30829 -0.85118
OS 0.30829 -0.79016
OE
CE
PIN 4-9 S 0.29353 -0.66123 0 U U
CT
OB 0.28861 -0.63072 I
OS 0.29845 -0.63072
OS 0.29845 -0.69174
OS 0.28861 -0.69174
OS 0.28861 -0.63072
OE
CE
PIN 4-10 S 0.29353 -0.82067 0 U U
CT
OB 0.28861 -0.79016 I
OS 0.29845 -0.79016
OS 0.29845 -0.85118
OS 0.28861 -0.85118
OS 0.28861 -0.79016
OE
CE
PIN 4-11 S 0.27384 -0.66123 0 U U
CT
OB 0.26892 -0.63072 I
OS 0.27876 -0.63072
OS 0.27876 -0.69174
OS 0.26892 -0.69174
OS 0.26892 -0.63072
OE
CE
PIN 4-12 S 0.27384 -0.82067 0 U U
CT
OB 0.26892 -0.79016 I
OS 0.27876 -0.79016
OS 0.27876 -0.85118
OS 0.26892 -0.85118
OS 0.26892 -0.79016
OE
CE
PIN 4-13 S 0.25416 -0.66123 0 U U
CT
OB 0.24924 -0.63072 I
OS 0.25908 -0.63072
OS 0.25908 -0.69174
OS 0.24924 -0.69174
OS 0.24924 -0.63072
OE
CE
PIN 4-14 S 0.25416 -0.82067 0 U U
CT
OB 0.24924 -0.79016 I
OS 0.25908 -0.79016
OS 0.25908 -0.85118
OS 0.24924 -0.85118
OS 0.24924 -0.79016
OE
CE
PIN 4-15 S 0.23447 -0.66123 0 U U
CT
OB 0.22955 -0.63072 I
OS 0.23939 -0.63072
OS 0.23939 -0.69174
OS 0.22955 -0.69174
OS 0.22955 -0.63072
OE
CE
PIN 4-16 S 0.23447 -0.82067 0 U U
CT
OB 0.22955 -0.79016 I
OS 0.23939 -0.79016
OS 0.23939 -0.85118
OS 0.22955 -0.85118
OS 0.22955 -0.79016
OE
CE
PIN 4-17 S 0.21479 -0.66123 0 U U
CT
OB 0.20987 -0.63072 I
OS 0.21971 -0.63072
OS 0.21971 -0.69174
OS 0.20987 -0.69174
OS 0.20987 -0.63072
OE
CE
PIN 4-18 S 0.21479 -0.82067 0 U U
CT
OB 0.20987 -0.79016 I
OS 0.21971 -0.79016
OS 0.21971 -0.85118
OS 0.20987 -0.85118
OS 0.20987 -0.79016
OE
CE
PIN 4-19 S 0.1951 -0.66123 0 U U
CT
OB 0.19018 -0.63072 I
OS 0.20002 -0.63072
OS 0.20002 -0.69174
OS 0.19018 -0.69174
OS 0.19018 -0.63072
OE
CE
PIN 4-20 S 0.1951 -0.82067 0 U U
CT
OB 0.19018 -0.79016 I
OS 0.20002 -0.79016
OS 0.20002 -0.85118
OS 0.19018 -0.85118
OS 0.19018 -0.79016
OE
CE
PIN 4-21 S 0.17542 -0.66123 0 U U
CT
OB 0.1705 -0.63072 I
OS 0.18034 -0.63072
OS 0.18034 -0.69174
OS 0.1705 -0.69174
OS 0.1705 -0.63072
OE
CE
PIN 4-22 S 0.17542 -0.82067 0 U U
CT
OB 0.1705 -0.79016 I
OS 0.18034 -0.79016
OS 0.18034 -0.85118
OS 0.1705 -0.85118
OS 0.1705 -0.79016
OE
CE
PIN 4-23 S 0.15573 -0.66123 0 U U
CT
OB 0.15081 -0.63072 I
OS 0.16065 -0.63072
OS 0.16065 -0.69174
OS 0.15081 -0.69174
OS 0.15081 -0.63072
OE
CE
PIN 4-24 S 0.15573 -0.82067 0 U U
CT
OB 0.15081 -0.79016 I
OS 0.16065 -0.79016
OS 0.16065 -0.85118
OS 0.15081 -0.85118
OS 0.15081 -0.79016
OE
CE
PIN 4-25 S 0.13605 -0.66123 0 U U
CT
OB 0.13113 -0.63072 I
OS 0.14097 -0.63072
OS 0.14097 -0.69174
OS 0.13113 -0.69174
OS 0.13113 -0.63072
OE
CE
PIN 4-26 S 0.13605 -0.82067 0 U U
CT
OB 0.13113 -0.79016 I
OS 0.14097 -0.79016
OS 0.14097 -0.85118
OS 0.13113 -0.85118
OS 0.13113 -0.79016
OE
CE
PIN 4-27 S 0.11636 -0.66123 0 U U
CT
OB 0.11144 -0.63072 I
OS 0.12128 -0.63072
OS 0.12128 -0.69174
OS 0.11144 -0.69174
OS 0.11144 -0.63072
OE
CE
PIN 4-28 S 0.11636 -0.82067 0 U U
CT
OB 0.11144 -0.79016 I
OS 0.12128 -0.79016
OS 0.12128 -0.85118
OS 0.11144 -0.85118
OS 0.11144 -0.79016
OE
CE
PIN 4-29 S 0.09668 -0.66123 0 U U
CT
OB 0.09176 -0.63072 I
OS 0.1016 -0.63072
OS 0.1016 -0.69174
OS 0.09176 -0.69174
OS 0.09176 -0.63072
OE
CE
PIN 4-30 S 0.09668 -0.82067 0 U U
CT
OB 0.09176 -0.79016 I
OS 0.1016 -0.79016
OS 0.1016 -0.85118
OS 0.09176 -0.85118
OS 0.09176 -0.79016
OE
CE
PIN 4-31 S 0.07699 -0.66123 0 U U
CT
OB 0.07207 -0.63072 I
OS 0.08191 -0.63072
OS 0.08191 -0.69174
OS 0.07207 -0.69174
OS 0.07207 -0.63072
OE
CE
PIN 4-32 S 0.07699 -0.82067 0 U U
CT
OB 0.07207 -0.79016 I
OS 0.08191 -0.79016
OS 0.08191 -0.85118
OS 0.07207 -0.85118
OS 0.07207 -0.79016
OE
CE
PIN 4-33 S 0.05731 -0.66123 0 U U
CT
OB 0.05239 -0.63072 I
OS 0.06223 -0.63072
OS 0.06223 -0.69174
OS 0.05239 -0.69174
OS 0.05239 -0.63072
OE
CE
PIN 4-34 S 0.05731 -0.82067 0 U U
CT
OB 0.05239 -0.79016 I
OS 0.06223 -0.79016
OS 0.06223 -0.85118
OS 0.05239 -0.85118
OS 0.05239 -0.79016
OE
CE
PIN 4-35 S 0.03762 -0.66123 0 U U
CT
OB 0.0327 -0.63072 I
OS 0.04254 -0.63072
OS 0.04254 -0.69174
OS 0.0327 -0.69174
OS 0.0327 -0.63072
OE
CE
PIN 4-36 S 0.03762 -0.82067 0 U U
CT
OB 0.0327 -0.79016 I
OS 0.04254 -0.79016
OS 0.04254 -0.85118
OS 0.0327 -0.85118
OS 0.0327 -0.79016
OE
CE
PIN 4-37 S 0.01794 -0.66123 0 U U
CT
OB 0.01302 -0.63072 I
OS 0.02286 -0.63072
OS 0.02286 -0.69174
OS 0.01302 -0.69174
OS 0.01302 -0.63072
OE
CE
PIN 4-38 S 0.01794 -0.82067 0 U U
CT
OB 0.01302 -0.79016 I
OS 0.02286 -0.79016
OS 0.02286 -0.85118
OS 0.01302 -0.85118
OS 0.01302 -0.79016
OE
CE
PIN 4-39 S -0.00175 -0.66123 0 U U
CT
OB -0.00667 -0.63072 I
OS 0.00317 -0.63072
OS 0.00317 -0.69174
OS -0.00667 -0.69174
OS -0.00667 -0.63072
OE
CE
PIN 4-40 S -0.00175 -0.82067 0 U U
CT
OB -0.00667 -0.79016 I
OS 0.00317 -0.79016
OS 0.00317 -0.85118
OS -0.00667 -0.85118
OS -0.00667 -0.79016
OE
CE
PIN 4-41 S -0.02143 -0.66123 0 U U
CT
OB -0.02635 -0.63072 I
OS -0.01651 -0.63072
OS -0.01651 -0.69174
OS -0.02635 -0.69174
OS -0.02635 -0.63072
OE
CE
PIN 4-42 S -0.02143 -0.82067 0 U U
CT
OB -0.02635 -0.79016 I
OS -0.01651 -0.79016
OS -0.01651 -0.85118
OS -0.02635 -0.85118
OS -0.02635 -0.79016
OE
CE
PIN 4-43 S -0.04112 -0.66123 0 U U
CT
OB -0.04604 -0.63072 I
OS -0.0362 -0.63072
OS -0.0362 -0.69174
OS -0.04604 -0.69174
OS -0.04604 -0.63072
OE
CE
PIN 4-44 S -0.04112 -0.82067 0 U U
CT
OB -0.04604 -0.79016 I
OS -0.0362 -0.79016
OS -0.0362 -0.85118
OS -0.04604 -0.85118
OS -0.04604 -0.79016
OE
CE
PIN 4-45 S -0.0608 -0.66123 0 U U
CT
OB -0.06572 -0.63072 I
OS -0.05588 -0.63072
OS -0.05588 -0.69174
OS -0.06572 -0.69174
OS -0.06572 -0.63072
OE
CE
PIN 4-46 S -0.0608 -0.82067 0 U U
CT
OB -0.06572 -0.79016 I
OS -0.05588 -0.79016
OS -0.05588 -0.85118
OS -0.06572 -0.85118
OS -0.06572 -0.79016
OE
CE
PIN 4-47 S -0.08049 -0.66123 0 U U
CT
OB -0.08541 -0.63072 I
OS -0.07557 -0.63072
OS -0.07557 -0.69174
OS -0.08541 -0.69174
OS -0.08541 -0.63072
OE
CE
PIN 4-48 S -0.08049 -0.82067 0 U U
CT
OB -0.08541 -0.79016 I
OS -0.07557 -0.79016
OS -0.07557 -0.85118
OS -0.08541 -0.85118
OS -0.08541 -0.79016
OE
CE
PIN 4-49 S -0.10017 -0.66123 0 U U
CT
OB -0.10509 -0.63072 I
OS -0.09525 -0.63072
OS -0.09525 -0.69174
OS -0.10509 -0.69174
OS -0.10509 -0.63072
OE
CE
PIN 4-50 S -0.10017 -0.82067 0 U U
CT
OB -0.10509 -0.79016 I
OS -0.09525 -0.79016
OS -0.09525 -0.85118
OS -0.10509 -0.85118
OS -0.10509 -0.79016
OE
CE
PIN 4-51 S -0.11986 -0.66123 0 U U
CT
OB -0.12478 -0.63072 I
OS -0.11494 -0.63072
OS -0.11494 -0.69174
OS -0.12478 -0.69174
OS -0.12478 -0.63072
OE
CE
PIN 4-52 S -0.11986 -0.82067 0 U U
CT
OB -0.12478 -0.79016 I
OS -0.11494 -0.79016
OS -0.11494 -0.85118
OS -0.12478 -0.85118
OS -0.12478 -0.79016
OE
CE
PIN 4-53 S -0.13954 -0.66123 0 U U
CT
OB -0.14446 -0.63072 I
OS -0.13462 -0.63072
OS -0.13462 -0.69174
OS -0.14446 -0.69174
OS -0.14446 -0.63072
OE
CE
PIN 4-54 S -0.13954 -0.82067 0 U U
CT
OB -0.14446 -0.79016 I
OS -0.13462 -0.79016
OS -0.13462 -0.85118
OS -0.14446 -0.85118
OS -0.14446 -0.79016
OE
CE
PIN 4-55 S -0.15923 -0.66123 0 U U
CT
OB -0.16415 -0.63072 I
OS -0.15431 -0.63072
OS -0.15431 -0.69174
OS -0.16415 -0.69174
OS -0.16415 -0.63072
OE
CE
PIN 4-56 S -0.15923 -0.82067 0 U U
CT
OB -0.16415 -0.79016 I
OS -0.15431 -0.79016
OS -0.15431 -0.85118
OS -0.16415 -0.85118
OS -0.16415 -0.79016
OE
CE
PIN 4-57 S -0.17891 -0.66123 0 U U
CT
OB -0.18383 -0.63072 I
OS -0.17399 -0.63072
OS -0.17399 -0.69174
OS -0.18383 -0.69174
OS -0.18383 -0.63072
OE
CE
PIN 4-58 S -0.17891 -0.82067 0 U U
CT
OB -0.18383 -0.79016 I
OS -0.17399 -0.79016
OS -0.17399 -0.85118
OS -0.18383 -0.85118
OS -0.18383 -0.79016
OE
CE
PIN 4-59 S -0.1986 -0.66123 0 U U
CT
OB -0.20352 -0.63072 I
OS -0.19368 -0.63072
OS -0.19368 -0.69174
OS -0.20352 -0.69174
OS -0.20352 -0.63072
OE
CE
PIN 4-60 S -0.1986 -0.82067 0 U U
CT
OB -0.20352 -0.79016 I
OS -0.19368 -0.79016
OS -0.19368 -0.85118
OS -0.20352 -0.85118
OS -0.20352 -0.79016
OE
CE
PIN 4-61 S -0.21828 -0.66123 0 U U
CT
OB -0.2232 -0.63072 I
OS -0.21336 -0.63072
OS -0.21336 -0.69174
OS -0.2232 -0.69174
OS -0.2232 -0.63072
OE
CE
PIN 4-62 S -0.21828 -0.82067 0 U U
CT
OB -0.2232 -0.79016 I
OS -0.21336 -0.79016
OS -0.21336 -0.85118
OS -0.2232 -0.85118
OS -0.2232 -0.79016
OE
CE
PIN 4-63 S -0.23797 -0.66123 0 U U
CT
OB -0.24289 -0.63072 I
OS -0.23305 -0.63072
OS -0.23305 -0.69174
OS -0.24289 -0.69174
OS -0.24289 -0.63072
OE
CE
PIN 4-64 S -0.23797 -0.82067 0 U U
CT
OB -0.24289 -0.79016 I
OS -0.23305 -0.79016
OS -0.23305 -0.85118
OS -0.24289 -0.85118
OS -0.24289 -0.79016
OE
CE
PIN 4-65 S -0.25765 -0.66123 0 U U
CT
OB -0.26257 -0.63072 I
OS -0.25273 -0.63072
OS -0.25273 -0.69174
OS -0.26257 -0.69174
OS -0.26257 -0.63072
OE
CE
PIN 4-66 S -0.25765 -0.82067 0 U U
CT
OB -0.26257 -0.79016 I
OS -0.25273 -0.79016
OS -0.25273 -0.85118
OS -0.26257 -0.85118
OS -0.26257 -0.79016
OE
CE
PIN 4-67 S -0.27734 -0.66123 0 U U
CT
OB -0.28226 -0.63072 I
OS -0.27242 -0.63072
OS -0.27242 -0.69174
OS -0.28226 -0.69174
OS -0.28226 -0.63072
OE
CE
PIN 4-68 S -0.27734 -0.82067 0 U U
CT
OB -0.28226 -0.79016 I
OS -0.27242 -0.79016
OS -0.27242 -0.85118
OS -0.28226 -0.85118
OS -0.28226 -0.79016
OE
CE
PIN 4-69 S -0.29702 -0.66123 0 U U
CT
OB -0.30194 -0.63072 I
OS -0.2921 -0.63072
OS -0.2921 -0.69174
OS -0.30194 -0.69174
OS -0.30194 -0.63072
OE
CE
PIN 4-70 S -0.29702 -0.82067 0 U U
CT
OB -0.30194 -0.79016 I
OS -0.2921 -0.79016
OS -0.2921 -0.85118
OS -0.30194 -0.85118
OS -0.30194 -0.79016
OE
CE
PIN 4-71 S -0.31671 -0.66123 0 U U
CT
OB -0.32163 -0.63072 I
OS -0.31179 -0.63072
OS -0.31179 -0.69174
OS -0.32163 -0.69174
OS -0.32163 -0.63072
OE
CE
PIN 4-72 S -0.31671 -0.82067 0 U U
CT
OB -0.32163 -0.79016 I
OS -0.31179 -0.79016
OS -0.31179 -0.85118
OS -0.32163 -0.85118
OS -0.32163 -0.79016
OE
CE
PIN 4-73 S -0.33639 -0.66123 0 U U
CT
OB -0.34131 -0.63072 I
OS -0.33147 -0.63072
OS -0.33147 -0.69174
OS -0.34131 -0.69174
OS -0.34131 -0.63072
OE
CE
PIN 4-74 S -0.33639 -0.82067 0 U U
CT
OB -0.34131 -0.79016 I
OS -0.33147 -0.79016
OS -0.33147 -0.85118
OS -0.34131 -0.85118
OS -0.34131 -0.79016
OE
CE
PIN 4-75 S -0.35608 -0.66123 0 U U
CT
OB -0.361 -0.63072 I
OS -0.35116 -0.63072
OS -0.35116 -0.69174
OS -0.361 -0.69174
OS -0.361 -0.63072
OE
CE
PIN 4-76 S -0.35608 -0.82067 0 U U
CT
OB -0.361 -0.79016 I
OS -0.35116 -0.79016
OS -0.35116 -0.85118
OS -0.361 -0.85118
OS -0.361 -0.79016
OE
CE
PIN 4-77 S -0.37576 -0.66123 0 U U
CT
OB -0.38068 -0.63072 I
OS -0.37084 -0.63072
OS -0.37084 -0.69174
OS -0.38068 -0.69174
OS -0.38068 -0.63072
OE
CE
PIN 4-78 S -0.37576 -0.82067 0 U U
CT
OB -0.38068 -0.79016 I
OS -0.37084 -0.79016
OS -0.37084 -0.85118
OS -0.38068 -0.85118
OS -0.38068 -0.79016
OE
CE
PIN 4-79 S -0.39545 -0.66123 0 U U
CT
OB -0.40037 -0.63072 I
OS -0.39053 -0.63072
OS -0.39053 -0.69174
OS -0.40037 -0.69174
OS -0.40037 -0.63072
OE
CE
PIN 4-80 S -0.39545 -0.82067 0 U U
CT
OB -0.40037 -0.79016 I
OS -0.39053 -0.79016
OS -0.39053 -0.85118
OS -0.40037 -0.85118
OS -0.40037 -0.79016
OE
CE
PIN 81 S 0.96331 0.4321 0 U U
CT
OB 0.929845 0.458675 I
OS 0.996775 0.458675
OS 0.996775 0.405525
OS 0.929845 0.405525
OS 0.929845 0.458675
OE
CE
PIN 81 S -0.43975 0.73899 0 U U
CT
OB -0.466325 0.772455 I
OS -0.413175 0.772455
OS -0.413175 0.705525
OS -0.466325 0.705525
OS -0.466325 0.772455
OE
CE
PIN 81 S -0.9116 -0.42416 0 U U
CT
OB -0.945065 -0.397585 I
OS -0.878135 -0.397585
OS -0.878135 -0.450735
OS -0.945065 -0.450735
OS -0.945065 -0.397585
OE
CE
PIN 81 S 0.41656 -0.74095 0 U U
CT
OB 0.389985 -0.707485 I
OS 0.443135 -0.707485
OS 0.443135 -0.774415
OS 0.389985 -0.774415
OS 0.389985 -0.707485
OE
CE
PIN 82 T 0.96331 0.39765 0 U U
CR 0.96331 0.39765 0.01083
PIN 82 T -0.4053 0.73899 0 U U
CR -0.4053 0.73899 0.01083
PIN 82 T -0.9116 -0.38971 0 U U
CR -0.9116 -0.38971 0.01083
PIN 82 T 0.38211 -0.74095 0 U U
CR 0.38211 -0.74095 0.01083
PIN 83 T 0.96331 -0.38975 0 U U
CR 0.96331 -0.38975 0.01083
PIN 83 T -0.9116 0.39769 0 U U
CR -0.9116 0.39769 0.01083
PIN 83 T -0.40529 -0.74095 0 U U
CR -0.40529 -0.74095 0.01083
PIN 83 T 0.3821 0.73899 0 U U
CR 0.3821 0.73899 0.01083
PIN 84 S 0.96331 -0.4242 0 U U
CT
OB 0.929845 -0.397625 I
OS 0.996775 -0.397625
OS 0.996775 -0.450775
OS 0.929845 -0.450775
OS 0.929845 -0.397625
OE
CE
PIN 84 S -0.9116 0.43214 0 U U
CT
OB -0.945065 0.458715 I
OS -0.878135 0.458715
OS -0.878135 0.405565
OS -0.945065 0.405565
OS -0.945065 0.458715
OE
CE
PIN 84 S -0.43974 -0.74095 0 U U
CT
OB -0.466315 -0.707485 I
OS -0.413165 -0.707485
OS -0.413165 -0.774415
OS -0.466315 -0.774415
OS -0.466315 -0.707485
OE
CE
PIN 84 S 0.41655 0.73899 0 U U
CT
OB 0.389975 0.772455 I
OS 0.443125 0.772455
OS 0.443125 0.705525
OS 0.389975 0.705525
OS 0.389975 0.772455
OE
CE
#
# PKG 3
PKG AMPHENOL-901-143-6RFX 0.1414214 -0.16 -0.16 0.3558016 0.16
CT
OB 0.3558016 -0.1377888 I
OS -0.1377888 -0.1377888
OS -0.1377888 0.1378016
OS 0.3558016 0.1378016
OS 0.3558016 -0.1377888
OE
CE
PIN 1 T 0 0 0 U U
CR 0 0 0.056
PIN 2 T -0.1 -0.1 0 U U
CR -0.1 -0.1 0.06
PIN 3 T -0.1 0.1 0 U U
CR -0.1 0.1 0.06
PIN 4 T 0.1 0.1 0 U U
CR 0.1 0.1 0.06
PIN 5 T 0.1 -0.1 0 U U
CR 0.1 -0.1 0.06
#
# PKG 4
PKG BMP388 0.019685 -0.0354134 -0.0354528 0.0354134 0.0354528
RC -0.0354134 -0.0354528 0.0708268 0.0709056
PIN 1 S 0.0098425 0.0300394 0 U U
CT
OB 0.0049425 0.0246394 I
OS 0.0049425 0.0354394
OS 0.0147425 0.0354394
OS 0.0147425 0.0246394
OS 0.0049425 0.0246394
OE
CE
PIN 2 S -0.0098425 0.0300394 0 U U
CT
OB -0.0147425 0.0246394 I
OS -0.0147425 0.0354394
OS -0.0049425 0.0354394
OS -0.0049425 0.0246394
OS -0.0147425 0.0246394
OE
CE
PIN 3 S -0.03 0.019685 0 U U
CT
OB -0.0354134 0.02460625 I
OS -0.0245866 0.02460625
OS -0.0245866 0.01476375
OS -0.0354134 0.01476375
OS -0.0354134 0.02460625
OE
CE
PIN 4 S -0.03 0 0 U U
CT
OB -0.0354134 0.00492125 I
OS -0.0245866 0.00492125
OS -0.0245866 -0.00492125
OS -0.0354134 -0.00492125
OS -0.0354134 0.00492125
OE
CE
PIN 5 S -0.03 -0.019685 0 U U
CT
OB -0.0354134 -0.01476375 I
OS -0.0245866 -0.01476375
OS -0.0245866 -0.02460625
OS -0.0354134 -0.02460625
OS -0.0354134 -0.01476375
OE
CE
PIN 6 S -0.0098425 -0.0300394 0 U U
CT
OB -0.0147425 -0.0354394 I
OS -0.0147425 -0.0246394
OS -0.0049425 -0.0246394
OS -0.0049425 -0.0354394
OS -0.0147425 -0.0354394
OE
CE
PIN 7 S 0.0098425 -0.0300394 0 U U
CT
OB 0.0049425 -0.0354394 I
OS 0.0049425 -0.0246394
OS 0.0147425 -0.0246394
OS 0.0147425 -0.0354394
OS 0.0049425 -0.0354394
OE
CE
PIN 8 S 0.03 -0.019685 0 U U
CT
OB 0.0245866 -0.01476375 I
OS 0.0354134 -0.01476375
OS 0.0354134 -0.02460625
OS 0.0245866 -0.02460625
OS 0.0245866 -0.01476375
OE
CE
PIN 9 S 0.03 0 0 U U
CT
OB 0.0245866 0.00492125 I
OS 0.0354134 0.00492125
OS 0.0354134 -0.00492125
OS 0.0245866 -0.00492125
OS 0.0245866 0.00492125
OE
CE
PIN 10 S 0.03 0.019685 0 U U
CT
OB 0.0245866 0.02460625 I
OS 0.0354134 0.02460625
OS 0.0354134 0.01476375
OS 0.0245866 0.01476375
OS 0.0245866 0.02460625
OE
CE
#
# PKG 5
PKG CAPC1005X06N 0.0338583 -0.0303149 -0.0125984 0.030315 0.0125984
CT
OB 0.0216536 -0.011811 I
OS -0.0216535 -0.011811
OS -0.0216535 0.011811
OS 0.0216536 0.011811
OS 0.0216536 -0.011811
OE
CE
PIN 1 S -0.0169291 0 0 U U
CT
OB -0.0302291 -0.0125 I
OS -0.0302291 0.0125
OS -0.0036291 0.0125
OS -0.0036291 -0.0125
OS -0.0302291 -0.0125
OE
CE
PIN 2 S 0.0169292 0 0 U U
CT
OB 0.0036292 -0.0125 I
OS 0.0036292 0.0125
OS 0.0302292 0.0125
OS 0.0302292 -0.0125
OS 0.0036292 -0.0125
OE
CE
#
# PKG 6
PKG CAPC1608X10N 0.0629921 -0.0511811 -0.0187008 0.051181 0.0187008
CT
OB 0.0344488 -0.0187008 I
OS -0.0344489 -0.0187008
OS -0.0344489 0.0187008
OS 0.0344488 0.0187008
OS 0.0344488 -0.0187008
OE
CE
PIN 1 S -0.0314961 0 0 U U
CT
OB -0.0510961 -0.0187 I
OS -0.0510961 0.0187
OS -0.0118961 0.0187
OS -0.0118961 -0.0187
OS -0.0510961 -0.0187
OE
CE
PIN 2 S 0.031496 0 0 U U
CT
OB 0.011896 -0.0187 I
OS 0.011896 0.0187
OS 0.051096 0.0187
OS 0.051096 -0.0187
OS 0.011896 -0.0187
OE
CE
#
# PKG 7
PKG CAPC2012X14N 0.0708662 -0.0580709 -0.0285433 0.0580709 0.0285433
CT
OB 0.0433071 -0.0285433 I
OS -0.0433071 -0.0285433
OS -0.0433071 0.0285433
OS 0.0433071 0.0285433
OS 0.0433071 -0.0285433
OE
CE
PIN 1 S -0.0354331 0 0 U U
CT
OB -0.0580331 -0.0285 I
OS -0.0580331 0.0285
OS -0.0128331 0.0285
OS -0.0128331 -0.0285
OS -0.0580331 -0.0285
OE
CE
PIN 2 S 0.0354331 0 0 U U
CT
OB 0.0128331 -0.0285 I
OS 0.0128331 0.0285
OS 0.0580331 0.0285
OS 0.0580331 -0.0285
OS 0.0128331 -0.0285
OE
CE
#
# PKG 8
PKG CUI_PJ-002A 0.2195213 -0.0492126 -0.1760768 0.537928 0.2293307
CT
OB 0.537928 -0.1760768 I
OS -0.029 -0.1760768
OS -0.029 0.194
OS 0.537928 0.194
OS 0.537928 -0.1760768
OE
CE
PIN 1 T 0 0 0 U U
CT
OB -0.0492 -0.0492 I
OS -0.0492 0.0492
OC 0.0492 0.0492 0 0.0492 Y
OS 0.0492 -0.0492
OC -0.0492 -0.0492 0 -0.0492 Y
OE
CE
PIN 2 T 0.2362205 0 0 U U
CT
OB 0.1920205 -0.0442 I
OS 0.1920205 0.0442
OC 0.2804205 0.0442 0.2362205 0.0442 Y
OS 0.2804205 -0.0442
OC 0.1920205 -0.0442 0.2362205 -0.0442 Y
OE
CE
PIN 3 T 0.1181102 0.1850394 0 U U
CT
OB 0.1623102 0.1408394 I
OS 0.0739102 0.1408394
OC 0.0739102 0.2292394 0.0739102 0.1850394 Y
OS 0.1623102 0.2292394
OC 0.1623102 0.1408394 0.1623102 0.1850394 Y
OE
CE
#
# PKG 9
PKG DIOM1608X06N 0.0570866 -0.0482283 -0.0167323 0.0482283 0.0167323
CT
OB 0.0314961 -0.015748 I
OS -0.0314961 -0.015748
OS -0.0314961 0.015748
OS 0.0314961 0.015748
OS 0.0314961 -0.015748
OE
CE
PIN 1 S -0.0285433 0 0 U U
CT
OB -0.0481433 -0.0167 I
OS -0.0481433 0.0167
OS -0.0089433 0.0167
OS -0.0089433 -0.0167
OS -0.0481433 -0.0167
OE
CE
PIN 2 S 0.0285433 0 0 U U
CT
OB 0.0089433 -0.0167 I
OS 0.0089433 0.0167
OS 0.0481433 0.0167
OS 0.0481433 -0.0167
OS 0.0089433 -0.0167
OE
CE
#
# PKG 10
PKG DIOM6959X26N 0.2244094 -0.160433 -0.1239968 0.160433 0.1240032
CT
OB 0.1600096 -0.1239968 I
OS -0.1599904 -0.1239968
OS -0.1599904 0.1240032
OS 0.1600096 0.1240032
OS 0.1600096 -0.1239968
OE
CE
PIN A S 0.1122047 0 0 U U
CT
OB 0.0640047 -0.062 I
OS 0.0640047 0.062
OS 0.1604047 0.062
OS 0.1604047 -0.062
OS 0.0640047 -0.062
OE
CE
PIN K S -0.1122047 0 0 U U
CT
OB -0.1604047 -0.062 I
OS -0.1604047 0.062
OS -0.0640047 0.062
OS -0.0640047 -0.062
OS -0.1604047 -0.062
OE
CE
#
# PKG 11
PKG FP-BU2032SM-BT-GTR-MFG 1.1535434 -0.6437008 -0.3287402 0.6437008 0.3287402
CT
OB 0.6437008 -0.3287402 I
OS -0.6437008 -0.3287402
OS -0.6437008 0.3287402
OS 0.6437008 0.3287402
OS 0.6437008 -0.3287402
OE
CE
PIN 1 S 0.5767717 0 0 U U
CT
OB 0.51377955 0.08267715 I
OS 0.63976385 0.08267715
OS 0.63976385 -0.08267715
OS 0.51377955 -0.08267715
OS 0.51377955 0.08267715
OE
CE
PIN 2 S -0.5767717 0 0 U U
CT
OB -0.63976385 0.08267715 I
OS -0.51377955 0.08267715
OS -0.51377955 -0.08267715
OS -0.63976385 -0.08267715
OS -0.63976385 0.08267715
OE
CE
#
# PKG 12
PKG FUSM1608X60N 0.0543307 -0.0413386 -0.019685 0.0413385 0.019685
CT
OB 0.032 -0.016 I
OS -0.032 -0.016
OS -0.032 0.016
OS 0.032 0.016
OS 0.032 -0.016
OE
CE
PIN 1 S -0.0271654 0 0 U U
CT
OB -0.0412654 -0.0196 I
OS -0.0412654 0.0196
OS -0.0130654 0.0196
OS -0.0130654 -0.0196
OS -0.0412654 -0.0196
OE
CE
PIN 2 S 0.0271653 0 0 U U
CT
OB 0.0130653 -0.0196 I
OS 0.0130653 0.0196
OS 0.0412653 0.0196
OS 0.0412653 -0.0196
OS 0.0130653 -0.0196
OE
CE
#
# PKG 13
PKG IND_PM124SH 0.3818898 -0.2680315 -0.2569685 0.2680315 0.2569685
CT
OB 0.2680315 -0.2569685 I
OS -0.2680315 -0.2569685
OS -0.2680315 0.2569685
OS 0.2680315 0.2569685
OS 0.2680315 -0.2569685
OE
CE
PIN 1 S -0.1909449 0 0 U U
CT
OB -0.2480315 0.1062992 I
OS -0.1338583 0.1062992
OS -0.1338583 -0.1062992
OS -0.2480315 -0.1062992
OS -0.2480315 0.1062992
OE
CE
PIN 2 S 0.1909449 0 0 U U
CT
OB 0.1338583 0.1062992 I
OS 0.2480315 0.1062992
OS 0.2480315 -0.1062992
OS 0.1338583 -0.1062992
OS 0.1338583 0.1062992
OE
CE
#
# PKG 14
PKG INDC1608X09N 0.0523622 -0.0433071 -0.0192913 0.0433071 0.0192913
CT
OB 0.0345045 -0.0184978 I
OS -0.0344955 -0.0184978
OS -0.0344955 0.0185022
OS 0.0345045 0.0185022
OS 0.0345045 -0.0184978
OE
CE
PIN 1 S -0.0261811 0 0 U U
CT
OB -0.0432811 -0.0192 I
OS -0.0432811 0.0192
OS -0.0090811 0.0192
OS -0.0090811 -0.0192
OS -0.0432811 -0.0192
OE
CE
PIN 2 S 0.0261811 0 0 U U
CT
OB 0.0090811 -0.0192 I
OS 0.0090811 0.0192
OS 0.0432811 0.0192
OS 0.0432811 -0.0192
OS 0.0090811 -0.0192
OE
CE
#
# PKG 15
PKG J1-0603 0.0590551 -0.043307 -0.0187008 0.0433071 0.0187008
CT
OB 0.0334646 -0.0187008 I
OS -0.0334646 -0.0187008
OS -0.0334646 0.0187008
OS 0.0334646 0.0187008
OS 0.0334646 -0.0187008
OE
CE
PIN 1 S -0.0295275 0.0000001 0 U U
CT
OB -0.0432275 -0.0176999 I
OS -0.0432275 0.0177001
OS -0.0158275 0.0177001
OS -0.0158275 -0.0176999
OS -0.0432275 -0.0176999
OE
CE
PIN 2 S 0.0295276 0.0000001 0 U U
CT
OB 0.0158276 -0.0176999 I
OS 0.0158276 0.0177001
OS 0.0432276 0.0177001
OS 0.0432276 -0.0176999
OS 0.0158276 -0.0176999
OE
CE
#
# PKG 16
PKG L101011MS02Q 0.1811024 -0.2144992 -0.3764928 0.2144992 0.3765056
CT
OB 0.2144992 -0.3764928 I
OS -0.2144992 -0.3764928
OS -0.2144992 0.3765056
OS 0.2144992 0.3765056
OS 0.2144992 -0.3764928
OE
CE
PIN 1 T -0.1122047 -0.1811024 0 U U
CR -0.1122047 -0.1811024 0.0492126
PIN 2 T -0.1122047 0 0 U U
CR -0.1122047 0 0.0492126
#
# PKG 17
PKG LGA-28 0.0195276 -0.1023622 -0.0748031 0.1023622 0.0748031
RC -0.1023622 -0.0748031 0.2047244 0.1496062
PIN 1 S 0.0885827 0.0615157 0 U U
CT
OB 0.0934827 0.0483157 I
OS 0.0836827 0.0483157
OS 0.0836827 0.0747157
OS 0.0934827 0.0747157
OS 0.0934827 0.0483157
OE
CE
PIN 2 S 0.0910433 0.0295276 0 U U
CT
OB 0.0797244 0.03444885 I
OS 0.1023622 0.03444885
OS 0.1023622 0.02460635
OS 0.0797244 0.02460635
OS 0.0797244 0.03444885
OE
CE
PIN 3 S 0.0910433 0.01 0 U U
CT
OB 0.0797244 0.01492125 I
OS 0.1023622 0.01492125
OS 0.1023622 0.00507875
OS 0.0797244 0.00507875
OS 0.0797244 0.01492125
OE
CE
PIN 4 S 0.0910433 -0.0098425 0 U U
CT
OB 0.0797244 -0.00492125 I
OS 0.1023622 -0.00492125
OS 0.1023622 -0.01476375
OS 0.0797244 -0.01476375
OS 0.0797244 -0.00492125
OE
CE
PIN 5 S 0.0910433 -0.0295276 0 U U
CT
OB 0.0797244 -0.02460635 I
OS 0.1023622 -0.02460635
OS 0.1023622 -0.03444885
OS 0.0797244 -0.03444885
OS 0.0797244 -0.02460635
OE
CE
PIN 6 S 0.0885827 -0.0615157 0 U U
CT
OB 0.0934827 -0.0747157 I
OS 0.0836827 -0.0747157
OS 0.0836827 -0.0483157
OS 0.0934827 -0.0483157
OS 0.0934827 -0.0747157
OE
CE
PIN 7 S 0.0688976 -0.0615157 0 U U
CT
OB 0.0737976 -0.0747157 I
OS 0.0639976 -0.0747157
OS 0.0639976 -0.0483157
OS 0.0737976 -0.0483157
OS 0.0737976 -0.0747157
OE
CE
PIN 8 S 0.0492126 -0.0615157 0 U U
CT
OB 0.0541126 -0.0747157 I
OS 0.0443126 -0.0747157
OS 0.0443126 -0.0483157
OS 0.0541126 -0.0483157
OS 0.0541126 -0.0747157
OE
CE
PIN 9 S 0.0295276 -0.0615157 0 U U
CT
OB 0.0344276 -0.0747157 I
OS 0.0246276 -0.0747157
OS 0.0246276 -0.0483157
OS 0.0344276 -0.0483157
OS 0.0344276 -0.0747157
OE
CE
PIN 10 S 0.0098425 -0.0615157 0 U U
CT
OB 0.0147425 -0.0747157 I
OS 0.0049425 -0.0747157
OS 0.0049425 -0.0483157
OS 0.0147425 -0.0483157
OS 0.0147425 -0.0747157
OE
CE
PIN 11 S -0.0098425 -0.0615157 0 U U
CT
OB -0.0049425 -0.0747157 I
OS -0.0147425 -0.0747157
OS -0.0147425 -0.0483157
OS -0.0049425 -0.0483157
OS -0.0049425 -0.0747157
OE
CE
PIN 12 S -0.0295276 -0.0615157 0 U U
CT
OB -0.0246276 -0.0747157 I
OS -0.0344276 -0.0747157
OS -0.0344276 -0.0483157
OS -0.0246276 -0.0483157
OS -0.0246276 -0.0747157
OE
CE
PIN 13 S -0.0492126 -0.0615157 0 U U
CT
OB -0.0443126 -0.0747157 I
OS -0.0541126 -0.0747157
OS -0.0541126 -0.0483157
OS -0.0443126 -0.0483157
OS -0.0443126 -0.0747157
OE
CE
PIN 14 S -0.0688976 -0.0615157 0 U U
CT
OB -0.0639976 -0.0747157 I
OS -0.0737976 -0.0747157
OS -0.0737976 -0.0483157
OS -0.0639976 -0.0483157
OS -0.0639976 -0.0747157
OE
CE
PIN 15 S -0.0885827 -0.0615157 0 U U
CT
OB -0.0836827 -0.0747157 I
OS -0.0934827 -0.0747157
OS -0.0934827 -0.0483157
OS -0.0836827 -0.0483157
OS -0.0836827 -0.0747157
OE
CE
PIN 16 S -0.0910433 -0.0295276 0 U U
CT
OB -0.0797433 -0.0344276 I
OS -0.1023433 -0.0344276
OS -0.1023433 -0.0246276
OS -0.0797433 -0.0246276
OS -0.0797433 -0.0344276
OE
CE
PIN 17 S -0.0910433 -0.0098425 0 U U
CT
OB -0.0797433 -0.0147425 I
OS -0.1023433 -0.0147425
OS -0.1023433 -0.0049425
OS -0.0797433 -0.0049425
OS -0.0797433 -0.0147425
OE
CE
PIN 18 S -0.0910433 0.0098425 0 U U
CT
OB -0.0797433 0.0049425 I
OS -0.1023433 0.0049425
OS -0.1023433 0.0147425
OS -0.0797433 0.0147425
OS -0.0797433 0.0049425
OE
CE
PIN 19 S -0.0910433 0.0295276 0 U U
CT
OB -0.0797433 0.0246276 I
OS -0.1023433 0.0246276
OS -0.1023433 0.0344276
OS -0.0797433 0.0344276
OS -0.0797433 0.0246276
OE
CE
PIN 20 S -0.0885827 0.0615157 0 U U
CT
OB -0.0836827 0.0483157 I
OS -0.0934827 0.0483157
OS -0.0934827 0.0747157
OS -0.0836827 0.0747157
OS -0.0836827 0.0483157
OE
CE
PIN 21 S -0.0688976 0.0615157 0 U U
CT
OB -0.0639976 0.0483157 I
OS -0.0737976 0.0483157
OS -0.0737976 0.0747157
OS -0.0639976 0.0747157
OS -0.0639976 0.0483157
OE
CE
PIN 22 S -0.0492126 0.0615157 0 U U
CT
OB -0.0443126 0.0483157 I
OS -0.0541126 0.0483157
OS -0.0541126 0.0747157
OS -0.0443126 0.0747157
OS -0.0443126 0.0483157
OE
CE
PIN 23 S -0.0295276 0.0615157 0 U U
CT
OB -0.0246276 0.0483157 I
OS -0.0344276 0.0483157
OS -0.0344276 0.0747157
OS -0.0246276 0.0747157
OS -0.0246276 0.0483157
OE
CE
PIN 24 S -0.0098425 0.0615157 0 U U
CT
OB -0.0049425 0.0483157 I
OS -0.0147425 0.0483157
OS -0.0147425 0.0747157
OS -0.0049425 0.0747157
OS -0.0049425 0.0483157
OE
CE
PIN 25 S 0.0098425 0.0615157 0 U U
CT
OB 0.0147425 0.0483157 I
OS 0.0049425 0.0483157
OS 0.0049425 0.0747157
OS 0.0147425 0.0747157
OS 0.0147425 0.0483157
OE
CE
PIN 26 S 0.0295276 0.0615157 0 U U
CT
OB 0.0344276 0.0483157 I
OS 0.0246276 0.0483157
OS 0.0246276 0.0747157
OS 0.0344276 0.0747157
OS 0.0344276 0.0483157
OE
CE
PIN 27 S 0.0492126 0.0615157 0 U U
CT
OB 0.0541126 0.0483157 I
OS 0.0443126 0.0483157
OS 0.0443126 0.0747157
OS 0.0541126 0.0747157
OS 0.0541126 0.0483157
OE
CE
PIN 28 S 0.0688976 0.0615157 0 U U
CT
OB 0.0737976 0.0483157 I
OS 0.0639976 0.0483157
OS 0.0639976 0.0747157
OS 0.0737976 0.0747157
OS 0.0737976 0.0483157
OE
CE
#
# PKG 18
PKG MAC-SA5X 0.02 0.0569882 0.0970486 1.8367126 1.8367126
CT
OB 1.173232 0.106304 I
OS 0.8267744 0.106304
OS 0.8267744 0.3188992
OS 1.173232 0.3188992
OS 1.173232 0.106304
OE
CE
PIN 1 S 1.090208 0.2899619 0 U U
CT
OB 1.095108 0.2545619 I
OS 1.085308 0.2545619
OS 1.085308 0.3253619
OS 1.095108 0.3253619
OS 1.095108 0.2545619
OE
CE
PIN 2 S 1.090208 0.1324816 0 U U
CT
OB 1.095108 0.0970816 I
OS 1.085308 0.0970816
OS 1.085308 0.1678816
OS 1.095108 0.1678816
OS 1.095108 0.0970816
OE
CE
PIN 3 S 1.070208 0.2899619 0 U U
CT
OB 1.075108 0.2545619 I
OS 1.065308 0.2545619
OS 1.065308 0.3253619
OS 1.075108 0.3253619
OS 1.075108 0.2545619
OE
CE
PIN 4 S 1.070208 0.1324816 0 U U
CT
OB 1.075108 0.0970816 I
OS 1.065308 0.0970816
OS 1.065308 0.1678816
OS 1.075108 0.1678816
OS 1.075108 0.0970816
OE
CE
PIN 5 S 1.050208 0.2899619 0 U U
CT
OB 1.055108 0.2545619 I
OS 1.045308 0.2545619
OS 1.045308 0.3253619
OS 1.055108 0.3253619
OS 1.055108 0.2545619
OE
CE
PIN 6 S 1.050208 0.1324816 0 U U
CT
OB 1.055108 0.0970816 I
OS 1.045308 0.0970816
OS 1.045308 0.1678816
OS 1.055108 0.1678816
OS 1.055108 0.0970816
OE
CE
PIN 7 S 1.030208 0.2899619 0 U U
CT
OB 1.035108 0.2545619 I
OS 1.025308 0.2545619
OS 1.025308 0.3253619
OS 1.035108 0.3253619
OS 1.035108 0.2545619
OE
CE
PIN 8 S 1.030208 0.1324816 0 U U
CT
OB 1.035108 0.0970816 I
OS 1.025308 0.0970816
OS 1.025308 0.1678816
OS 1.035108 0.1678816
OS 1.035108 0.0970816
OE
CE
PIN 9 S 1.010208 0.2899619 0 U U
CT
OB 1.015108 0.2545619 I
OS 1.005308 0.2545619
OS 1.005308 0.3253619
OS 1.015108 0.3253619
OS 1.015108 0.2545619
OE
CE
PIN 10 S 1.010208 0.1324816 0 U U
CT
OB 1.015108 0.0970816 I
OS 1.005308 0.0970816
OS 1.005308 0.1678816
OS 1.015108 0.1678816
OS 1.015108 0.0970816
OE
CE
PIN 11 S 0.990208 0.2899619 0 U U
CT
OB 0.995108 0.2545619 I
OS 0.985308 0.2545619
OS 0.985308 0.3253619
OS 0.995108 0.3253619
OS 0.995108 0.2545619
OE
CE
PIN 12 S 0.990208 0.1324816 0 U U
CT
OB 0.995108 0.0970816 I
OS 0.985308 0.0970816
OS 0.985308 0.1678816
OS 0.995108 0.1678816
OS 0.995108 0.0970816
OE
CE
PIN 13 S 0.970208 0.2899619 0 U U
CT
OB 0.975108 0.2545619 I
OS 0.965308 0.2545619
OS 0.965308 0.3253619
OS 0.975108 0.3253619
OS 0.975108 0.2545619
OE
CE
PIN 14 S 0.970208 0.1324816 0 U U
CT
OB 0.975108 0.0970816 I
OS 0.965308 0.0970816
OS 0.965308 0.1678816
OS 0.975108 0.1678816
OS 0.975108 0.0970816
OE
CE
PIN 15 S 0.950208 0.2899619 0 U U
CT
OB 0.955108 0.2545619 I
OS 0.945308 0.2545619
OS 0.945308 0.3253619
OS 0.955108 0.3253619
OS 0.955108 0.2545619
OE
CE
PIN 16 S 0.950208 0.1324816 0 U U
CT
OB 0.955108 0.0970816 I
OS 0.945308 0.0970816
OS 0.945308 0.1678816
OS 0.955108 0.1678816
OS 0.955108 0.0970816
OE
CE
PIN 17 S 0.930208 0.2899619 0 U U
CT
OB 0.935108 0.2545619 I
OS 0.925308 0.2545619
OS 0.925308 0.3253619
OS 0.935108 0.3253619
OS 0.935108 0.2545619
OE
CE
PIN 18 S 0.930208 0.1324816 0 U U
CT
OB 0.935108 0.0970816 I
OS 0.925308 0.0970816
OS 0.925308 0.1678816
OS 0.935108 0.1678816
OS 0.935108 0.0970816
OE
CE
PIN 19 S 0.910208 0.2899619 0 U U
CT
OB 0.915108 0.2545619 I
OS 0.905308 0.2545619
OS 0.905308 0.3253619
OS 0.915108 0.3253619
OS 0.915108 0.2545619
OE
CE
PIN 20 S 0.910208 0.1324816 0 U U
CT
OB 0.915108 0.0970816 I
OS 0.905308 0.0970816
OS 0.905308 0.1678816
OS 0.915108 0.1678816
OS 0.915108 0.0970816
OE
CE
PIN P1 T 1.7992126 1.7992126 0 U U
CR 1.7992126 1.7992126 0.0375
PIN P2 T 1 1.7992126 0 U U
CR 1 1.7992126 0.0375
PIN P3 T 0.2007874 1.7992126 0 U U
CR 0.2007874 1.7992126 0.0375
PIN P4 T 0.2007874 0.2007874 0 U U
CR 0.2007874 0.2007874 0.0375
PIN P5 T 1.7992126 0.2007874 0 U U
CR 1.7992126 0.2007874 0.0375
PIN P6 T 0.0944882 0.2834646 0 U U
CR 0.0944882 0.2834646 0.0375
PIN P7 T 0.0944882 0.4015748 0 U U
CR 0.0944882 0.4015748 0.0375
PIN P8 T 0.0944882 0.519685 0 U U
CR 0.0944882 0.519685 0.0375
#
# PKG 19
PKG MCSM-090-02984-00X 0.2 -0.79998 -0.69498 0.79998 0.69498
CT
OB 0.79998 -0.69498 I
OS -0.79998 -0.69498
OS -0.79998 0.69498
OS 0.79998 0.69498
OS 0.79998 -0.69498
OE
CE
PIN 1 T -0.65 0.5 0 U U
CT
OB -0.6805118 0.5305118 I
OS -0.6194882 0.5305118
OS -0.6194882 0.4694882
OS -0.6805118 0.4694882
OS -0.6805118 0.5305118
OE
CE
PIN 4 T -0.65 -0.1 0 U U
CR -0.65 -0.1 0.0305118
PIN 5 T -0.65 -0.3 0 U U
CR -0.65 -0.3 0.0305118
PIN 6 T -0.65 -0.5 0 U U
CR -0.65 -0.5 0.0305118
PIN 7 T 0.65 -0.5 0 U U
CR 0.65 -0.5 0.0305118
PIN 8 T 0.65 -0.3 0 U U
CR 0.65 -0.3 0.0305118
PIN 9 T 0.65 -0.1 0 U U
CR 0.65 -0.1 0.0305118
PIN 10 T 0.65 0.1 0 U U
CR 0.65 0.1 0.0305118
PIN 12 T 0.65 0.5 0 U U
CR 0.65 0.5 0.0305118
#
# PKG 20
PKG OMRON-B3U-1000P 0.1338582 -0.0826771 -0.0492128 0.0826771 0.0492128
CT
OB 0.0787392 -0.0492128 I
OS -0.0787392 -0.0492128
OS -0.0787392 0.0492128
OS 0.0787392 0.0492128
OS 0.0787392 -0.0492128
OE
CE
PIN 1 S -0.0669291 0 0 U U
CT
OB -0.08267715 0.03346455 I
OS -0.05118105 0.03346455
OS -0.05118105 -0.03346455
OS -0.08267715 -0.03346455
OS -0.08267715 0.03346455
OE
CE
PIN 2 S 0.0669291 0 0 U U
CT
OB 0.05118105 0.03346455 I
OS 0.08267715 0.03346455
OS 0.08267715 -0.03346455
OS 0.05118105 -0.03346455
OS 0.05118105 0.03346455
OE
CE
#
# PKG 21
PKG PCIE_4LANE_EDGE 0 -0.6636 -0.18974 0.66361 -0.02474
RC -0.6636 -0.18974 1.32721 0.165
PIN A1 S -0.6496 -0.08774 0 U U
CT
OB -0.6636 -0.02474 I
OS -0.6356 -0.02474
OS -0.6356 -0.15074
OS -0.6636 -0.15074
OS -0.6636 -0.02474
OE
CE
PIN A2 S -0.61023 -0.10724 0 U U
CT
OB -0.62423 -0.02474 I
OS -0.59623 -0.02474
OS -0.59623 -0.18974
OS -0.62423 -0.18974
OS -0.62423 -0.02474
OE
CE
PIN A3 S -0.57086 -0.10724 0 U U
CT
OB -0.58486 -0.02474 I
OS -0.55686 -0.02474
OS -0.55686 -0.18974
OS -0.58486 -0.18974
OS -0.58486 -0.02474
OE
CE
PIN A4 S -0.53149 -0.10724 0 U U
CT
OB -0.54549 -0.02474 I
OS -0.51749 -0.02474
OS -0.51749 -0.18974
OS -0.54549 -0.18974
OS -0.54549 -0.02474
OE
CE
PIN A5 S -0.49212 -0.10724 0 U U
CT
OB -0.50612 -0.02474 I
OS -0.47812 -0.02474
OS -0.47812 -0.18974
OS -0.50612 -0.18974
OS -0.50612 -0.02474
OE
CE
PIN A6 S -0.45275 -0.10724 0 U U
CT
OB -0.46675 -0.02474 I
OS -0.43875 -0.02474
OS -0.43875 -0.18974
OS -0.46675 -0.18974
OS -0.46675 -0.02474
OE
CE
PIN A7 S -0.41338 -0.10724 0 U U
CT
OB -0.42738 -0.02474 I
OS -0.39938 -0.02474
OS -0.39938 -0.18974
OS -0.42738 -0.18974
OS -0.42738 -0.02474
OE
CE
PIN A8 S -0.37401 -0.10724 0 U U
CT
OB -0.38801 -0.02474 I
OS -0.36001 -0.02474
OS -0.36001 -0.18974
OS -0.38801 -0.18974
OS -0.38801 -0.02474
OE
CE
PIN A9 S -0.33464 -0.10724 0 U U
CT
OB -0.34864 -0.02474 I
OS -0.32064 -0.02474
OS -0.32064 -0.18974
OS -0.34864 -0.18974
OS -0.34864 -0.02474
OE
CE
PIN A10 S -0.29527 -0.10724 0 U U
CT
OB -0.30927 -0.02474 I
OS -0.28127 -0.02474
OS -0.28127 -0.18974
OS -0.30927 -0.18974
OS -0.30927 -0.02474
OE
CE
PIN A11 S -0.2559 -0.10724 0 U U
CT
OB -0.2699 -0.02474 I
OS -0.2419 -0.02474
OS -0.2419 -0.18974
OS -0.2699 -0.18974
OS -0.2699 -0.02474
OE
CE
PIN A12 S -0.13779 -0.10724 0 U U
CT
OB -0.15179 -0.02474 I
OS -0.12379 -0.02474
OS -0.12379 -0.18974
OS -0.15179 -0.18974
OS -0.15179 -0.02474
OE
CE
PIN A13 S -0.09842 -0.10724 0 U U
CT
OB -0.11242 -0.02474 I
OS -0.08442 -0.02474
OS -0.08442 -0.18974
OS -0.11242 -0.18974
OS -0.11242 -0.02474
OE
CE
PIN A14 S -0.05905 -0.10724 0 U U
CT
OB -0.07305 -0.02474 I
OS -0.04505 -0.02474
OS -0.04505 -0.18974
OS -0.07305 -0.18974
OS -0.07305 -0.02474
OE
CE
PIN A15 S -0.01968 -0.10724 0 U U
CT
OB -0.03368 -0.02474 I
OS -0.00568 -0.02474
OS -0.00568 -0.18974
OS -0.03368 -0.18974
OS -0.03368 -0.02474
OE
CE
PIN A16 S 0.01969 -0.10724 0 U U
CT
OB 0.00569 -0.02474 I
OS 0.03369 -0.02474
OS 0.03369 -0.18974
OS 0.00569 -0.18974
OS 0.00569 -0.02474
OE
CE
PIN A17 S 0.05906 -0.10724 0 U U
CT
OB 0.04506 -0.02474 I
OS 0.07306 -0.02474
OS 0.07306 -0.18974
OS 0.04506 -0.18974
OS 0.04506 -0.02474
OE
CE
PIN A18 S 0.09843 -0.10724 0 U U
CT
OB 0.08443 -0.02474 I
OS 0.11243 -0.02474
OS 0.11243 -0.18974
OS 0.08443 -0.18974
OS 0.08443 -0.02474
OE
CE
PIN A19 S 0.1378 -0.10724 0 U U
CT
OB 0.1238 -0.02474 I
OS 0.1518 -0.02474
OS 0.1518 -0.18974
OS 0.1238 -0.18974
OS 0.1238 -0.02474
OE
CE
PIN A20 S 0.17717 -0.10724 0 U U
CT
OB 0.16317 -0.02474 I
OS 0.19117 -0.02474
OS 0.19117 -0.18974
OS 0.16317 -0.18974
OS 0.16317 -0.02474
OE
CE
PIN A21 S 0.21654 -0.10724 0 U U
CT
OB 0.20254 -0.02474 I
OS 0.23054 -0.02474
OS 0.23054 -0.18974
OS 0.20254 -0.18974
OS 0.20254 -0.02474
OE
CE
PIN A22 S 0.25591 -0.10724 0 U U
CT
OB 0.24191 -0.02474 I
OS 0.26991 -0.02474
OS 0.26991 -0.18974
OS 0.24191 -0.18974
OS 0.24191 -0.02474
OE
CE
PIN A23 S 0.29528 -0.10724 0 U U
CT
OB 0.28128 -0.02474 I
OS 0.30928 -0.02474
OS 0.30928 -0.18974
OS 0.28128 -0.18974
OS 0.28128 -0.02474
OE
CE
PIN A24 S 0.33465 -0.10724 0 U U
CT
OB 0.32065 -0.02474 I
OS 0.34865 -0.02474
OS 0.34865 -0.18974
OS 0.32065 -0.18974
OS 0.32065 -0.02474
OE
CE
PIN A25 S 0.37402 -0.10724 0 U U
CT
OB 0.36002 -0.02474 I
OS 0.38802 -0.02474
OS 0.38802 -0.18974
OS 0.36002 -0.18974
OS 0.36002 -0.02474
OE
CE
PIN A26 S 0.41339 -0.10724 0 U U
CT
OB 0.39939 -0.02474 I
OS 0.42739 -0.02474
OS 0.42739 -0.18974
OS 0.39939 -0.18974
OS 0.39939 -0.02474
OE
CE
PIN A27 S 0.45276 -0.10724 0 U U
CT
OB 0.43876 -0.02474 I
OS 0.46676 -0.02474
OS 0.46676 -0.18974
OS 0.43876 -0.18974
OS 0.43876 -0.02474
OE
CE
PIN A28 S 0.49213 -0.10724 0 U U
CT
OB 0.47813 -0.02474 I
OS 0.50613 -0.02474
OS 0.50613 -0.18974
OS 0.47813 -0.18974
OS 0.47813 -0.02474
OE
CE
PIN A29 S 0.5315 -0.10724 0 U U
CT
OB 0.5175 -0.02474 I
OS 0.5455 -0.02474
OS 0.5455 -0.18974
OS 0.5175 -0.18974
OS 0.5175 -0.02474
OE
CE
PIN A30 S 0.57087 -0.10724 0 U U
CT
OB 0.55687 -0.02474 I
OS 0.58487 -0.02474
OS 0.58487 -0.18974
OS 0.55687 -0.18974
OS 0.55687 -0.02474
OE
CE
PIN A31 S 0.61024 -0.10724 0 U U
CT
OB 0.59624 -0.02474 I
OS 0.62424 -0.02474
OS 0.62424 -0.18974
OS 0.59624 -0.18974
OS 0.59624 -0.02474
OE
CE
PIN A32 S 0.64961 -0.10724 0 U U
CT
OB 0.63561 -0.02474 I
OS 0.66361 -0.02474
OS 0.66361 -0.18974
OS 0.63561 -0.18974
OS 0.63561 -0.02474
OE
CE
PIN B1 S -0.6496 -0.10724 0 U U
CT
OB -0.6636 -0.02474 I
OS -0.6356 -0.02474
OS -0.6356 -0.18974
OS -0.6636 -0.18974
OS -0.6636 -0.02474
OE
CE
PIN B2 S -0.61023 -0.10724 0 U U
CT
OB -0.62423 -0.02474 I
OS -0.59623 -0.02474
OS -0.59623 -0.18974
OS -0.62423 -0.18974
OS -0.62423 -0.02474
OE
CE
PIN B3 S -0.57086 -0.10724 0 U U
CT
OB -0.58486 -0.02474 I
OS -0.55686 -0.02474
OS -0.55686 -0.18974
OS -0.58486 -0.18974
OS -0.58486 -0.02474
OE
CE
PIN B4 S -0.53149 -0.10724 0 U U
CT
OB -0.54549 -0.02474 I
OS -0.51749 -0.02474
OS -0.51749 -0.18974
OS -0.54549 -0.18974
OS -0.54549 -0.02474
OE
CE
PIN B5 S -0.49212 -0.10724 0 U U
CT
OB -0.50612 -0.02474 I
OS -0.47812 -0.02474
OS -0.47812 -0.18974
OS -0.50612 -0.18974
OS -0.50612 -0.02474
OE
CE
PIN B6 S -0.45275 -0.10724 0 U U
CT
OB -0.46675 -0.02474 I
OS -0.43875 -0.02474
OS -0.43875 -0.18974
OS -0.46675 -0.18974
OS -0.46675 -0.02474
OE
CE
PIN B7 S -0.41338 -0.10724 0 U U
CT
OB -0.42738 -0.02474 I
OS -0.39938 -0.02474
OS -0.39938 -0.18974
OS -0.42738 -0.18974
OS -0.42738 -0.02474
OE
CE
PIN B8 S -0.37401 -0.10724 0 U U
CT
OB -0.38801 -0.02474 I
OS -0.36001 -0.02474
OS -0.36001 -0.18974
OS -0.38801 -0.18974
OS -0.38801 -0.02474
OE
CE
PIN B9 S -0.33464 -0.10724 0 U U
CT
OB -0.34864 -0.02474 I
OS -0.32064 -0.02474
OS -0.32064 -0.18974
OS -0.34864 -0.18974
OS -0.34864 -0.02474
OE
CE
PIN B10 S -0.29527 -0.10724 0 U U
CT
OB -0.30927 -0.02474 I
OS -0.28127 -0.02474
OS -0.28127 -0.18974
OS -0.30927 -0.18974
OS -0.30927 -0.02474
OE
CE
PIN B11 S -0.2559 -0.10724 0 U U
CT
OB -0.2699 -0.02474 I
OS -0.2419 -0.02474
OS -0.2419 -0.18974
OS -0.2699 -0.18974
OS -0.2699 -0.02474
OE
CE
PIN B12 S -0.13779 -0.10724 0 U U
CT
OB -0.15179 -0.02474 I
OS -0.12379 -0.02474
OS -0.12379 -0.18974
OS -0.15179 -0.18974
OS -0.15179 -0.02474
OE
CE
PIN B13 S -0.09842 -0.10724 0 U U
CT
OB -0.11242 -0.02474 I
OS -0.08442 -0.02474
OS -0.08442 -0.18974
OS -0.11242 -0.18974
OS -0.11242 -0.02474
OE
CE
PIN B14 S -0.05905 -0.10724 0 U U
CT
OB -0.07305 -0.02474 I
OS -0.04505 -0.02474
OS -0.04505 -0.18974
OS -0.07305 -0.18974
OS -0.07305 -0.02474
OE
CE
PIN B15 S -0.01968 -0.10724 0 U U
CT
OB -0.03368 -0.02474 I
OS -0.00568 -0.02474
OS -0.00568 -0.18974
OS -0.03368 -0.18974
OS -0.03368 -0.02474
OE
CE
PIN B16 S 0.01969 -0.10724 0 U U
CT
OB 0.00569 -0.02474 I
OS 0.03369 -0.02474
OS 0.03369 -0.18974
OS 0.00569 -0.18974
OS 0.00569 -0.02474
OE
CE
PIN B17 S 0.05906 -0.10724 0 U U
CT
OB 0.04506 -0.02474 I
OS 0.07306 -0.02474
OS 0.07306 -0.18974
OS 0.04506 -0.18974
OS 0.04506 -0.02474
OE
CE
PIN B18 S 0.09843 -0.10724 0 U U
CT
OB 0.08443 -0.02474 I
OS 0.11243 -0.02474
OS 0.11243 -0.18974
OS 0.08443 -0.18974
OS 0.08443 -0.02474
OE
CE
PIN B19 S 0.1378 -0.10724 0 U U
CT
OB 0.1238 -0.02474 I
OS 0.1518 -0.02474
OS 0.1518 -0.18974
OS 0.1238 -0.18974
OS 0.1238 -0.02474
OE
CE
PIN B20 S 0.17717 -0.10724 0 U U
CT
OB 0.16317 -0.02474 I
OS 0.19117 -0.02474
OS 0.19117 -0.18974
OS 0.16317 -0.18974
OS 0.16317 -0.02474
OE
CE
PIN B21 S 0.21654 -0.10724 0 U U
CT
OB 0.20254 -0.02474 I
OS 0.23054 -0.02474
OS 0.23054 -0.18974
OS 0.20254 -0.18974
OS 0.20254 -0.02474
OE
CE
PIN B22 S 0.25591 -0.10724 0 U U
CT
OB 0.24191 -0.02474 I
OS 0.26991 -0.02474
OS 0.26991 -0.18974
OS 0.24191 -0.18974
OS 0.24191 -0.02474
OE
CE
PIN B23 S 0.29528 -0.10724 0 U U
CT
OB 0.28128 -0.02474 I
OS 0.30928 -0.02474
OS 0.30928 -0.18974
OS 0.28128 -0.18974
OS 0.28128 -0.02474
OE
CE
PIN B24 S 0.33465 -0.10724 0 U U
CT
OB 0.32065 -0.02474 I
OS 0.34865 -0.02474
OS 0.34865 -0.18974
OS 0.32065 -0.18974
OS 0.32065 -0.02474
OE
CE
PIN B25 S 0.37402 -0.10724 0 U U
CT
OB 0.36002 -0.02474 I
OS 0.38802 -0.02474
OS 0.38802 -0.18974
OS 0.36002 -0.18974
OS 0.36002 -0.02474
OE
CE
PIN B26 S 0.41339 -0.10724 0 U U
CT
OB 0.39939 -0.02474 I
OS 0.42739 -0.02474
OS 0.42739 -0.18974
OS 0.39939 -0.18974
OS 0.39939 -0.02474
OE
CE
PIN B27 S 0.45276 -0.10724 0 U U
CT
OB 0.43876 -0.02474 I
OS 0.46676 -0.02474
OS 0.46676 -0.18974
OS 0.43876 -0.18974
OS 0.43876 -0.02474
OE
CE
PIN B28 S 0.49213 -0.10724 0 U U
CT
OB 0.47813 -0.02474 I
OS 0.50613 -0.02474
OS 0.50613 -0.18974
OS 0.47813 -0.18974
OS 0.47813 -0.02474
OE
CE
PIN B29 S 0.5315 -0.10724 0 U U
CT
OB 0.5175 -0.02474 I
OS 0.5455 -0.02474
OS 0.5455 -0.18974
OS 0.5175 -0.18974
OS 0.5175 -0.02474
OE
CE
PIN B30 S 0.57087 -0.10724 0 U U
CT
OB 0.55687 -0.02474 I
OS 0.58487 -0.02474
OS 0.58487 -0.18974
OS 0.55687 -0.18974
OS 0.55687 -0.02474
OE
CE
PIN B31 S 0.61024 -0.08774 0 U U
CT
OB 0.59624 -0.02474 I
OS 0.62424 -0.02474
OS 0.62424 -0.15074
OS 0.59624 -0.15074
OS 0.59624 -0.02474
OE
CE
PIN B32 S 0.64961 -0.10724 0 U U
CT
OB 0.63561 -0.02474 I
OS 0.66361 -0.02474
OS 0.66361 -0.18974
OS 0.63561 -0.18974
OS 0.63561 -0.02474
OE
CE
#
# PKG 22
PKG RCB-F9T 0.0787401 0.6426036 0.1116142 0.9574036 0.3694882
CT
OB 0.9574036 0.1310559 I
OS 0.6426036 0.1310559
OS 0.6426036 0.3500559
OS 0.9574036 0.3500559
OS 0.9574036 0.1310559
OE
CE
PIN 0 T 0.8846457 0.2405512 0 U U
CR 0.8846457 0.2405512 0.01496065
PIN 0 T 0.7271654 0.2405512 0 U U
CR 0.7271654 0.2405512 0.01496065
PIN 1 S 0.9240157 0.1530512 0 U U
CT
OB 0.90196845 0.1944882 I
OS 0.94606295 0.1944882
OS 0.94606295 0.1116142
OS 0.90196845 0.1116142
OS 0.90196845 0.1944882
OE
CE
PIN 2 S 0.9240157 0.3280512 0 U U
CT
OB 0.90196845 0.3694882 I
OS 0.94606295 0.3694882
OS 0.94606295 0.2866142
OS 0.90196845 0.2866142
OS 0.90196845 0.3694882
OE
CE
PIN 3 S 0.8452756 0.1530512 0 U U
CT
OB 0.82322835 0.1944882 I
OS 0.86732285 0.1944882
OS 0.86732285 0.1116142
OS 0.82322835 0.1116142
OS 0.82322835 0.1944882
OE
CE
PIN 4 S 0.8452756 0.3280512 0 U U
CT
OB 0.82322835 0.3694882 I
OS 0.86732285 0.3694882
OS 0.86732285 0.2866142
OS 0.82322835 0.2866142
OS 0.82322835 0.3694882
OE
CE
PIN 5 S 0.7665354 0.1530512 0 U U
CT
OB 0.74448815 0.1944882 I
OS 0.78858265 0.1944882
OS 0.78858265 0.1116142
OS 0.74448815 0.1116142
OS 0.74448815 0.1944882
OE
CE
PIN 6 S 0.7665354 0.3280512 0 U U
CT
OB 0.74448815 0.3694882 I
OS 0.78858265 0.3694882
OS 0.78858265 0.2866142
OS 0.74448815 0.2866142
OS 0.74448815 0.3694882
OE
CE
PIN 7 S 0.6877953 0.1530512 0 U U
CT
OB 0.66574805 0.1944882 I
OS 0.70984255 0.1944882
OS 0.70984255 0.1116142
OS 0.66574805 0.1116142
OS 0.66574805 0.1944882
OE
CE
PIN 8 S 0.6877953 0.3280512 0 U U
CT
OB 0.66574805 0.3694882 I
OS 0.70984255 0.3694882
OS 0.70984255 0.2866142
OS 0.66574805 0.2866142
OS 0.66574805 0.3694882
OE
CE
#
# PKG 23
PKG RESC1005X04N 0.0334646 -0.0295276 -0.011811 0.0295276 0.011811
CT
OB 0.0216535 -0.011811 I
OS -0.0216536 -0.011811
OS -0.0216536 0.011811
OS 0.0216535 0.011811
OS 0.0216535 -0.011811
OE
CE
PIN 1 S -0.0167323 0 0 U U
CT
OB -0.0294323 -0.0118 I
OS -0.0294323 0.0118
OS -0.0040323 0.0118
OS -0.0040323 -0.0118
OS -0.0294323 -0.0118
OE
CE
PIN 2 S 0.0167323 0 0 U U
CT
OB 0.0040323 -0.0118 I
OS 0.0040323 0.0118
OS 0.0294323 0.0118
OS 0.0294323 -0.0118
OS 0.0040323 -0.0118
OE
CE
#
# PKG 24
PKG RESC1608X50N 0.0543307 -0.0413386 -0.019685 0.0413385 0.019685
CT
OB 0.0324803 -0.0187008 I
OS -0.0324804 -0.0187008
OS -0.0324804 0.0187008
OS 0.0324803 0.0187008
OS 0.0324803 -0.0187008
OE
CE
PIN 1 S -0.0271654 0 0 U U
CT
OB -0.0412654 -0.0196 I
OS -0.0412654 0.0196
OS -0.0130654 0.0196
OS -0.0130654 -0.0196
OS -0.0412654 -0.0196
OE
CE
PIN 2 S 0.0271653 0 0 U U
CT
OB 0.0130653 -0.0196 I
OS 0.0130653 0.0196
OS 0.0412653 0.0196
OS 0.0412653 -0.0196
OS 0.0130653 -0.0196
OE
CE
#
# PKG 25
PKG RESC2012X50N 0.0787402 -0.0580709 -0.0285433 0.0580709 0.0285433
CT
OB 0.0433071 -0.0275591 I
OS -0.0433071 -0.0275591
OS -0.0433071 0.027559
OS 0.0433071 0.027559
OS 0.0433071 -0.0275591
OE
CE
PIN 1 S -0.0393701 0 0 U U
CT
OB -0.0580701 -0.0285 I
OS -0.0580701 0.0285
OS -0.0206701 0.0285
OS -0.0206701 -0.0285
OS -0.0580701 -0.0285
OE
CE
PIN 2 S 0.0393701 0 0 U U
CT
OB 0.0206701 -0.0285 I
OS 0.0206701 0.0285
OS 0.0580701 0.0285
OS 0.0580701 -0.0285
OS 0.0206701 -0.0285
OE
CE
#
# PKG 26
PKG SAMTEC_HTST-105-01-L-DV-A 0.1 -0.4000032 -0.2350393 0.3999968 0.2350394
CT
OB 0.3999968 -0.2199993 I
OS -0.4000032 -0.2199993
OS -0.4000032 0.2200007
OS 0.3999968 0.2200007
OS 0.3999968 -0.2199993
OE
CE
PIN 1 S -0.2 -0.1350393 0 U U
CT
OB -0.225 -0.0350393 I
OS -0.175 -0.0350393
OS -0.175 -0.2350393
OS -0.225 -0.2350393
OS -0.225 -0.0350393
OE
CE
PIN 2 S -0.2 0.1350394 0 U U
CT
OB -0.225 0.2350394 I
OS -0.175 0.2350394
OS -0.175 0.0350394
OS -0.225 0.0350394
OS -0.225 0.2350394
OE
CE
PIN 3 S -0.1 -0.1350393 0 U U
CT
OB -0.125 -0.0350393 I
OS -0.075 -0.0350393
OS -0.075 -0.2350393
OS -0.125 -0.2350393
OS -0.125 -0.0350393
OE
CE
PIN 4 S -0.1 0.1350394 0 U U
CT
OB -0.125 0.2350394 I
OS -0.075 0.2350394
OS -0.075 0.0350394
OS -0.125 0.0350394
OS -0.125 0.2350394
OE
CE
PIN 5 S 0 -0.1350393 0 U U
CT
OB -0.025 -0.0350393 I
OS 0.025 -0.0350393
OS 0.025 -0.2350393
OS -0.025 -0.2350393
OS -0.025 -0.0350393
OE
CE
PIN 6 S 0 0.1350394 0 U U
CT
OB -0.025 0.2350394 I
OS 0.025 0.2350394
OS 0.025 0.0350394
OS -0.025 0.0350394
OS -0.025 0.2350394
OE
CE
PIN 7 S 0.1 -0.1350393 0 U U
CT
OB 0.075 -0.0350393 I
OS 0.125 -0.0350393
OS 0.125 -0.2350393
OS 0.075 -0.2350393
OS 0.075 -0.0350393
OE
CE
PIN 8 S 0.1 0.1350394 0 U U
CT
OB 0.075 0.2350394 I
OS 0.125 0.2350394
OS 0.125 0.0350394
OS 0.075 0.0350394
OS 0.075 0.2350394
OE
CE
PIN 9 S 0.2 -0.1350393 0 U U
CT
OB 0.175 -0.0350393 I
OS 0.225 -0.0350393
OS 0.225 -0.2350393
OS 0.175 -0.2350393
OS 0.175 -0.0350393
OE
CE
PIN 10 S 0.2 0.1350394 0 U U
CT
OB 0.175 0.2350394 I
OS 0.225 0.2350394
OS 0.225 0.0350394
OS 0.175 0.0350394
OS 0.175 0.2350394
OE
CE
PIN empty-1 T -0.15 0.0000001 0 U U
CR -0.15 0.0000001 0.03299215
PIN empty-2 T 0.15 0.0000001 0 U U
CR 0.15 0.0000001 0.03299215
#
# PKG 27
PKG SiT5155 0.0462598 -0.0669291 -0.1023622 0.0669291 0.1023622
RC -0.0669291 -0.1023622 0.1338582 0.2047244
PIN 1 S -0.0462598 0.0797244 0 U U
CT
OB -0.0669291 0.1023622 I
OS -0.0255905 0.1023622
OS -0.0255905 0.0570866
OS -0.0669291 0.0570866
OS -0.0669291 0.1023622
OE
CE
PIN 2 S -0.0403543 0.023622 0 U U
CT
OB -0.0669291 0.03740155 I
OS -0.0137795 0.03740155
OS -0.0137795 0.00984245
OS -0.0669291 0.00984245
OS -0.0669291 0.03740155
OE
CE
PIN 3 S -0.0403543 -0.023622 0 U U
CT
OB -0.0669291 -0.00984245 I
OS -0.0137795 -0.00984245
OS -0.0137795 -0.03740155
OS -0.0669291 -0.03740155
OS -0.0669291 -0.00984245
OE
CE
PIN 4 S -0.0462598 -0.0797244 0 U U
CT
OB -0.0669291 -0.0570866 I
OS -0.0255905 -0.0570866
OS -0.0255905 -0.1023622
OS -0.0669291 -0.1023622
OS -0.0669291 -0.0570866
OE
CE
PIN 5 S 0 -0.0797244 0 U U
CT
OB -0.0137 -0.1023244 I
OS -0.0137 -0.0571244
OS 0.0137 -0.0571244
OS 0.0137 -0.1023244
OS -0.0137 -0.1023244
OE
CE
PIN 6 S 0.0462598 -0.0797244 0 U U
CT
OB 0.0255905 -0.0570866 I
OS 0.0669291 -0.0570866
OS 0.0669291 -0.1023622
OS 0.0255905 -0.1023622
OS 0.0255905 -0.0570866
OE
CE
PIN 7 S 0.0403543 -0.023622 0 U U
CT
OB 0.0137795 -0.00984245 I
OS 0.0669291 -0.00984245
OS 0.0669291 -0.03740155
OS 0.0137795 -0.03740155
OS 0.0137795 -0.00984245
OE
CE
PIN 8 S 0.0403543 0.023622 0 U U
CT
OB 0.0137795 0.03740155 I
OS 0.0669291 0.03740155
OS 0.0669291 0.00984245
OS 0.0137795 0.00984245
OS 0.0137795 0.03740155
OE
CE
PIN 9 S 0.0462598 0.0797244 0 U U
CT
OB 0.0255905 0.1023622 I
OS 0.0669291 0.1023622
OS 0.0669291 0.0570866
OS 0.0255905 0.0570866
OS 0.0255905 0.1023622
OE
CE
PIN 10 S 0 0.0797244 0 U U
CT
OB -0.0137 0.0571244 I
OS -0.0137 0.1023244
OS 0.0137 0.1023244
OS 0.0137 0.0571244
OS -0.0137 0.0571244
OE
CE
#
# PKG 28
PKG SIT5721 0.0590551 -0.1299212 -0.1377952 0.1299212 0.1377952
RC -0.1299212 -0.1377952 0.2598424 0.2755904
PIN 1 S -0.0846456 0.1181102 0 U U
CT
OB -0.1299212 0.13779525 I
OS -0.03937 0.13779525
OS -0.03937 0.09842515
OS -0.1299212 0.09842515
OS -0.1299212 0.13779525
OE
CE
PIN 2 S -0.0944882 0.0590551 0 U U
CT
OB -0.12992125 0.07874015 I
OS -0.05905515 0.07874015
OS -0.05905515 0.03937005
OS -0.12992125 0.03937005
OS -0.12992125 0.07874015
OE
CE
PIN 3 S -0.0944882 0 0 U U
CT
OB -0.12992125 0.01968505 I
OS -0.05905515 0.01968505
OS -0.05905515 -0.01968505
OS -0.12992125 -0.01968505
OS -0.12992125 0.01968505
OE
CE
PIN 4 S -0.0944882 -0.0590551 0 U U
CT
OB -0.12992125 -0.03937005 I
OS -0.05905515 -0.03937005
OS -0.05905515 -0.07874015
OS -0.12992125 -0.07874015
OS -0.12992125 -0.03937005
OE
CE
PIN 5 S -0.0944882 -0.1181102 0 U U
CT
OB -0.0590882 -0.1377102 I
OS -0.1298882 -0.1377102
OS -0.1298882 -0.0985102
OS -0.0590882 -0.0985102
OS -0.0590882 -0.1377102
OE
CE
PIN 6 S 0.0944882 -0.1181102 0 U U
CT
OB 0.05905515 -0.09842515 I
OS 0.12992125 -0.09842515
OS 0.12992125 -0.13779525
OS 0.05905515 -0.13779525
OS 0.05905515 -0.09842515
OE
CE
PIN 7 S 0.0944882 -0.0590551 0 U U
CT
OB 0.05905515 -0.03937005 I
OS 0.12992125 -0.03937005
OS 0.12992125 -0.07874015
OS 0.05905515 -0.07874015
OS 0.05905515 -0.03937005
OE
CE
PIN 8 S 0.0944882 0 0 U U
CT
OB 0.05905515 0.01968505 I
OS 0.12992125 0.01968505
OS 0.12992125 -0.01968505
OS 0.05905515 -0.01968505
OS 0.05905515 0.01968505
OE
CE
PIN 9 S 0.0944882 0.0590551 0 U U
CT
OB 0.05905515 0.07874015 I
OS 0.12992125 0.07874015
OS 0.12992125 0.03937005
OS 0.05905515 0.03937005
OS 0.05905515 0.07874015
OE
CE
PIN 10 S 0.0944882 0.1181102 0 U U
CT
OB 0.1298882 0.0985102 I
OS 0.0590882 0.0985102
OS 0.0590882 0.1377102
OS 0.1298882 0.1377102
OS 0.1298882 0.0985102
OE
CE
#
# PKG 29
PKG SM8 0.1259842 -0.15 -0.1003936 0.15 0.1003936
CT
OB 0.118 0.06 I
OS 0.15 0.06
OS 0.15 -0.06
OS 0.118 -0.06
OS 0.118 -0.075
OS 0.098 -0.075
OS 0.098 -0.06
OS -0.098 -0.06
OS -0.098 -0.075
OS -0.118 -0.075
OS -0.118 -0.06
OS -0.15 -0.06
OS -0.15 0.06
OS -0.118 0.06
OS -0.118 0.075
OS -0.098 0.075
OS -0.098 0.06
OS 0.098 0.06
OS 0.098 0.075
OS 0.118 0.075
OS 0.118 0.06
OE
CE
PIN 1 S -0.1082677 -0.0629921 0 U U
CT
OB -0.1337677 -0.1003921 I
OS -0.1337677 -0.0255921
OS -0.0827677 -0.0255921
OS -0.0827677 -0.1003921
OS -0.1337677 -0.1003921
OE
CE
PIN 2 S 0.1082677 -0.0629921 0 U U
CT
OB 0.0827677 -0.1003921 I
OS 0.0827677 -0.0255921
OS 0.1337677 -0.0255921
OS 0.1337677 -0.1003921
OS 0.0827677 -0.1003921
OE
CE
PIN 3 S 0.1082677 0.0629921 0 U U
CT
OB 0.0827677 0.0255921 I
OS 0.0827677 0.1003921
OS 0.1337677 0.1003921
OS 0.1337677 0.0255921
OS 0.0827677 0.0255921
OE
CE
PIN 4 S -0.1082677 0.0629921 0 U U
CT
OB -0.1337677 0.0255921 I
OS -0.1337677 0.1003921
OS -0.0827677 0.1003921
OS -0.0827677 0.0255921
OS -0.1337677 0.0255921
OE
CE
#
# PKG 30
PKG SODFL370X135-2N 0.1437008 -0.0846457 -0.0423901 0.0846457 0.0423715
CT
OB 0.0757774 -0.0423901 I
OS -0.0758002 -0.0423901
OS -0.0758002 0.0423715
OS 0.0757774 0.0423715
OS 0.0757774 -0.0423901
OE
CE
PIN 1 S -0.0718504 0 0 U U
CT
OB -0.0845504 -0.0206 I
OS -0.0845504 0.0206
OS -0.0591504 0.0206
OS -0.0591504 -0.0206
OS -0.0845504 -0.0206
OE
CE
PIN 2 S 0.0718504 0 0 U U
CT
OB 0.0591504 -0.0206 I
OS 0.0591504 0.0206
OS 0.0845504 0.0206
OS 0.0845504 -0.0206
OS 0.0591504 -0.0206
OE
CE
#
# PKG 31
PKG SOIC127P600X175-8N 0.05 -0.1362204 -0.0964656 0.1362204 0.0964496
CT
OB 0.1181152 -0.0964656 I
OS -0.1181024 -0.0964656
OS -0.1181024 0.0964496
OS 0.1181152 0.0964496
OS 0.1181152 -0.0964656
OE
CE
PIN 1 S -0.0974409 0.075 0 U U
CT
OB -0.13622045 0.08622045 I
OS -0.05866135 0.08622045
OS -0.05866135 0.06377955
OS -0.13622045 0.06377955
OS -0.13622045 0.08622045
OE
CE
PIN 2 S -0.0974409 0.025 0 U U
CT
OB -0.13622045 0.03622045 I
OS -0.05866135 0.03622045
OS -0.05866135 0.01377955
OS -0.13622045 0.01377955
OS -0.13622045 0.03622045
OE
CE
PIN 3 S -0.0974409 -0.025 0 U U
CT
OB -0.13622045 -0.01377955 I
OS -0.05866135 -0.01377955
OS -0.05866135 -0.03622045
OS -0.13622045 -0.03622045
OS -0.13622045 -0.01377955
OE
CE
PIN 4 S -0.0974409 -0.075 0 U U
CT
OB -0.13622045 -0.06377955 I
OS -0.05866135 -0.06377955
OS -0.05866135 -0.08622045
OS -0.13622045 -0.08622045
OS -0.13622045 -0.06377955
OE
CE
PIN 5 S 0.0974409 -0.075 0 U U
CT
OB 0.05866135 -0.06377955 I
OS 0.13622045 -0.06377955
OS 0.13622045 -0.08622045
OS 0.05866135 -0.08622045
OS 0.05866135 -0.06377955
OE
CE
PIN 6 S 0.0974409 -0.025 0 U U
CT
OB 0.05866135 -0.01377955 I
OS 0.13622045 -0.01377955
OS 0.13622045 -0.03622045
OS 0.05866135 -0.03622045
OS 0.05866135 -0.01377955
OE
CE
PIN 7 S 0.0974409 0.025 0 U U
CT
OB 0.05866135 0.03622045 I
OS 0.13622045 0.03622045
OS 0.13622045 0.01377955
OS 0.05866135 0.01377955
OS 0.05866135 0.03622045
OE
CE
PIN 8 S 0.0974409 0.075 0 U U
CT
OB 0.05866135 0.08622045 I
OS 0.13622045 0.08622045
OS 0.13622045 0.06377955
OS 0.05866135 0.06377955
OS 0.05866135 0.08622045
OE
CE
#
# PKG 32
PKG SOP64P600X170-16N 0.025 -0.1358268 -0.0984955 0.1358267 0.0985093
CT
OB 0.1220131 -0.0984955 I
OS -0.1219997 -0.0984955
OS -0.1219997 0.0985093
OS 0.1220131 0.0985093
OS 0.1220131 -0.0984955
OE
CE
PIN 1 S -0.1072835 0.0875 0 U U
CT
OB -0.0876835 0.0787 I
OS -0.1268835 0.0787
OC -0.1268835 0.0963 -0.1268835 0.0875 Y
OS -0.0876835 0.0963
OC -0.0876835 0.0787 -0.0876835 0.0875 Y
OE
CE
PIN 2 S -0.1072835 0.0625 0 U U
CT
OB -0.0876835 0.0537 I
OS -0.1268835 0.0537
OC -0.1268835 0.0713 -0.1268835 0.0625 Y
OS -0.0876835 0.0713
OC -0.0876835 0.0537 -0.0876835 0.0625 Y
OE
CE
PIN 3 S -0.1072835 0.0375 0 U U
CT
OB -0.0876835 0.0287 I
OS -0.1268835 0.0287
OC -0.1268835 0.0463 -0.1268835 0.0375 Y
OS -0.0876835 0.0463
OC -0.0876835 0.0287 -0.0876835 0.0375 Y
OE
CE
PIN 4 S -0.1072835 0.0125 0 U U
CT
OB -0.0876835 0.0037 I
OS -0.1268835 0.0037
OC -0.1268835 0.0213 -0.1268835 0.0125 Y
OS -0.0876835 0.0213
OC -0.0876835 0.0037 -0.0876835 0.0125 Y
OE
CE
PIN 5 S -0.1072835 -0.0125 0 U U
CT
OB -0.0876835 -0.0213 I
OS -0.1268835 -0.0213
OC -0.1268835 -0.0037 -0.1268835 -0.0125 Y
OS -0.0876835 -0.0037
OC -0.0876835 -0.0213 -0.0876835 -0.0125 Y
OE
CE
PIN 6 S -0.1072835 -0.0375 0 U U
CT
OB -0.0876835 -0.0463 I
OS -0.1268835 -0.0463
OC -0.1268835 -0.0287 -0.1268835 -0.0375 Y
OS -0.0876835 -0.0287
OC -0.0876835 -0.0463 -0.0876835 -0.0375 Y
OE
CE
PIN 7 S -0.1072835 -0.0625 0 U U
CT
OB -0.0876835 -0.0713 I
OS -0.1268835 -0.0713
OC -0.1268835 -0.0537 -0.1268835 -0.0625 Y
OS -0.0876835 -0.0537
OC -0.0876835 -0.0713 -0.0876835 -0.0625 Y
OE
CE
PIN 8 S -0.1072835 -0.0875 0 U U
CT
OB -0.0876835 -0.0963 I
OS -0.1268835 -0.0963
OC -0.1268835 -0.0787 -0.1268835 -0.0875 Y
OS -0.0876835 -0.0787
OC -0.0876835 -0.0963 -0.0876835 -0.0875 Y
OE
CE
PIN 9 S 0.1072834 -0.0875 0 U U
CT
OB 0.1268834 -0.0963 I
OS 0.0876834 -0.0963
OC 0.0876834 -0.0787 0.0876834 -0.0875 Y
OS 0.1268834 -0.0787
OC 0.1268834 -0.0963 0.1268834 -0.0875 Y
OE
CE
PIN 10 S 0.1072834 -0.0625 0 U U
CT
OB 0.1268834 -0.0713 I
OS 0.0876834 -0.0713
OC 0.0876834 -0.0537 0.0876834 -0.0625 Y
OS 0.1268834 -0.0537
OC 0.1268834 -0.0713 0.1268834 -0.0625 Y
OE
CE
PIN 11 S 0.1072834 -0.0375 0 U U
CT
OB 0.1268834 -0.0463 I
OS 0.0876834 -0.0463
OC 0.0876834 -0.0287 0.0876834 -0.0375 Y
OS 0.1268834 -0.0287
OC 0.1268834 -0.0463 0.1268834 -0.0375 Y
OE
CE
PIN 12 S 0.1072834 -0.0125 0 U U
CT
OB 0.1268834 -0.0213 I
OS 0.0876834 -0.0213
OC 0.0876834 -0.0037 0.0876834 -0.0125 Y
OS 0.1268834 -0.0037
OC 0.1268834 -0.0213 0.1268834 -0.0125 Y
OE
CE
PIN 13 S 0.1072834 0.0125 0 U U
CT
OB 0.1268834 0.0037 I
OS 0.0876834 0.0037
OC 0.0876834 0.0213 0.0876834 0.0125 Y
OS 0.1268834 0.0213
OC 0.1268834 0.0037 0.1268834 0.0125 Y
OE
CE
PIN 14 S 0.1072834 0.0375 0 U U
CT
OB 0.1268834 0.0287 I
OS 0.0876834 0.0287
OC 0.0876834 0.0463 0.0876834 0.0375 Y
OS 0.1268834 0.0463
OC 0.1268834 0.0287 0.1268834 0.0375 Y
OE
CE
PIN 15 S 0.1072834 0.0625 0 U U
CT
OB 0.1268834 0.0537 I
OS 0.0876834 0.0537
OC 0.0876834 0.0713 0.0876834 0.0625 Y
OS 0.1268834 0.0713
OC 0.1268834 0.0537 0.1268834 0.0625 Y
OE
CE
PIN 16 S 0.1072834 0.0875 0 U U
CT
OB 0.1268834 0.0787 I
OS 0.0876834 0.0787
OC 0.0876834 0.0963 0.0876834 0.0875 Y
OS 0.1268834 0.0963
OC 0.1268834 0.0787 0.1268834 0.0875 Y
OE
CE
#
# PKG 33
PKG SOT65P210X110-3N 0.0511811 -0.0620078 -0.0433121 0.0620079 0.0432991
CT
OB 0.0392002 -0.0433121 I
OS -0.0491902 -0.0433121
OS -0.0491902 0.0432991
OS 0.0392002 0.0432991
OS 0.0392002 -0.0433121
OE
CE
PIN 1 S -0.0442913 0.0255906 0 U U
CT
OB -0.0619913 0.0157906 I
OS -0.0619913 0.0353906
OS -0.0265913 0.0353906
OS -0.0265913 0.0157906
OS -0.0619913 0.0157906
OE
CE
PIN 2 S -0.0442913 -0.0255905 0 U U
CT
OB -0.0619913 -0.0353905 I
OS -0.0619913 -0.0157905
OS -0.0265913 -0.0157905
OS -0.0265913 -0.0353905
OS -0.0619913 -0.0353905
OE
CE
PIN 3 S 0.0442914 0 0 U U
CT
OB 0.0265914 -0.0098 I
OS 0.0265914 0.0098
OS 0.0619914 0.0098
OS 0.0619914 -0.0098
OS 0.0265914 -0.0098
OE
CE
#
# PKG 34
PKG U.FL_UMCC_JACK 0.0835282 -0.0787402 -0.0807087 0.0787402 0.061024
CT
OB 0.0590528 -0.061024 I
OS -0.0590592 -0.061024
OS -0.0590592 0.061024
OS 0.0590528 0.061024
OS 0.0590528 -0.061024
OE
CE
PIN 1 S 0 -0.0600394 0 U U
CT
OB -0.01968505 -0.0393701 I
OS 0.01968505 -0.0393701
OS 0.01968505 -0.0807087
OS -0.01968505 -0.0807087
OS -0.01968505 -0.0393701
OE
CE
PIN 2 S -0.0580709 0 0 U U
CT
OB -0.0787402 0.0433071 I
OS -0.0374016 0.0433071
OS -0.0374016 -0.0433071
OS -0.0787402 -0.0433071
OS -0.0787402 0.0433071
OE
CE
PIN 3 S 0.0580709 0 0 U U
CT
OB 0.0374016 0.0433071 I
OS 0.0787402 0.0433071
OS 0.0787402 -0.0433071
OS 0.0374016 -0.0433071
OS 0.0374016 0.0433071
OE
CE
#
# PKG 35
PKG USB_1734035 0.031496 -0.1515749 -0.3346457 0.2775591 0.0452756
CT
OB 0.2588582 -0.3346457 I
OS -0.1309082 -0.3346457
OS -0.1309082 0.0275591
OS 0.2588582 0.0275591
OS 0.2588582 -0.3346457
OE
CE
PIN 0 T -0.0236221 -0.1023622 0 U U
CR -0.0236221 -0.1023622 0.01574805
PIN 0 T 0.1496063 -0.1023622 0 U U
CR 0.1496063 -0.1023622 0.01574805
PIN 0 S -0.1122048 -0.2204724 0 U U
CT
OB -0.1515749 -0.1712598 I
OS -0.0728347 -0.1712598
OS -0.0728347 -0.269685
OS -0.1515749 -0.269685
OS -0.1515749 -0.1712598
OE
CE
PIN 0 S -0.1122048 -0.003937 0 U U
CT
OB -0.1515749 0.0452756 I
OS -0.0728347 0.0452756
OS -0.0728347 -0.0531496
OS -0.1515749 -0.0531496
OS -0.1515749 0.0452756
OE
CE
PIN 0 S 0.238189 -0.003937 0 U U
CT
OB 0.1988189 0.0452756 I
OS 0.2775591 0.0452756
OS 0.2775591 -0.0531496
OS 0.1988189 -0.0531496
OS 0.1988189 0.0452756
OE
CE
PIN 0 S 0.238189 -0.2204724 0 U U
CT
OB 0.1988189 -0.1712598 I
OS 0.2775591 -0.1712598
OS 0.2775591 -0.269685
OS 0.1988189 -0.269685
OS 0.1988189 -0.1712598
OE
CE
PIN 1 S 0 0 0 U U
CT
OB -0.0098425 0.0452756 I
OS 0.0098425 0.0452756
OS 0.0098425 -0.0452756
OS -0.0098425 -0.0452756
OS -0.0098425 0.0452756
OE
CE
PIN 2 S 0.031496 0 0 U U
CT
OB 0.0216535 0.0452756 I
OS 0.0413385 0.0452756
OS 0.0413385 -0.0452756
OS 0.0216535 -0.0452756
OS 0.0216535 0.0452756
OE
CE
PIN 3 S 0.0629921 0 0 U U
CT
OB 0.0531496 0.0452756 I
OS 0.0728346 0.0452756
OS 0.0728346 -0.0452756
OS 0.0531496 -0.0452756
OS 0.0531496 0.0452756
OE
CE
PIN 4 S 0.0944882 0 0 U U
CT
OB 0.0846457 0.0452756 I
OS 0.1043307 0.0452756
OS 0.1043307 -0.0452756
OS 0.0846457 -0.0452756
OS 0.0846457 0.0452756
OE
CE
PIN 5 S 0.1259842 0 0 U U
CT
OB 0.1161417 0.0452756 I
OS 0.1358267 0.0452756
OS 0.1358267 -0.0452756
OS 0.1161417 -0.0452756
OS 0.1161417 0.0452756
OE
CE
#
# PKG 36
PKG USB_47346-1001 0.0255905 -0.1141732 -0.187001 0.2165354 0.0271653
CT
OB 0.2047299 -0.187001 I
OS -0.1023549 -0.187001
OS -0.1023549 0.009847
OS 0.2047299 0.009847
OS 0.2047299 -0.187001
OE
CE
PIN 0 S 0.1122047 -0.1047244 0 U U
CT
OB 0.09251965 -0.06732285 I
OS 0.13188975 -0.06732285
OS 0.13188975 -0.14212595
OS 0.09251965 -0.14212595
OS 0.09251965 -0.06732285
OE
CE
PIN 0 S 0.0059055 -0.1047244 0 U U
CT
OB -0.02952755 -0.06732285 I
OS 0.04133855 -0.06732285
OS 0.04133855 -0.14212595
OS -0.02952755 -0.14212595
OS -0.02952755 -0.06732285
OE
CE
PIN 0 S 0.1496063 -0.0033465 0 U U
CT
OB 0.12165355 0.0271653 I
OS 0.17755905 0.0271653
OS 0.17755905 -0.0338583
OS 0.12165355 -0.0338583
OS 0.12165355 0.0271653
OE
CE
PIN 0 S -0.0472441 -0.0033465 0 U U
CT
OB -0.07519685 0.0271653 I
OS -0.01929135 0.0271653
OS -0.01929135 -0.0338583
OS -0.07519685 -0.0338583
OS -0.07519685 0.0271653
OE
CE
PIN 0 S -0.0816929 -0.1047244 0 U U
CT
OB -0.1141732 -0.07913385 I
OS -0.0492126 -0.07913385
OS -0.0492126 -0.13031495
OS -0.1141732 -0.13031495
OS -0.1141732 -0.07913385
OE
CE
PIN 0 S 0.1840551 -0.1047244 0 U U
CT
OB 0.1515748 -0.07913385 I
OS 0.2165354 -0.07913385
OS 0.2165354 -0.13031495
OS 0.1515748 -0.13031495
OS 0.1515748 -0.07913385
OE
CE
PIN 1 S 0 0 0 U U
CT
OB -0.00885825 0.02716535 I
OS 0.00885825 0.02716535
OS 0.00885825 -0.02716535
OS -0.00885825 -0.02716535
OS -0.00885825 0.02716535
OE
CE
PIN 2 S 0.0255905 0 0 U U
CT
OB 0.01673225 0.02716535 I
OS 0.03444875 0.02716535
OS 0.03444875 -0.02716535
OS 0.01673225 -0.02716535
OS 0.01673225 0.02716535
OE
CE
PIN 3 S 0.0511811 0 0 U U
CT
OB 0.04232285 0.02716535 I
OS 0.06003935 0.02716535
OS 0.06003935 -0.02716535
OS 0.04232285 -0.02716535
OS 0.04232285 0.02716535
OE
CE
PIN 4 S 0.0767717 0 0 U U
CT
OB 0.06791345 0.02716535 I
OS 0.08562995 0.02716535
OS 0.08562995 -0.02716535
OS 0.06791345 -0.02716535
OS 0.06791345 0.02716535
OE
CE
PIN 5 S 0.1023622 0 0 U U
CT
OB 0.09350395 0.02716535 I
OS 0.11122045 0.02716535
OS 0.11122045 -0.02716535
OS 0.09350395 -0.02716535
OS 0.09350395 0.02716535
OE
CE
#
# PKG 37
PKG W16-H2_L 0.05 -0.2165354 -0.2066929 0.2165355 0.2066929
CT
OB 0.1496064 -0.2066929 I
OS -0.1496062 -0.2066929
OS -0.1496062 0.2066929
OS 0.1496064 0.2066929
OS 0.1496064 -0.2066929
OE
CE
PIN 1 S -0.1771653 0.175 0 U U
CT
OB -0.1496653 0.1632 I
OS -0.2046653 0.1632
OC -0.2046653 0.1868 -0.2046653 0.175 Y
OS -0.1496653 0.1868
OC -0.1496653 0.1632 -0.1496653 0.175 Y
OE
CE
PIN 2 S -0.1771653 0.125 0 U U
CT
OB -0.1496653 0.1132 I
OS -0.2046653 0.1132
OC -0.2046653 0.1368 -0.2046653 0.125 Y
OS -0.1496653 0.1368
OC -0.1496653 0.1132 -0.1496653 0.125 Y
OE
CE
PIN 3 S -0.1771653 0.075 0 U U
CT
OB -0.1496653 0.0632 I
OS -0.2046653 0.0632
OC -0.2046653 0.0868 -0.2046653 0.075 Y
OS -0.1496653 0.0868
OC -0.1496653 0.0632 -0.1496653 0.075 Y
OE
CE
PIN 4 S -0.1771653 0.025 0 U U
CT
OB -0.1496653 0.0132 I
OS -0.2046653 0.0132
OC -0.2046653 0.0368 -0.2046653 0.025 Y
OS -0.1496653 0.0368
OC -0.1496653 0.0132 -0.1496653 0.025 Y
OE
CE
PIN 5 S -0.1771653 -0.025 0 U U
CT
OB -0.1496653 -0.0368 I
OS -0.2046653 -0.0368
OC -0.2046653 -0.0132 -0.2046653 -0.025 Y
OS -0.1496653 -0.0132
OC -0.1496653 -0.0368 -0.1496653 -0.025 Y
OE
CE
PIN 6 S -0.1771653 -0.075 0 U U
CT
OB -0.1496653 -0.0868 I
OS -0.2046653 -0.0868
OC -0.2046653 -0.0632 -0.2046653 -0.075 Y
OS -0.1496653 -0.0632
OC -0.1496653 -0.0868 -0.1496653 -0.075 Y
OE
CE
PIN 7 S -0.1771653 -0.125 0 U U
CT
OB -0.1496653 -0.1368 I
OS -0.2046653 -0.1368
OC -0.2046653 -0.1132 -0.2046653 -0.125 Y
OS -0.1496653 -0.1132
OC -0.1496653 -0.1368 -0.1496653 -0.125 Y
OE
CE
PIN 8 S -0.1771653 -0.175 0 U U
CT
OB -0.1496653 -0.1868 I
OS -0.2046653 -0.1868
OC -0.2046653 -0.1632 -0.2046653 -0.175 Y
OS -0.1496653 -0.1632
OC -0.1496653 -0.1868 -0.1496653 -0.175 Y
OE
CE
PIN 9 S 0.1771654 -0.175 0 U U
CT
OB 0.2046654 -0.1868 I
OS 0.1496654 -0.1868
OC 0.1496654 -0.1632 0.1496654 -0.175 Y
OS 0.2046654 -0.1632
OC 0.2046654 -0.1868 0.2046654 -0.175 Y
OE
CE
PIN 10 S 0.1771654 -0.125 0 U U
CT
OB 0.2046654 -0.1368 I
OS 0.1496654 -0.1368
OC 0.1496654 -0.1132 0.1496654 -0.125 Y
OS 0.2046654 -0.1132
OC 0.2046654 -0.1368 0.2046654 -0.125 Y
OE
CE
PIN 11 S 0.1771654 -0.075 0 U U
CT
OB 0.2046654 -0.0868 I
OS 0.1496654 -0.0868
OC 0.1496654 -0.0632 0.1496654 -0.075 Y
OS 0.2046654 -0.0632
OC 0.2046654 -0.0868 0.2046654 -0.075 Y
OE
CE
PIN 12 S 0.1771654 -0.025 0 U U
CT
OB 0.2046654 -0.0368 I
OS 0.1496654 -0.0368
OC 0.1496654 -0.0132 0.1496654 -0.025 Y
OS 0.2046654 -0.0132
OC 0.2046654 -0.0368 0.2046654 -0.025 Y
OE
CE
PIN 13 S 0.1771654 0.025 0 U U
CT
OB 0.2046654 0.0132 I
OS 0.1496654 0.0132
OC 0.1496654 0.0368 0.1496654 0.025 Y
OS 0.2046654 0.0368
OC 0.2046654 0.0132 0.2046654 0.025 Y
OE
CE
PIN 14 S 0.1771654 0.075 0 U U
CT
OB 0.2046654 0.0632 I
OS 0.1496654 0.0632
OC 0.1496654 0.0868 0.1496654 0.075 Y
OS 0.2046654 0.0868
OC 0.2046654 0.0632 0.2046654 0.075 Y
OE
CE
PIN 15 S 0.1771654 0.125 0 U U
CT
OB 0.2046654 0.1132 I
OS 0.1496654 0.1132
OC 0.1496654 0.1368 0.1496654 0.125 Y
OS 0.2046654 0.1368
OC 0.2046654 0.1132 0.2046654 0.125 Y
OE
CE
PIN 16 S 0.1771654 0.175 0 U U
CT
OB 0.2046654 0.1632 I
OS 0.1496654 0.1632
OC 0.1496654 0.1868 0.1496654 0.175 Y
OS 0.2046654 0.1868
OC 0.2046654 0.1632 0.2046654 0.175 Y
OE
CE
#
FGR TEXT
# FGR 0
PRP string 'BT1'
FID C 6 2028
FID C 6 2026
FID C 6 2038
FID C 6 2042
FID C 6 2043
FID C 6 2039
FID C 6 2027
FID C 6 2040
FID C 6 2044
FID C 6 2045
FID C 6 2041
FID C 6 2058
FID C 6 2086
FID C 6 2074
FID C 6 2100
FID C 6 2108
FID C 6 2102
FID C 6 2103
#
FGR TEXT
# FGR 1
PRP string 'U10AL'
FID C 6 1707
FID C 6 1706
FID C 6 1714
FID C 6 1739
FID C 6 1750
FID C 6 1773
FID C 6 1786
FID C 6 1777
FID C 6 1778
FID C 6 1793
FID C 6 1798
FID C 6 1803
FID C 6 1809
FID C 6 1808
FID C 6 1802
FID C 6 1797
FID C 6 1792
FID C 6 1819
FID C 6 1820
FID C 6 1837
FID C 6 1849
FID C 6 1847
FID C 6 1848
FID C 6 1856
FID C 6 1855
#
FGR TEXT
# FGR 2
PRP string 'U3'
FID C 6 1035
FID C 6 1034
FID C 6 1036
FID C 6 1037
FID C 6 1039
FID C 6 1045
FID C 6 1049
FID C 6 1057
FID C 6 1063
FID C 6 1062
FID C 6 1055
FID C 6 1053
FID C 6 1056
FID C 6 1061
FID C 6 1060
FID C 6 1054
FID C 6 1048
#
FGR TEXT
# FGR 3
PRP string 'R1'
FID C 6 1708
FID C 6 1709
FID C 6 1741
FID C 6 1752
FID C 6 1751
FID C 6 1740
FID C 6 1727
FID C 6 1774
FID C 6 1787
FID C 6 1779
FID C 6 1780
#
FGR TEXT
# FGR 4
PRP string 'R14'
FID C 6 485
FID C 6 486
FID C 6 495
FID C 6 500
FID C 6 499
FID C 6 494
FID C 6 489
FID C 6 502
FID C 6 511
FID C 6 507
FID C 6 508
FID C 6 525
FID C 6 526
FID C 6 520
#
FGR TEXT
# FGR 5
PRP string 'R17'
FID C 6 875
FID C 6 876
FID C 6 880
FID C 6 884
FID C 6 883
FID C 6 879
FID C 6 878
FID C 6 890
FID C 6 895
FID C 6 892
FID C 6 893
FID C 6 903
FID C 6 921
FID C 6 920
FID C 6 902
#
FGR TEXT
# FGR 6
PRP string 'IC?'
FID C 6 1177
FID C 6 1189
FID C 6 1181
FID C 6 1180
FID C 6 1176
FID C 6 1204
FID C 6 1199
FID C 6 1196
FID C 6 1192
FID C 6 1191
FID C 6 1195
FID C 6 1198
FID C 6 1207
FID C 6 1208
FID C 6 1214
FID C 6 1218
FID C 6 1217
FID C 6 1209
#
FGR TEXT
# FGR 7
PRP string 'P2'
FID C 6 687
FID C 6 688
FID C 6 691
FID C 6 693
FID C 6 692
FID C 6 690
FID C 6 699
FID C 6 696
FID C 6 700
FID C 6 701
FID C 6 698
FID C 6 697
#
FGR TEXT
# FGR 8
PRP string 'R36'
FID C 6 305
FID C 6 306
FID C 6 341
FID C 6 347
FID C 6 346
FID C 6 340
FID C 6 323
FID C 6 360
FID C 6 368
FID C 6 385
FID C 6 395
FID C 6 394
FID C 6 383
FID C 6 371
FID C 6 384
FID C 6 393
FID C 6 392
FID C 6 382
FID C 6 367
FID C 6 445
FID C 6 425
FID C 6 406
FID C 6 405
FID C 6 419
FID C 6 435
FID C 6 443
FID C 6 444
FID C 6 436
#
FGR TEXT
# FGR 9
PRP string 'R16'
FID C 6 476
FID C 6 477
FID C 6 480
FID C 6 482
FID C 6 481
FID C 6 479
FID C 6 478
FID C 6 487
FID C 6 496
FID C 6 490
FID C 6 491
FID C 6 517
FID C 6 512
FID C 6 504
FID C 6 503
FID C 6 509
FID C 6 513
FID C 6 515
FID C 6 516
FID C 6 514
#
FGR TEXT
# FGR 10
PRP string 'R15'
FID C 6 483
FID C 6 484
FID C 6 493
FID C 6 498
FID C 6 497
FID C 6 492
FID C 6 488
FID C 6 501
FID C 6 510
FID C 6 505
FID C 6 506
FID C 6 529
FID C 6 519
FID C 6 518
FID C 6 522
FID C 6 524
FID C 6 528
FID C 6 527
FID C 6 523
FID C 6 521
#
FGR TEXT
# FGR 11
PRP string 'P1'
FID C 6 627
FID C 6 628
FID C 6 644
FID C 6 646
FID C 6 645
FID C 6 643
FID C 6 651
FID C 6 654
FID C 6 652
FID C 6 653
#
FGR TEXT
# FGR 12
PRP string '1'
FID C 6 1315
FID C 6 1326
FID C 6 1322
FID C 6 1323
#
FGR TEXT
# FGR 13
PRP string '2'
FID C 6 819
FID C 6 793
FID C 6 820
FID C 6 821
FID C 6 818
FID C 6 801
#
FGR TEXT
# FGR 14
PRP string '3'
FID C 6 664
FID C 6 671
FID C 6 676
FID C 6 680
FID C 6 679
FID C 6 674
FID C 6 672
FID C 6 675
FID C 6 678
FID C 6 677
FID C 6 673
FID C 6 670
#
FGR TEXT
# FGR 15
PRP string '4'
FID C 6 816
FID C 6 817
FID C 6 792
#
FGR TEXT
# FGR 16
PRP string '1'
FID C 6 889
FID C 6 887
FID C 6 888
FID C 6 929
#
FGR TEXT
# FGR 17
PRP string '1'
FID C 6 1608
FID C 6 1592
FID C 6 1597
FID C 6 1596
#
FGR TEXT
# FGR 18
PRP string 'JP2'
FID C 6 726
FID C 6 724
FID C 6 725
FID C 6 758
FID C 6 762
FID C 6 761
FID C 6 763
FID C 6 727
FID C 6 728
FID C 6 732
FID C 6 748
FID C 6 753
FID C 6 765
FID C 6 764
FID C 6 739
FID C 6 733
FID C 6 730
FID C 6 729
#
FGR TEXT
# FGR 19
PRP string 'JP1'
FID C 6 584
FID C 6 581
FID C 6 583
FID C 6 582
FID C 6 580
FID C 6 577
FID C 6 585
FID C 6 586
FID C 6 590
FID C 6 592
FID C 6 591
FID C 6 589
FID C 6 593
FID C 6 596
FID C 6 594
FID C 6 595
#
FGR TEXT
# FGR 20
PRP string 'C72'
FID C 6 1915
FID C 6 1903
FID C 6 1902
FID C 6 1914
FID C 6 1937
FID C 6 1944
FID C 6 1945
FID C 6 1904
FID C 6 1905
FID C 6 1916
FID C 6 1938
FID C 6 1947
FID C 6 1946
FID C 6 1926
FID C 6 1917
FID C 6 1907
FID C 6 1906
#
FGR TEXT
# FGR 21
PRP string 'C73'
FID C 6 1839
FID C 6 1828
FID C 6 1827
FID C 6 1838
FID C 6 1857
FID C 6 1865
FID C 6 1866
FID C 6 1829
FID C 6 1830
FID C 6 1840
FID C 6 1858
FID C 6 1841
FID C 6 1831
FID C 6 1832
FID C 6 1842
FID C 6 1844
FID C 6 1851
FID C 6 1850
FID C 6 1852
FID C 6 1853
FID C 6 1859
FID C 6 1868
FID C 6 1867
#
FGR TEXT
# FGR 22
PRP string 'C74'
FID C 6 1497
FID C 6 1493
FID C 6 1483
FID C 6 1480
FID C 6 1479
FID C 6 1482
FID C 6 1492
FID C 6 1507
FID C 6 1529
FID C 6 1528
FID C 6 1506
FID C 6 1558
FID C 6 1559
FID C 6 1538
#
FGR TEXT
# FGR 23
PRP string 'C75'
FID C 6 1614
FID C 6 1612
FID C 6 1610
FID C 6 1603
FID C 6 1602
FID C 6 1609
FID C 6 1611
FID C 6 1627
FID C 6 1633
FID C 6 1632
FID C 6 1626
FID C 6 1645
FID C 6 1637
FID C 6 1636
FID C 6 1639
FID C 6 1641
FID C 6 1644
FID C 6 1643
FID C 6 1640
FID C 6 1638
#
FGR TEXT
# FGR 24
PRP string 'C76'
FID C 6 1589
FID C 6 1584
FID C 6 1583
FID C 6 1588
FID C 6 1598
FID C 6 1604
FID C 6 1605
FID C 6 1585
FID C 6 1586
FID C 6 1590
FID C 6 1599
FID C 6 1587
FID C 6 1591
FID C 6 1593
FID C 6 1600
FID C 6 1606
FID C 6 1607
FID C 6 1601
FID C 6 1595
FID C 6 1594
#
FGR TEXT
# FGR 25
PRP string 'C77'
FID C 6 1622
FID C 6 1616
FID C 6 1615
FID C 6 1621
FID C 6 1629
FID C 6 1634
FID C 6 1635
FID C 6 1617
FID C 6 1618
FID C 6 1623
FID C 6 1630
FID C 6 1619
FID C 6 1620
FID C 6 1624
FID C 6 1631
#
FGR TEXT
# FGR 26
PRP string 'C78'
FID C 6 1655
FID C 6 1647
FID C 6 1646
FID C 6 1654
FID C 6 1666
FID C 6 1670
FID C 6 1671
FID C 6 1648
FID C 6 1649
FID C 6 1656
FID C 6 1667
FID C 6 1657
FID C 6 1650
FID C 6 1651
FID C 6 1658
FID C 6 1660
FID C 6 1663
FID C 6 1665
FID C 6 1669
FID C 6 1673
FID C 6 1672
FID C 6 1668
FID C 6 1664
FID C 6 1661
FID C 6 1659
FID C 6 1662
#
FGR TEXT
# FGR 27
PRP string 'C79'
FID C 6 1683
FID C 6 1676
FID C 6 1675
FID C 6 1682
FID C 6 1722
FID C 6 1731
FID C 6 1732
FID C 6 1677
FID C 6 1678
FID C 6 1684
FID C 6 1723
FID C 6 1724
FID C 6 1733
FID C 6 1734
FID C 6 1725
FID C 6 1686
FID C 6 1680
FID C 6 1679
FID C 6 1685
FID C 6 1694
FID C 6 1702
#
FGR TEXT
# FGR 28
PRP string 'C80'
FID C 6 1919
FID C 6 1909
FID C 6 1908
FID C 6 1918
FID C 6 1939
FID C 6 1948
FID C 6 1949
FID C 6 1920
FID C 6 1910
FID C 6 1911
FID C 6 1921
FID C 6 1928
FID C 6 1933
FID C 6 1935
FID C 6 1941
FID C 6 1951
FID C 6 1950
FID C 6 1940
FID C 6 1934
FID C 6 1931
FID C 6 1927
FID C 6 1932
FID C 6 1922
FID C 6 1912
FID C 6 1913
FID C 6 1923
FID C 6 1943
FID C 6 1953
FID C 6 1952
FID C 6 1942
#
FGR TEXT
# FGR 29
PRP string 'C81'
FID C 6 1963
FID C 6 1958
FID C 6 1957
FID C 6 1962
FID C 6 1975
FID C 6 1985
FID C 6 1986
FID C 6 1964
FID C 6 1959
FID C 6 1960
FID C 6 1965
FID C 6 1967
FID C 6 1970
FID C 6 1972
FID C 6 1977
FID C 6 1988
FID C 6 1987
FID C 6 1976
FID C 6 1971
FID C 6 1968
FID C 6 1966
FID C 6 1969
FID C 6 1989
FID C 6 1991
FID C 6 1990
FID C 6 1961
#
FGR TEXT
# FGR 30
PRP string 'C82'
FID C 6 2007
FID C 6 1999
FID C 6 1998
FID C 6 2006
FID C 6 2029
FID C 6 2032
FID C 6 2033
FID C 6 2008
FID C 6 2000
FID C 6 2001
FID C 6 2009
FID C 6 2013
FID C 6 2018
FID C 6 2022
FID C 6 2031
FID C 6 2035
FID C 6 2034
FID C 6 2030
FID C 6 2021
FID C 6 2016
FID C 6 2012
FID C 6 2017
FID C 6 2037
FID C 6 2036
FID C 6 2014
FID C 6 2010
FID C 6 2003
FID C 6 2002
#
FGR TEXT
# FGR 31
PRP string 'C83'
FID C 6 2053
FID C 6 2047
FID C 6 2046
FID C 6 2052
FID C 6 2082
FID C 6 2093
FID C 6 2094
FID C 6 2054
FID C 6 2048
FID C 6 2049
FID C 6 2055
FID C 6 2060
FID C 6 2070
FID C 6 2078
FID C 6 2084
FID C 6 2096
FID C 6 2095
FID C 6 2083
FID C 6 2077
FID C 6 2068
FID C 6 2059
FID C 6 2069
FID C 6 2056
FID C 6 2050
FID C 6 2051
FID C 6 2057
FID C 6 2061
FID C 6 2072
FID C 6 2071
FID C 6 2073
FID C 6 2079
FID C 6 2085
FID C 6 2098
FID C 6 2097
#
FGR TEXT
# FGR 32
PRP string 'C84'
FID C 6 1799
FID C 6 1795
FID C 6 1791
FID C 6 1789
FID C 6 1788
FID C 6 1790
FID C 6 1794
FID C 6 1807
FID C 6 1815
FID C 6 1824
FID C 6 1836
FID C 6 1835
FID C 6 1823
FID C 6 1834
FID C 6 1833
FID C 6 1822
FID C 6 1812
FID C 6 1804
FID C 6 1805
FID C 6 1813
FID C 6 1806
FID C 6 1814
FID C 6 1860
FID C 6 1861
FID C 6 1845
#
FGR TEXT
# FGR 33
PRP string 'C85'
FID C 6 2833
FID C 6 2824
FID C 6 2815
FID C 6 2807
FID C 6 2806
FID C 6 2814
FID C 6 2823
FID C 6 2848
FID C 6 2858
FID C 6 2871
FID C 6 2876
FID C 6 2875
FID C 6 2870
FID C 6 2874
FID C 6 2873
FID C 6 2869
FID C 6 2855
FID C 6 2845
FID C 6 2846
FID C 6 2856
FID C 6 2847
FID C 6 2857
FID C 6 2898
FID C 6 2878
FID C 6 2877
FID C 6 2881
FID C 6 2889
FID C 6 2897
FID C 6 2896
FID C 6 2888
FID C 6 2880
#
FGR TEXT
# FGR 34
PRP string 'C86'
FID C 6 2775
FID C 6 2770
FID C 6 2764
FID C 6 2760
FID C 6 2759
FID C 6 2763
FID C 6 2769
FID C 6 2781
FID C 6 2787
FID C 6 2796
FID C 6 2811
FID C 6 2810
FID C 6 2795
FID C 6 2809
FID C 6 2808
FID C 6 2794
FID C 6 2784
FID C 6 2778
FID C 6 2779
FID C 6 2785
FID C 6 2780
FID C 6 2786
FID C 6 2852
FID C 6 2834
FID C 6 2822
FID C 6 2821
FID C 6 2828
FID C 6 2842
FID C 6 2850
FID C 6 2851
FID C 6 2843
#
FGR TEXT
# FGR 35
PRP string 'C91'
FID C 6 717
FID C 6 712
FID C 6 711
FID C 6 716
FID C 6 734
FID C 6 740
FID C 6 741
FID C 6 735
FID C 6 742
FID C 6 743
FID C 6 736
FID C 6 719
FID C 6 714
FID C 6 713
FID C 6 718
FID C 6 722
FID C 6 723
FID C 6 744
FID C 6 746
FID C 6 745
FID C 6 715
#
FGR TEXT
# FGR 36
PRP string 'C92'
FID C 6 607
FID C 6 606
FID C 6 604
FID C 6 601
FID C 6 600
FID C 6 603
FID C 6 605
FID C 6 608
FID C 6 611
FID C 6 621
FID C 6 623
FID C 6 624
FID C 6 622
FID C 6 613
FID C 6 610
FID C 6 609
FID C 6 612
FID C 6 648
FID C 6 630
FID C 6 649
FID C 6 650
FID C 6 647
FID C 6 635
#
FGR TEXT
# FGR 37
PRP string 'R42'
FID C 6 1253
FID C 6 1254
FID C 6 1257
FID C 6 1263
FID C 6 1262
FID C 6 1256
FID C 6 1255
FID C 6 1278
FID C 6 1279
FID C 6 1269
FID C 6 1308
FID C 6 1294
FID C 6 1309
FID C 6 1310
FID C 6 1305
FID C 6 1298
#
FGR TEXT
# FGR 38
PRP string 'R43'
FID C 6 702
FID C 6 703
FID C 6 706
FID C 6 709
FID C 6 708
FID C 6 705
FID C 6 704
FID C 6 720
FID C 6 721
FID C 6 710
FID C 6 731
FID C 6 738
FID C 6 752
FID C 6 757
FID C 6 756
FID C 6 750
FID C 6 747
FID C 6 751
FID C 6 755
FID C 6 754
FID C 6 749
FID C 6 737
#
FGR TEXT
# FGR 39
PRP string 'U16'
FID C 6 614
FID C 6 631
FID C 6 636
FID C 6 637
FID C 6 632
FID C 6 638
FID C 6 640
FID C 6 639
FID C 6 615
FID C 6 616
FID C 6 617
FID C 6 625
FID C 6 633
FID C 6 641
FID C 6 642
FID C 6 634
FID C 6 629
FID C 6 626
#
FGR TEXT
# FGR 40
PRP string 'J4'
FID C 6 942
FID C 6 939
FID C 6 941
FID C 6 940
FID C 6 938
FID C 6 937
FID C 6 944
FID C 6 945
FID C 6 943
#
FGR TEXT
# FGR 41
PRP string 'R5'
FID C 6 2435
FID C 6 2411
FID C 6 2412
FID C 6 2416
FID C 6 2421
FID C 6 2428
FID C 6 2427
FID C 6 2414
FID C 6 2413
FID C 6 2422
FID C 6 2418
FID C 6 2419
FID C 6 2423
FID C 6 2430
FID C 6 2437
FID C 6 2436
#
FGR TEXT
# FGR 42
PRP string 'X1'
FID C 6 3092
FID C 6 3095
FID C 6 3100
FID C 6 3104
FID C 6 3101
FID C 6 3102
#
FGR TEXT
# FGR 43
PRP string 'U13'
FID C 6 1342
FID C 6 1341
FID C 6 1348
FID C 6 1356
FID C 6 1365
FID C 6 1369
FID C 6 1382
FID C 6 1374
FID C 6 1375
FID C 6 1386
FID C 6 1390
FID C 6 1400
FID C 6 1406
FID C 6 1405
FID C 6 1398
FID C 6 1395
FID C 6 1399
FID C 6 1404
FID C 6 1403
FID C 6 1397
FID C 6 1389
#
FGR TEXT
# FGR 44
PRP string 'U11'
FID C 6 1164
FID C 6 1163
FID C 6 1167
FID C 6 1173
FID C 6 1174
FID C 6 1175
FID C 6 1182
FID C 6 1178
FID C 6 1179
FID C 6 1190
FID C 6 1197
FID C 6 1193
FID C 6 1194
#
FGR TEXT
# FGR 45
PRP string 'U10'
FID C 6 2290
FID C 6 2289
FID C 6 2294
FID C 6 2295
FID C 6 2296
FID C 6 2297
FID C 6 2300
FID C 6 2298
FID C 6 2299
FID C 6 2302
FID C 6 2304
FID C 6 2306
FID C 6 2308
FID C 6 2307
FID C 6 2305
FID C 6 2303
FID C 6 2301
#
FGR TEXT
# FGR 46
PRP string 'U9'
FID C 6 882
FID C 6 881
FID C 6 885
FID C 6 891
FID C 6 894
FID C 6 896
FID C 6 899
FID C 6 904
FID C 6 912
FID C 6 913
FID C 6 905
FID C 6 901
FID C 6 898
FID C 6 897
FID C 6 900
#
FGR TEXT
# FGR 47
PRP string 'U8'
FID C 6 2672
FID C 6 2671
FID C 6 2676
FID C 6 2680
FID C 6 2685
FID C 6 2693
FID C 6 2697
FID C 6 2701
FID C 6 2705
FID C 6 2704
FID C 6 2700
FID C 6 2703
FID C 6 2702
FID C 6 2699
FID C 6 2694
FID C 6 2690
FID C 6 2691
FID C 6 2695
FID C 6 2692
FID C 6 2696
#
FGR TEXT
# FGR 48
PRP string 'U6'
FID C 6 1557
FID C 6 1556
FID C 6 1560
FID C 6 1564
FID C 6 1566
FID C 6 1580
FID C 6 1575
FID C 6 1573
FID C 6 1572
FID C 6 1574
FID C 6 1576
FID C 6 1578
FID C 6 1579
FID C 6 1577
#
FGR TEXT
# FGR 49
PRP string 'U5'
FID C 6 948
FID C 6 947
FID C 6 949
FID C 6 950
FID C 6 951
FID C 6 964
FID C 6 953
FID C 6 952
FID C 6 956
FID C 6 958
FID C 6 963
FID C 6 962
FID C 6 957
FID C 6 955
#
FGR TEXT
# FGR 50
PRP string 'U2'
FID C 6 2353
FID C 6 2352
FID C 6 2358
FID C 6 2361
FID C 6 2362
FID C 6 2379
FID C 6 2363
FID C 6 2380
FID C 6 2381
FID C 6 2377
FID C 6 2370
#
FGR TEXT
# FGR 51
PRP string 'U1'
FID C 6 2748
FID C 6 2747
FID C 6 2749
FID C 6 2753
FID C 6 2758
FID C 6 2765
FID C 6 2772
FID C 6 2767
FID C 6 2768
#
FGR TEXT
# FGR 52
PRP string 'SW1'
FID C 6 2269
FID C 6 2266
FID C 6 2263
FID C 6 2256
FID C 6 2255
FID C 6 2262
FID C 6 2265
FID C 6 2268
FID C 6 2267
FID C 6 2264
FID C 6 2261
FID C 6 2271
FID C 6 2270
FID C 6 2272
FID C 6 2273
FID C 6 2274
FID C 6 2277
FID C 6 2275
FID C 6 2276
#
FGR TEXT
# FGR 53
PRP string 'S6'
FID C 6 2179
FID C 6 2176
FID C 6 2173
FID C 6 2166
FID C 6 2165
FID C 6 2172
FID C 6 2175
FID C 6 2178
FID C 6 2177
FID C 6 2174
FID C 6 2171
FID C 6 2188
FID C 6 2183
FID C 6 2181
FID C 6 2180
FID C 6 2182
FID C 6 2184
FID C 6 2186
FID C 6 2187
FID C 6 2185
#
FGR TEXT
# FGR 54
PRP string 'S5'
FID C 6 1997
FID C 6 1994
FID C 6 1984
FID C 6 1974
FID C 6 1973
FID C 6 1983
FID C 6 1993
FID C 6 1996
FID C 6 1995
FID C 6 1992
FID C 6 1982
FID C 6 2025
FID C 6 2005
FID C 6 2004
FID C 6 2015
FID C 6 2020
FID C 6 2024
FID C 6 2023
FID C 6 2019
FID C 6 2011
#
FGR TEXT
# FGR 55
PRP string 'R35'
FID C 6 2191
FID C 6 2192
FID C 6 2197
FID C 6 2199
FID C 6 2198
FID C 6 2196
FID C 6 2193
FID C 6 2200
FID C 6 2202
FID C 6 2207
FID C 6 2211
FID C 6 2210
FID C 6 2205
FID C 6 2203
FID C 6 2206
FID C 6 2209
FID C 6 2208
FID C 6 2204
FID C 6 2201
FID C 6 2220
FID C 6 2213
FID C 6 2212
FID C 6 2215
FID C 6 2217
FID C 6 2219
FID C 6 2218
FID C 6 2216
FID C 6 2214
#
FGR TEXT
# FGR 56
PRP string 'R34'
FID C 6 2116
FID C 6 2117
FID C 6 2123
FID C 6 2127
FID C 6 2126
FID C 6 2122
FID C 6 2119
FID C 6 2129
FID C 6 2133
FID C 6 2145
FID C 6 2153
FID C 6 2152
FID C 6 2143
FID C 6 2137
FID C 6 2144
FID C 6 2151
FID C 6 2150
FID C 6 2142
FID C 6 2132
FID C 6 2158
FID C 6 2159
FID C 6 2155
#
FGR TEXT
# FGR 57
PRP string 'R33'
FID C 6 2221
FID C 6 2222
FID C 6 2225
FID C 6 2227
FID C 6 2226
FID C 6 2224
FID C 6 2223
FID C 6 2228
FID C 6 2231
FID C 6 2238
FID C 6 2242
FID C 6 2241
FID C 6 2236
FID C 6 2232
FID C 6 2237
FID C 6 2240
FID C 6 2239
FID C 6 2235
FID C 6 2230
FID C 6 2243
FID C 6 2245
FID C 6 2250
FID C 6 2254
FID C 6 2253
FID C 6 2248
FID C 6 2246
FID C 6 2249
FID C 6 2252
FID C 6 2251
FID C 6 2247
FID C 6 2244
#
FGR TEXT
# FGR 58
PRP string 'R32'
FID C 6 2114
FID C 6 2115
FID C 6 2121
FID C 6 2125
FID C 6 2124
FID C 6 2120
FID C 6 2118
FID C 6 2128
FID C 6 2131
FID C 6 2141
FID C 6 2149
FID C 6 2148
FID C 6 2139
FID C 6 2134
FID C 6 2140
FID C 6 2147
FID C 6 2146
FID C 6 2138
FID C 6 2130
FID C 6 2160
FID C 6 2154
FID C 6 2161
FID C 6 2162
FID C 6 2157
FID C 6 2156
#
FGR TEXT
# FGR 59
PRP string 'R31'
FID C 6 568
FID C 6 535
FID C 6 536
FID C 6 540
FID C 6 545
FID C 6 559
FID C 6 558
FID C 6 541
FID C 6 537
FID C 6 538
FID C 6 542
FID C 6 544
FID C 6 547
FID C 6 546
FID C 6 548
FID C 6 560
FID C 6 567
FID C 6 570
FID C 6 569
FID C 6 571
FID C 6 573
FID C 6 572
FID C 6 539
#
FGR TEXT
# FGR 60
PRP string 'R30'
FID C 6 470
FID C 6 426
FID C 6 427
FID C 6 437
FID C 6 450
FID C 6 456
FID C 6 455
FID C 6 438
FID C 6 428
FID C 6 429
FID C 6 439
FID C 6 446
FID C 6 452
FID C 6 451
FID C 6 453
FID C 6 457
FID C 6 460
FID C 6 472
FID C 6 471
FID C 6 440
FID C 6 430
FID C 6 431
FID C 6 441
FID C 6 462
FID C 6 474
FID C 6 473
FID C 6 461
#
FGR TEXT
# FGR 61
PRP string 'R29'
FID C 6 283
FID C 6 257
FID C 6 258
FID C 6 263
FID C 6 276
FID C 6 280
FID C 6 279
FID C 6 285
FID C 6 284
FID C 6 272
FID C 6 264
FID C 6 260
FID C 6 259
FID C 6 281
FID C 6 286
FID C 6 287
FID C 6 282
FID C 6 266
FID C 6 262
FID C 6 261
FID C 6 265
FID C 6 273
FID C 6 277
#
FGR TEXT
# FGR 62
PRP string 'R28'
FID C 6 203
FID C 6 162
FID C 6 163
FID C 6 172
FID C 6 188
FID C 6 193
FID C 6 192
FID C 6 205
FID C 6 204
FID C 6 185
FID C 6 173
FID C 6 165
FID C 6 164
FID C 6 174
FID C 6 166
FID C 6 167
FID C 6 175
FID C 6 187
FID C 6 191
FID C 6 195
FID C 6 197
FID C 6 207
FID C 6 206
FID C 6 196
FID C 6 194
FID C 6 189
FID C 6 186
FID C 6 190
#
FGR TEXT
# FGR 63
PRP string 'R27'
FID C 6 1800
FID C 6 1801
FID C 6 1818
FID C 6 1826
FID C 6 1825
FID C 6 1817
FID C 6 1816
FID C 6 1862
FID C 6 1843
FID C 6 1863
FID C 6 1864
FID C 6 1854
FID C 6 1846
FID C 6 1870
FID C 6 1889
FID C 6 1888
FID C 6 1869
#
FGR TEXT
# FGR 64
PRP string 'R26'
FID C 6 1446
FID C 6 1414
FID C 6 1415
FID C 6 1420
FID C 6 1431
FID C 6 1437
FID C 6 1436
FID C 6 1448
FID C 6 1447
FID C 6 1429
FID C 6 1421
FID C 6 1417
FID C 6 1416
FID C 6 1418
FID C 6 1422
FID C 6 1432
FID C 6 1442
FID C 6 1449
FID C 6 1450
FID C 6 1443
FID C 6 1438
FID C 6 1433
#
FGR TEXT
# FGR 65
PRP string 'R25'
FID C 6 1383
FID C 6 1384
FID C 6 1388
FID C 6 1394
FID C 6 1393
FID C 6 1387
FID C 6 1385
FID C 6 1425
FID C 6 1402
FID C 6 1426
FID C 6 1427
FID C 6 1419
FID C 6 1411
FID C 6 1458
FID C 6 1435
FID C 6 1434
FID C 6 1445
FID C 6 1453
FID C 6 1457
FID C 6 1456
FID C 6 1452
FID C 6 1441
#
FGR TEXT
# FGR 66
PRP string 'R24'
FID C 6 1112
FID C 6 1095
FID C 6 1096
FID C 6 1100
FID C 6 1107
FID C 6 1110
FID C 6 1109
FID C 6 1114
FID C 6 1113
FID C 6 1106
FID C 6 1101
FID C 6 1098
FID C 6 1097
FID C 6 1115
FID C 6 1099
FID C 6 1108
#
FGR TEXT
# FGR 67
PRP string 'R23'
FID C 6 931
FID C 6 906
FID C 6 907
FID C 6 914
FID C 6 922
FID C 6 927
FID C 6 926
FID C 6 933
FID C 6 932
FID C 6 918
FID C 6 915
FID C 6 909
FID C 6 908
FID C 6 916
FID C 6 910
FID C 6 911
FID C 6 917
FID C 6 919
FID C 6 924
FID C 6 923
FID C 6 925
FID C 6 928
FID C 6 930
FID C 6 935
FID C 6 934
#
FGR TEXT
# FGR 68
PRP string 'R22'
FID C 6 759
FID C 6 760
FID C 6 771
FID C 6 773
FID C 6 772
FID C 6 770
FID C 6 766
FID C 6 777
FID C 6 774
FID C 6 778
FID C 6 779
FID C 6 776
FID C 6 775
FID C 6 783
FID C 6 780
FID C 6 784
FID C 6 785
FID C 6 782
FID C 6 781
#
FGR TEXT
# FGR 69
PRP string 'R21'
FID C 6 1239
FID C 6 1228
FID C 6 1229
FID C 6 1233
FID C 6 1236
FID C 6 1238
FID C 6 1237
FID C 6 1241
FID C 6 1240
FID C 6 1235
FID C 6 1234
FID C 6 1231
FID C 6 1230
FID C 6 1242
FID C 6 1244
FID C 6 1243
FID C 6 1232
#
FGR TEXT
# FGR 70
PRP string 'R20'
FID C 6 1168
FID C 6 1149
FID C 6 1150
FID C 6 1155
FID C 6 1160
FID C 6 1162
FID C 6 1161
FID C 6 1170
FID C 6 1169
FID C 6 1159
FID C 6 1156
FID C 6 1152
FID C 6 1151
FID C 6 1157
FID C 6 1153
FID C 6 1154
FID C 6 1158
FID C 6 1166
FID C 6 1172
FID C 6 1171
FID C 6 1165
#
FGR TEXT
# FGR 71
PRP string 'R19'
FID C 6 1142
FID C 6 1124
FID C 6 1125
FID C 6 1131
FID C 6 1135
FID C 6 1139
FID C 6 1138
FID C 6 1143
FID C 6 1145
FID C 6 1144
FID C 6 1126
FID C 6 1140
FID C 6 1146
FID C 6 1147
FID C 6 1141
FID C 6 1133
FID C 6 1128
FID C 6 1127
FID C 6 1132
FID C 6 1134
FID C 6 1136
#
FGR TEXT
# FGR 72
PRP string 'R18'
FID C 6 1089
FID C 6 1069
FID C 6 1070
FID C 6 1074
FID C 6 1079
FID C 6 1084
FID C 6 1083
FID C 6 1090
FID C 6 1092
FID C 6 1091
FID C 6 1071
FID C 6 1075
FID C 6 1072
FID C 6 1073
FID C 6 1076
FID C 6 1078
FID C 6 1082
FID C 6 1086
FID C 6 1088
FID C 6 1094
FID C 6 1093
FID C 6 1087
FID C 6 1085
FID C 6 1080
FID C 6 1077
FID C 6 1081
#
FGR TEXT
# FGR 73
PRP string 'R9'
FID C 6 2355
FID C 6 2335
FID C 6 2336
FID C 6 2339
FID C 6 2343
FID C 6 2347
FID C 6 2346
FID C 6 2350
FID C 6 2356
FID C 6 2357
FID C 6 2351
FID C 6 2341
FID C 6 2338
FID C 6 2337
FID C 6 2340
FID C 6 2342
FID C 6 2344
#
FGR TEXT
# FGR 74
PRP string 'R8'
FID C 6 3131
FID C 6 3107
FID C 6 3108
FID C 6 3111
FID C 6 3121
FID C 6 3126
FID C 6 3125
FID C 6 3112
FID C 6 3109
FID C 6 3110
FID C 6 3113
FID C 6 3117
FID C 6 3124
FID C 6 3128
FID C 6 3130
FID C 6 3133
FID C 6 3132
FID C 6 3129
FID C 6 3127
FID C 6 3122
FID C 6 3116
FID C 6 3123
#
FGR TEXT
# FGR 75
PRP string 'R7'
FID C 6 2466
FID C 6 2467
FID C 6 2485
FID C 6 2492
FID C 6 2491
FID C 6 2484
FID C 6 2476
FID C 6 2512
FID C 6 2546
FID C 6 2545
FID C 6 2511
#
FGR TEXT
# FGR 76
PRP string 'R6'
FID C 6 2788
FID C 6 2789
FID C 6 2813
FID C 6 2817
FID C 6 2816
FID C 6 2812
FID C 6 2797
FID C 6 2864
FID C 6 2844
FID C 6 2830
FID C 6 2829
FID C 6 2835
FID C 6 2853
FID C 6 2862
FID C 6 2863
FID C 6 2854
#
FGR TEXT
# FGR 77
PRP string 'R4'
FID C 6 3026
FID C 6 3027
FID C 6 3035
FID C 6 3038
FID C 6 3037
FID C 6 3034
FID C 6 3033
FID C 6 3049
FID C 6 3050
FID C 6 3045
#
FGR TEXT
# FGR 78
PRP string 'R3'
FID C 6 2507
FID C 6 2508
FID C 6 2536
FID C 6 2542
FID C 6 2541
FID C 6 2535
FID C 6 2529
FID C 6 2555
FID C 6 2559
FID C 6 2573
FID C 6 2580
FID C 6 2579
FID C 6 2571
FID C 6 2563
FID C 6 2572
FID C 6 2578
FID C 6 2577
FID C 6 2570
FID C 6 2558
#
FGR TEXT
# FGR 79
PRP string 'R2'
FID C 6 2961
FID C 6 2909
FID C 6 2910
FID C 6 2920
FID C 6 2940
FID C 6 2947
FID C 6 2946
FID C 6 2963
FID C 6 2962
FID C 6 2934
FID C 6 2921
FID C 6 2912
FID C 6 2911
#
FGR TEXT
# FGR 80
PRP string 'L2'
FID C 6 3040
FID C 6 3039
FID C 6 3061
FID C 6 3054
FID C 6 3062
FID C 6 3063
FID C 6 3060
FID C 6 3055
#
FGR TEXT
# FGR 81
PRP string 'L1'
FID C 6 2333
FID C 6 2332
FID C 6 2345
FID C 6 2354
FID C 6 2348
FID C 6 2349
#
FGR TEXT
# FGR 82
PRP string 'J3'
FID C 6 1703
FID C 6 1688
FID C 6 1696
FID C 6 1695
FID C 6 1687
FID C 6 1681
FID C 6 1726
FID C 6 1736
FID C 6 1765
FID C 6 1771
FID C 6 1770
FID C 6 1763
FID C 6 1744
FID C 6 1764
FID C 6 1769
FID C 6 1768
FID C 6 1762
FID C 6 1735
#
FGR TEXT
# FGR 83
PRP string 'J2'
FID C 6 3091
FID C 6 3079
FID C 6 3084
FID C 6 3083
FID C 6 3078
FID C 6 3077
FID C 6 3097
FID C 6 3093
FID C 6 3098
FID C 6 3099
FID C 6 3096
FID C 6 3094
#
FGR TEXT
# FGR 84
PRP string 'J1'
FID C 6 2657
FID C 6 2646
FID C 6 2651
FID C 6 2650
FID C 6 2645
FID C 6 2635
FID C 6 2665
FID C 6 2674
FID C 6 2669
FID C 6 2670
#
FGR TEXT
# FGR 85
PRP string 'FB3'
FID C 6 1717
FID C 6 1716
FID C 6 1753
FID C 6 1755
FID C 6 1754
FID C 6 1718
FID C 6 1781
FID C 6 1782
FID C 6 1775
FID C 6 1766
FID C 6 1758
FID C 6 1756
FID C 6 1757
FID C 6 1742
FID C 6 1728
FID C 6 1719
FID C 6 1729
FID C 6 1720
FID C 6 1721
FID C 6 1730
FID C 6 1743
FID C 6 1760
FID C 6 1759
FID C 6 1761
FID C 6 1767
FID C 6 1776
FID C 6 1784
FID C 6 1783
#
FGR TEXT
# FGR 86
PRP string 'FB2'
FID C 6 2063
FID C 6 2062
FID C 6 2087
FID C 6 2089
FID C 6 2088
FID C 6 2064
FID C 6 2104
FID C 6 2105
FID C 6 2101
FID C 6 2099
FID C 6 2092
FID C 6 2090
FID C 6 2091
FID C 6 2080
FID C 6 2075
FID C 6 2065
FID C 6 2107
FID C 6 2106
FID C 6 2081
FID C 6 2076
FID C 6 2067
FID C 6 2066
#
FGR TEXT
# FGR 87
PRP string 'F1'
FID C 6 2439
FID C 6 2426
FID C 6 2425
FID C 6 2434
FID C 6 2424
FID C 6 2443
FID C 6 2446
FID C 6 2444
FID C 6 2445
#
FGR TEXT
# FGR 88
PRP string 'D18'
FID C 6 298
FID C 6 297
FID C 6 307
FID C 6 315
FID C 6 316
FID C 6 308
FID C 6 342
FID C 6 356
FID C 6 348
FID C 6 349
FID C 6 375
FID C 6 389
FID C 6 400
FID C 6 410
FID C 6 409
FID C 6 399
FID C 6 408
FID C 6 407
FID C 6 398
FID C 6 386
FID C 6 372
FID C 6 373
FID C 6 387
FID C 6 374
FID C 6 388
#
FGR TEXT
# FGR 89
PRP string 'D17'
FID C 6 300
FID C 6 299
FID C 6 309
FID C 6 317
FID C 6 318
FID C 6 310
FID C 6 343
FID C 6 357
FID C 6 350
FID C 6 351
FID C 6 377
FID C 6 412
FID C 6 411
FID C 6 376
#
FGR TEXT
# FGR 90
PRP string 'D16'
FID C 6 304
FID C 6 303
FID C 6 313
FID C 6 321
FID C 6 322
FID C 6 314
FID C 6 345
FID C 6 359
FID C 6 354
FID C 6 355
FID C 6 418
FID C 6 397
FID C 6 381
FID C 6 380
FID C 6 391
FID C 6 403
FID C 6 416
FID C 6 417
FID C 6 404
#
FGR TEXT
# FGR 91
PRP string 'D15'
FID C 6 302
FID C 6 301
FID C 6 311
FID C 6 319
FID C 6 320
FID C 6 312
FID C 6 344
FID C 6 358
FID C 6 352
FID C 6 353
FID C 6 415
FID C 6 379
FID C 6 378
FID C 6 396
FID C 6 402
FID C 6 414
FID C 6 413
FID C 6 401
FID C 6 390
#
FGR TEXT
# FGR 92
PRP string 'D14'
FID C 6 530
FID C 6 561
FID C 6 562
FID C 6 557
FID C 6 534
FID C 6 531
FID C 6 563
FID C 6 565
FID C 6 564
FID C 6 532
FID C 6 566
FID C 6 533
FID C 6 543
#
FGR TEXT
# FGR 93
PRP string 'D13'
FID C 6 420
FID C 6 463
FID C 6 464
FID C 6 458
FID C 6 432
FID C 6 421
FID C 6 465
FID C 6 467
FID C 6 466
FID C 6 422
FID C 6 433
FID C 6 423
FID C 6 424
FID C 6 434
FID C 6 442
FID C 6 448
FID C 6 447
FID C 6 449
FID C 6 454
FID C 6 459
FID C 6 469
FID C 6 468
#
FGR TEXT
# FGR 94
PRP string 'D12'
FID C 6 267
FID C 6 289
FID C 6 290
FID C 6 288
FID C 6 274
FID C 6 268
FID C 6 291
FID C 6 293
FID C 6 292
FID C 6 269
FID C 6 295
FID C 6 294
FID C 6 278
FID C 6 275
FID C 6 271
FID C 6 270
#
FGR TEXT
# FGR 95
PRP string 'D11'
FID C 6 168
FID C 6 211
FID C 6 212
FID C 6 198
FID C 6 176
FID C 6 169
FID C 6 213
FID C 6 215
FID C 6 214
FID C 6 170
FID C 6 216
FID C 6 218
FID C 6 217
FID C 6 171
#
FGR TEXT
# FGR 96
PRP string 'D10'
FID C 6 1333
FID C 6 1358
FID C 6 1359
FID C 6 1353
FID C 6 1338
FID C 6 1334
FID C 6 1360
FID C 6 1362
FID C 6 1361
FID C 6 1335
FID C 6 1339
FID C 6 1336
FID C 6 1337
FID C 6 1340
FID C 6 1355
FID C 6 1364
FID C 6 1363
FID C 6 1354
#
FGR TEXT
# FGR 97
PRP string 'D9'
FID C 6 1344
FID C 6 1370
FID C 6 1371
FID C 6 1366
FID C 6 1349
FID C 6 1345
FID C 6 1367
FID C 6 1372
FID C 6 1373
FID C 6 1368
FID C 6 1351
FID C 6 1347
FID C 6 1346
FID C 6 1350
FID C 6 1352
FID C 6 1357
#
FGR TEXT
# FGR 98
PRP string 'D8'
FID C 6 1258
FID C 6 1284
FID C 6 1285
FID C 6 1275
FID C 6 1264
FID C 6 1259
FID C 6 1265
FID C 6 1260
FID C 6 1261
FID C 6 1266
FID C 6 1268
FID C 6 1272
FID C 6 1274
FID C 6 1277
FID C 6 1287
FID C 6 1286
FID C 6 1276
FID C 6 1273
FID C 6 1270
FID C 6 1267
FID C 6 1271
#
FGR TEXT
# FGR 99
PRP string 'D7'
FID C 6 1200
FID C 6 1215
FID C 6 1216
FID C 6 1212
FID C 6 1205
FID C 6 1201
FID C 6 1202
FID C 6 1203
FID C 6 1206
FID C 6 1213
#
FGR TEXT
# FGR 100
PRP string 'D6'
FID C 6 976
FID C 6 975
FID C 6 985
FID C 6 993
FID C 6 994
FID C 6 986
FID C 6 1007
FID C 6 1001
FID C 6 996
FID C 6 995
FID C 6 997
FID C 6 1003
FID C 6 1005
FID C 6 1006
FID C 6 1004
#
FGR TEXT
# FGR 101
PRP string 'D5'
FID C 6 1040
FID C 6 1064
FID C 6 1065
FID C 6 1058
FID C 6 1044
FID C 6 1041
FID C 6 1043
FID C 6 1042
FID C 6 1051
FID C 6 1046
FID C 6 1047
FID C 6 1052
FID C 6 1059
FID C 6 1067
FID C 6 1066
#
FGR TEXT
# FGR 102
PRP string 'D4'
FID C 6 1901
FID C 6 1900
FID C 6 1924
FID C 6 1929
FID C 6 1930
FID C 6 1925
FID C 6 1954
FID C 6 1955
FID C 6 1936
#
FGR TEXT
# FGR 103
PRP string 'D3'
FID C 6 2644
FID C 6 2643
FID C 6 2661
FID C 6 2663
FID C 6 2664
FID C 6 2662
FID C 6 2673
FID C 6 2678
FID C 6 2684
FID C 6 2689
FID C 6 2688
FID C 6 2682
FID C 6 2679
FID C 6 2683
FID C 6 2687
FID C 6 2686
FID C 6 2681
FID C 6 2677
#
FGR TEXT
# FGR 104
PRP string 'D2'
FID C 6 2496
FID C 6 2495
FID C 6 2530
FID C 6 2537
FID C 6 2538
FID C 6 2531
FID C 6 2574
FID C 6 2549
FID C 6 2575
FID C 6 2576
FID C 6 2564
FID C 6 2556
#
FGR TEXT
# FGR 105
PRP string 'D1'
FID C 6 2386
FID C 6 2385
FID C 6 2396
FID C 6 2400
FID C 6 2401
FID C 6 2397
FID C 6 2406
FID C 6 2415
FID C 6 2409
FID C 6 2410
#
FGR TEXT
# FGR 106
PRP string 'C67'
FID C 6 1430
FID C 6 1424
FID C 6 1413
FID C 6 1410
FID C 6 1409
FID C 6 1412
FID C 6 1423
FID C 6 1461
FID C 6 1451
FID C 6 1440
FID C 6 1439
FID C 6 1444
FID C 6 1454
FID C 6 1459
FID C 6 1460
FID C 6 1455
FID C 6 1465
FID C 6 1468
FID C 6 1467
FID C 6 1464
#
FGR TEXT
# FGR 107
PRP string 'C66'
FID C 6 1516
FID C 6 1510
FID C 6 1501
FID C 6 1495
FID C 6 1494
FID C 6 1500
FID C 6 1509
FID C 6 1551
FID C 6 1535
FID C 6 1526
FID C 6 1525
FID C 6 1531
FID C 6 1540
FID C 6 1549
FID C 6 1550
FID C 6 1541
FID C 6 1571
FID C 6 1565
FID C 6 1562
FID C 6 1561
FID C 6 1563
FID C 6 1567
FID C 6 1569
FID C 6 1570
FID C 6 1568
#
FGR TEXT
# FGR 108
PRP string 'C65'
FID C 6 1481
FID C 6 1478
FID C 6 1472
FID C 6 1470
FID C 6 1469
FID C 6 1471
FID C 6 1477
FID C 6 1513
FID C 6 1502
FID C 6 1491
FID C 6 1490
FID C 6 1496
FID C 6 1504
FID C 6 1511
FID C 6 1512
FID C 6 1505
FID C 6 1544
FID C 6 1521
FID C 6 1520
FID C 6 1532
FID C 6 1537
FID C 6 1543
FID C 6 1542
FID C 6 1536
FID C 6 1527
#
FGR TEXT
# FGR 109
PRP string 'C63'
FID C 6 1489
FID C 6 1485
FID C 6 1476
FID C 6 1474
FID C 6 1473
FID C 6 1475
FID C 6 1484
FID C 6 1519
FID C 6 1508
FID C 6 1499
FID C 6 1498
FID C 6 1503
FID C 6 1514
FID C 6 1517
FID C 6 1518
FID C 6 1515
FID C 6 1530
FID C 6 1534
FID C 6 1548
FID C 6 1555
FID C 6 1554
FID C 6 1546
FID C 6 1539
FID C 6 1547
FID C 6 1553
FID C 6 1552
FID C 6 1545
FID C 6 1533
#
FGR TEXT
# FGR 110
PRP string 'C62'
FID C 6 1300
FID C 6 1297
FID C 6 1292
FID C 6 1289
FID C 6 1288
FID C 6 1291
FID C 6 1296
FID C 6 1321
FID C 6 1312
FID C 6 1307
FID C 6 1306
FID C 6 1311
FID C 6 1313
FID C 6 1319
FID C 6 1320
FID C 6 1314
FID C 6 1330
FID C 6 1324
FID C 6 1331
FID C 6 1332
FID C 6 1329
FID C 6 1325
#
FGR TEXT
# FGR 111
PRP string 'C61'
FID C 6 1014
FID C 6 1010
FID C 6 1009
FID C 6 1013
FID C 6 1021
FID C 6 1024
FID C 6 1025
FID C 6 1011
FID C 6 1015
FID C 6 1016
FID C 6 1022
FID C 6 1026
FID C 6 1027
FID C 6 1023
FID C 6 1018
FID C 6 1017
FID C 6 1028
FID C 6 1030
FID C 6 1029
FID C 6 1012
#
FGR TEXT
# FGR 112
PRP string 'C60'
FID C 6 971
FID C 6 966
FID C 6 965
FID C 6 970
FID C 6 980
FID C 6 987
FID C 6 988
FID C 6 967
FID C 6 972
FID C 6 977
FID C 6 981
FID C 6 989
FID C 6 990
FID C 6 982
FID C 6 979
FID C 6 978
FID C 6 973
FID C 6 968
FID C 6 969
FID C 6 974
FID C 6 984
FID C 6 992
FID C 6 991
FID C 6 983
#
FGR TEXT
# FGR 113
PRP string 'C59'
FID C 6 795
FID C 6 787
FID C 6 786
FID C 6 794
FID C 6 805
FID C 6 810
FID C 6 811
FID C 6 789
FID C 6 788
FID C 6 802
FID C 6 798
FID C 6 799
FID C 6 803
FID C 6 806
FID C 6 813
FID C 6 812
FID C 6 807
FID C 6 814
FID C 6 815
FID C 6 808
FID C 6 797
FID C 6 791
FID C 6 790
FID C 6 796
FID C 6 800
FID C 6 804
#
FGR TEXT
# FGR 114
PRP string 'C58'
FID C 6 849
FID C 6 843
FID C 6 842
FID C 6 848
FID C 6 864
FID C 6 868
FID C 6 869
FID C 6 845
FID C 6 844
FID C 6 856
FID C 6 852
FID C 6 853
FID C 6 857
FID C 6 865
FID C 6 871
FID C 6 870
FID C 6 850
FID C 6 846
FID C 6 847
FID C 6 851
FID C 6 855
FID C 6 860
FID C 6 862
FID C 6 867
FID C 6 873
FID C 6 872
FID C 6 866
FID C 6 861
FID C 6 858
FID C 6 854
FID C 6 859
#
FGR TEXT
# FGR 115
PRP string 'C57'
FID C 6 2766
FID C 6 2762
FID C 6 2757
FID C 6 2752
FID C 6 2751
FID C 6 2756
FID C 6 2761
FID C 6 2793
FID C 6 2774
FID C 6 2773
FID C 6 2777
FID C 6 2783
FID C 6 2792
FID C 6 2791
FID C 6 2782
FID C 6 2776
FID C 6 2805
FID C 6 2832
FID C 6 2831
FID C 6 2804
#
FGR TEXT
# FGR 116
PRP string 'C56'
FID C 6 2587
FID C 6 2586
FID C 6 2584
FID C 6 2582
FID C 6 2581
FID C 6 2583
FID C 6 2585
FID C 6 2613
FID C 6 2591
FID C 6 2590
FID C 6 2600
FID C 6 2608
FID C 6 2612
FID C 6 2611
FID C 6 2607
FID C 6 2592
FID C 6 2654
FID C 6 2640
FID C 6 2623
FID C 6 2622
FID C 6 2630
FID C 6 2647
FID C 6 2652
FID C 6 2653
FID C 6 2648
#
FGR TEXT
# FGR 117
PRP string 'C55'
FID C 6 1879
FID C 6 1872
FID C 6 1871
FID C 6 1878
FID C 6 1890
FID C 6 1893
FID C 6 1894
FID C 6 1874
FID C 6 1873
FID C 6 1884
FID C 6 1880
FID C 6 1881
FID C 6 1885
FID C 6 1891
FID C 6 1896
FID C 6 1895
FID C 6 1876
FID C 6 1875
FID C 6 1886
FID C 6 1882
FID C 6 1883
FID C 6 1887
FID C 6 1892
FID C 6 1898
FID C 6 1897
#
FGR TEXT
# FGR 118
PRP string 'C54'
FID C 6 1698
FID C 6 1690
FID C 6 1689
FID C 6 1697
FID C 6 1737
FID C 6 1745
FID C 6 1746
FID C 6 1692
FID C 6 1691
FID C 6 1711
FID C 6 1704
FID C 6 1705
FID C 6 1712
FID C 6 1738
FID C 6 1748
FID C 6 1747
FID C 6 1749
FID C 6 1693
FID C 6 1713
#
FGR TEXT
# FGR 119
PRP string 'C22'
FID C 6 2372
FID C 6 2365
FID C 6 2364
FID C 6 2371
FID C 6 2387
FID C 6 2388
FID C 6 2389
FID C 6 2391
FID C 6 2390
FID C 6 2375
FID C 6 2373
FID C 6 2367
FID C 6 2366
FID C 6 2393
FID C 6 2392
FID C 6 2376
FID C 6 2374
FID C 6 2369
FID C 6 2368
#
FGR TEXT
# FGR 120
PRP string 'C21'
FID C 6 2407
FID C 6 2403
FID C 6 2399
FID C 6 2395
FID C 6 2394
FID C 6 2398
FID C 6 2402
FID C 6 2431
FID C 6 2417
FID C 6 2432
FID C 6 2433
FID C 6 2429
FID C 6 2420
FID C 6 2438
FID C 6 2442
FID C 6 2440
FID C 6 2441
#
FGR TEXT
# FGR 121
PRP string 'C20'
FID C 6 3071
FID C 6 3065
FID C 6 3064
FID C 6 3070
FID C 6 3080
FID C 6 3085
FID C 6 3086
FID C 6 3088
FID C 6 3087
FID C 6 3075
FID C 6 3072
FID C 6 3067
FID C 6 3066
FID C 6 3073
FID C 6 3068
FID C 6 3069
FID C 6 3074
FID C 6 3082
FID C 6 3090
FID C 6 3089
FID C 6 3081
#
FGR TEXT
# FGR 122
PRP string 'C19'
FID C 6 3032
FID C 6 3029
FID C 6 3025
FID C 6 3023
FID C 6 3022
FID C 6 3024
FID C 6 3028
FID C 6 3036
FID C 6 3044
FID C 6 3041
FID C 6 3042
FID C 6 3046
FID C 6 3051
FID C 6 3056
FID C 6 3058
FID C 6 3059
FID C 6 3057
FID C 6 3053
FID C 6 3048
FID C 6 3047
FID C 6 3052
#
FGR TEXT
# FGR 123
PRP string 'C18'
FID C 6 2906
FID C 6 2902
FID C 6 2893
FID C 6 2885
FID C 6 2884
FID C 6 2892
FID C 6 2901
FID C 6 2914
FID C 6 2936
FID C 6 2924
FID C 6 2925
FID C 6 2957
FID C 6 2968
FID C 6 2981
FID C 6 2994
FID C 6 2993
FID C 6 2980
FID C 6 2992
FID C 6 2991
FID C 6 2979
FID C 6 2965
FID C 6 2954
FID C 6 2955
FID C 6 2966
FID C 6 2956
FID C 6 2967
#
FGR TEXT
# FGR 124
PRP string 'C17'
FID C 6 2907
FID C 6 2904
FID C 6 2895
FID C 6 2887
FID C 6 2886
FID C 6 2894
FID C 6 2903
FID C 6 2915
FID C 6 2939
FID C 6 2928
FID C 6 2929
FID C 6 2960
FID C 6 2997
FID C 6 2996
FID C 6 2959
#
FGR TEXT
# FGR 125
PRP string 'C16'
FID C 6 2905
FID C 6 2900
FID C 6 2891
FID C 6 2883
FID C 6 2882
FID C 6 2890
FID C 6 2899
FID C 6 2913
FID C 6 2935
FID C 6 2922
FID C 6 2923
FID C 6 2990
FID C 6 2971
FID C 6 2953
FID C 6 2952
FID C 6 2964
FID C 6 2977
FID C 6 2988
FID C 6 2989
FID C 6 2978
#
FGR TEXT
# FGR 126
PRP string 'C15'
FID C 6 2951
FID C 6 2945
FID C 6 2933
FID C 6 2919
FID C 6 2918
FID C 6 2932
FID C 6 2944
FID C 6 2970
FID C 6 2987
FID C 6 2975
FID C 6 2976
FID C 6 3021
FID C 6 3000
FID C 6 2999
FID C 6 3006
FID C 6 3012
FID C 6 3020
FID C 6 3019
FID C 6 3011
FID C 6 3004
#
FGR TEXT
# FGR 127
PRP string 'C14'
FID C 6 2958
FID C 6 2949
FID C 6 2938
FID C 6 2927
FID C 6 2926
FID C 6 2937
FID C 6 2948
FID C 6 2972
FID C 6 2995
FID C 6 2982
FID C 6 2983
FID C 6 3013
FID C 6 3014
FID C 6 3001
#
FGR TEXT
# FGR 128
PRP string 'C13'
FID C 6 2950
FID C 6 2943
FID C 6 2931
FID C 6 2917
FID C 6 2916
FID C 6 2930
FID C 6 2942
FID C 6 2969
FID C 6 2986
FID C 6 2973
FID C 6 2974
FID C 6 2998
FID C 6 3003
FID C 6 3010
FID C 6 3018
FID C 6 3017
FID C 6 3008
FID C 6 3005
FID C 6 3009
FID C 6 3016
FID C 6 3015
FID C 6 3007
FID C 6 3002
#
FGR TEXT
# FGR 129
PRP string 'C12'
FID C 6 2487
FID C 6 2480
FID C 6 2471
FID C 6 2458
FID C 6 2457
FID C 6 2470
FID C 6 2479
FID C 6 2503
FID C 6 2528
FID C 6 2519
FID C 6 2520
FID C 6 2567
FID C 6 2548
FID C 6 2568
FID C 6 2569
FID C 6 2562
FID C 6 2554
#
FGR TEXT
# FGR 130
PRP string 'C11'
FID C 6 2486
FID C 6 2478
FID C 6 2469
FID C 6 2456
FID C 6 2455
FID C 6 2468
FID C 6 2477
FID C 6 2498
FID C 6 2527
FID C 6 2513
FID C 6 2514
FID C 6 2547
FID C 6 2557
FID C 6 2552
FID C 6 2553
#
FGR TEXT
# FGR 131
PRP string 'C10'
FID C 6 2483
FID C 6 2475
FID C 6 2465
FID C 6 2454
FID C 6 2453
FID C 6 2464
FID C 6 2474
FID C 6 2497
FID C 6 2526
FID C 6 2509
FID C 6 2510
FID C 6 2544
FID C 6 2551
FID C 6 2561
FID C 6 2566
FID C 6 2565
FID C 6 2560
FID C 6 2550
FID C 6 2543
#
FGR TEXT
# FGR 132
PRP string 'C9'
FID C 6 2488
FID C 6 2482
FID C 6 2473
FID C 6 2460
FID C 6 2459
FID C 6 2472
FID C 6 2481
FID C 6 2504
FID C 6 2521
FID C 6 2532
FID C 6 2539
FID C 6 2540
FID C 6 2533
FID C 6 2523
FID C 6 2506
FID C 6 2505
FID C 6 2522
#
FGR TEXT
# FGR 133
PRP string 'C8'
FID C 6 2604
FID C 6 2596
FID C 6 2595
FID C 6 2603
FID C 6 2626
FID C 6 2636
FID C 6 2637
FID C 6 2605
FID C 6 2597
FID C 6 2598
FID C 6 2606
FID C 6 2610
FID C 6 2618
FID C 6 2621
FID C 6 2628
FID C 6 2639
FID C 6 2638
FID C 6 2627
FID C 6 2620
FID C 6 2616
FID C 6 2609
FID C 6 2617
#
FGR TEXT
# FGR 134
PRP string 'C7'
FID C 6 2462
FID C 6 2448
FID C 6 2447
FID C 6 2461
FID C 6 2489
FID C 6 2493
FID C 6 2494
FID C 6 2449
FID C 6 2450
FID C 6 2463
FID C 6 2490
#
FGR TEXT
# FGR 135
PRP string 'C6'
FID C 6 2826
FID C 6 2819
FID C 6 2818
FID C 6 2825
FID C 6 2859
FID C 6 2865
FID C 6 2866
FID C 6 2820
FID C 6 2827
FID C 6 2840
FID C 6 2860
FID C 6 2867
FID C 6 2868
FID C 6 2861
FID C 6 2849
FID C 6 2841
#
FGR TEXT
# FGR 136
PRP string 'C5'
FID C 6 2619
FID C 6 2615
FID C 6 2602
FID C 6 2594
FID C 6 2593
FID C 6 2601
FID C 6 2614
FID C 6 2660
FID C 6 2634
FID C 6 2633
FID C 6 2649
FID C 6 2656
FID C 6 2659
FID C 6 2658
FID C 6 2655
FID C 6 2642
#
FGR TEXT
# FGR 137
PRP string 'C4'
FID C 6 2739
FID C 6 2736
FID C 6 2735
FID C 6 2738
FID C 6 2741
FID C 6 2742
FID C 6 2743
FID C 6 2744
FID C 6 2737
FID C 6 2740
#
FGR TEXT
# FGR 138
PRP string 'C3'
FID C 6 2719
FID C 6 2715
FID C 6 2714
FID C 6 2718
FID C 6 2727
FID C 6 2729
FID C 6 2730
FID C 6 2720
FID C 6 2716
FID C 6 2717
FID C 6 2721
FID C 6 2722
FID C 6 2724
FID C 6 2723
FID C 6 2725
FID C 6 2726
FID C 6 2728
FID C 6 2732
FID C 6 2731
#
FGR TEXT
# FGR 139
PRP string 'C2'
FID C 6 2285
FID C 6 2284
FID C 6 2282
FID C 6 2280
FID C 6 2279
FID C 6 2281
FID C 6 2283
FID C 6 2291
FID C 6 2286
FID C 6 2292
FID C 6 2293
FID C 6 2288
FID C 6 2287
#
FGR TEXT
# FGR 140
PRP string 'C1'
FID C 6 2317
FID C 6 2316
FID C 6 2314
FID C 6 2310
FID C 6 2309
FID C 6 2313
FID C 6 2315
FID C 6 2318
FID C 6 2322
FID C 6 2320
FID C 6 2321
#
FGR TEXT
# FGR 141
PRP string 'AN8'
FID C 6 138
FID C 6 139
FID C 6 146
FID C 6 152
FID C 6 150
FID C 6 151
FID C 6 177
FID C 6 178
FID C 6 199
FID C 6 222
FID C 6 232
FID C 6 239
FID C 6 247
FID C 6 246
FID C 6 238
FID C 6 245
FID C 6 244
FID C 6 237
FID C 6 229
FID C 6 219
FID C 6 220
FID C 6 230
FID C 6 221
FID C 6 231
#
FGR TEXT
# FGR 142
PRP string 'AN7'
FID C 6 140
FID C 6 141
FID C 6 147
FID C 6 155
FID C 6 153
FID C 6 154
FID C 6 179
FID C 6 180
FID C 6 200
FID C 6 224
FID C 6 249
FID C 6 248
FID C 6 223
#
FGR TEXT
# FGR 143
PRP string 'AN6'
FID C 6 144
FID C 6 145
FID C 6 149
FID C 6 161
FID C 6 159
FID C 6 160
FID C 6 183
FID C 6 184
FID C 6 202
FID C 6 255
FID C 6 236
FID C 6 228
FID C 6 227
FID C 6 234
FID C 6 242
FID C 6 253
FID C 6 254
FID C 6 243
#
FGR TEXT
# FGR 144
PRP string 'AN5'
FID C 6 142
FID C 6 143
FID C 6 148
FID C 6 158
FID C 6 156
FID C 6 157
FID C 6 181
FID C 6 182
FID C 6 201
FID C 6 252
FID C 6 226
FID C 6 225
FID C 6 235
FID C 6 241
FID C 6 251
FID C 6 250
FID C 6 240
FID C 6 233
#
FGR TEXT
# FGR 145
PRP string 'AN4'
FID C 6 77
FID C 6 78
FID C 6 85
FID C 6 91
FID C 6 89
FID C 6 90
FID C 6 101
FID C 6 102
FID C 6 109
FID C 6 124
FID C 6 125
FID C 6 113
#
FGR TEXT
# FGR 146
PRP string 'AN3'
FID C 6 83
FID C 6 84
FID C 6 88
FID C 6 100
FID C 6 98
FID C 6 99
FID C 6 107
FID C 6 108
FID C 6 112
FID C 6 116
FID C 6 121
FID C 6 130
FID C 6 137
FID C 6 136
FID C 6 128
FID C 6 123
FID C 6 129
FID C 6 135
FID C 6 134
FID C 6 127
FID C 6 120
#
FGR TEXT
# FGR 147
PRP string 'AN2'
FID C 6 79
FID C 6 80
FID C 6 86
FID C 6 94
FID C 6 92
FID C 6 93
FID C 6 103
FID C 6 104
FID C 6 110
FID C 6 131
FID C 6 114
FID C 6 132
FID C 6 133
FID C 6 126
FID C 6 117
#
FGR TEXT
# FGR 148
PRP string 'AN1'
FID C 6 81
FID C 6 82
FID C 6 87
FID C 6 97
FID C 6 95
FID C 6 96
FID C 6 105
FID C 6 106
FID C 6 111
FID C 6 115
FID C 6 122
FID C 6 118
FID C 6 119
#
FGR TEXT
# FGR 149
PRP string 'U14'
FID C 0 205
FID C 0 204
FID C 0 201
FID C 0 194
FID C 0 190
FID C 0 172
FID C 0 162
FID C 0 167
FID C 0 168
FID C 0 145
FID C 0 146
FID C 0 148
#
FGR TEXT
# FGR 150
PRP string 'C47'
FID C 0 138
FID C 0 141
FID C 0 140
FID C 0 137
FID C 0 134
FID C 0 131
FID C 0 132
FID C 0 133
FID C 0 142
FID C 0 136
FID C 0 143
FID C 0 144
FID C 0 139
FID C 0 135
#
FGR TEXT
# FGR 151
PRP string 'C46'
FID C 0 125
FID C 0 128
FID C 0 127
FID C 0 124
FID C 0 117
FID C 0 112
FID C 0 113
FID C 0 114
FID C 0 129
FID C 0 121
FID C 0 130
FID C 0 126
FID C 0 122
FID C 0 118
FID C 0 115
FID C 0 116
FID C 0 119
FID C 0 120
FID C 0 123
#
FGR TEXT
# FGR 152
PRP string 'C45'
FID C 0 106
FID C 0 108
FID C 0 107
FID C 0 105
FID C 0 98
FID C 0 93
FID C 0 94
FID C 0 95
FID C 0 109
FID C 0 100
FID C 0 111
FID C 0 110
FID C 0 101
FID C 0 103
FID C 0 104
FID C 0 102
FID C 0 99
FID C 0 97
FID C 0 96
#
FGR TEXT
# FGR 153
PRP string 'C44'
FID C 0 86
FID C 0 90
FID C 0 89
FID C 0 85
FID C 0 78
FID C 0 74
FID C 0 75
FID C 0 76
FID C 0 91
FID C 0 83
FID C 0 77
FID C 0 92
FID C 0 84
#
FGR TEXT
# FGR 154
PRP string 'C87'
FID C 0 45
FID C 0 51
FID C 0 57
FID C 0 62
FID C 0 61
FID C 0 56
FID C 0 50
FID C 0 40
FID C 0 33
FID C 0 25
FID C 0 22
FID C 0 21
FID C 0 24
FID C 0 20
FID C 0 19
FID C 0 23
FID C 0 30
FID C 0 37
FID C 0 38
FID C 0 32
FID C 0 39
FID C 0 31
FID C 0 18
FID C 0 16
FID C 0 15
FID C 0 17
#
FGR TEXT
# FGR 155
PRP string 'C88'
FID C 0 71
FID C 0 73
FID C 0 80
FID C 0 82
FID C 0 81
FID C 0 79
FID C 0 72
FID C 0 70
FID C 0 66
FID C 0 60
FID C 0 55
FID C 0 54
FID C 0 59
FID C 0 53
FID C 0 52
FID C 0 58
FID C 0 63
FID C 0 67
FID C 0 68
FID C 0 65
FID C 0 69
FID C 0 64
FID C 0 49
FID C 0 44
FID C 0 36
FID C 0 29
FID C 0 28
FID C 0 35
FID C 0 27
FID C 0 26
FID C 0 34
FID C 0 41
FID C 0 46
FID C 0 47
FID C 0 43
FID C 0 48
FID C 0 42
#
FGR TEXT
# FGR 156
PRP string 'C89'
FID C 0 174
FID C 0 180
FID C 0 179
FID C 0 173
FID C 0 155
FID C 0 149
FID C 0 150
FID C 0 175
FID C 0 181
FID C 0 182
FID C 0 176
FID C 0 170
FID C 0 165
FID C 0 161
FID C 0 157
FID C 0 152
FID C 0 151
FID C 0 156
FID C 0 160
FID C 0 164
FID C 0 169
FID C 0 163
FID C 0 158
FID C 0 153
FID C 0 154
FID C 0 159
FID C 0 178
FID C 0 184
FID C 0 183
FID C 0 177
FID C 0 171
FID C 0 166
#
FGR TEXT
# FGR 157
PRP string 'C90'
FID C 0 279
FID C 0 281
FID C 0 290
FID C 0 294
FID C 0 293
FID C 0 289
FID C 0 280
FID C 0 276
FID C 0 273
FID C 0 271
FID C 0 263
FID C 0 264
FID C 0 272
FID C 0 275
FID C 0 278
FID C 0 277
FID C 0 274
FID C 0 256
FID C 0 252
FID C 0 246
FID C 0 238
FID C 0 237
FID C 0 245
FID C 0 251
FID C 0 255
#
FGR TEXT
# FGR 158
PRP string 'C53'
FID C 0 347
FID C 0 351
FID C 0 350
FID C 0 346
FID C 0 334
FID C 0 328
FID C 0 329
FID C 0 353
FID C 0 352
FID C 0 338
FID C 0 343
FID C 0 344
FID C 0 339
FID C 0 335
FID C 0 331
FID C 0 330
FID C 0 348
FID C 0 354
FID C 0 355
FID C 0 349
FID C 0 345
FID C 0 342
FID C 0 340
FID C 0 341
FID C 0 337
FID C 0 336
FID C 0 333
FID C 0 332
#
FGR TEXT
# FGR 159
PRP string 'C52'
FID C 0 320
FID C 0 323
FID C 0 322
FID C 0 319
FID C 0 312
FID C 0 306
FID C 0 307
FID C 0 325
FID C 0 324
FID C 0 314
FID C 0 316
FID C 0 317
FID C 0 315
FID C 0 313
FID C 0 309
FID C 0 308
FID C 0 311
FID C 0 310
FID C 0 318
FID C 0 321
FID C 0 327
FID C 0 326
#
FGR TEXT
# FGR 160
PRP string 'C51'
FID C 0 300
FID C 0 302
FID C 0 301
FID C 0 299
FID C 0 291
FID C 0 282
FID C 0 283
FID C 0 304
FID C 0 303
FID C 0 295
FID C 0 297
FID C 0 298
FID C 0 296
FID C 0 292
FID C 0 285
FID C 0 284
FID C 0 286
FID C 0 288
FID C 0 287
FID C 0 305
#
FGR TEXT
# FGR 161
PRP string 'C50'
FID C 0 260
FID C 0 266
FID C 0 265
FID C 0 259
FID C 0 247
FID C 0 239
FID C 0 240
FID C 0 268
FID C 0 267
FID C 0 253
FID C 0 257
FID C 0 258
FID C 0 254
FID C 0 248
FID C 0 242
FID C 0 241
FID C 0 261
FID C 0 269
FID C 0 270
FID C 0 262
FID C 0 250
FID C 0 244
FID C 0 243
FID C 0 249
#
FGR TEXT
# FGR 162
PRP string 'C49'
FID C 0 229
FID C 0 233
FID C 0 232
FID C 0 228
FID C 0 222
FID C 0 217
FID C 0 218
FID C 0 219
FID C 0 234
FID C 0 225
FID C 0 223
FID C 0 220
FID C 0 221
FID C 0 224
FID C 0 231
FID C 0 236
FID C 0 235
FID C 0 230
FID C 0 227
FID C 0 226
#
FGR TEXT
# FGR 163
PRP string 'C48'
FID C 0 207
FID C 0 212
FID C 0 211
FID C 0 206
FID C 0 191
FID C 0 185
FID C 0 186
FID C 0 187
FID C 0 213
FID C 0 197
FID C 0 208
FID C 0 214
FID C 0 215
FID C 0 209
FID C 0 203
FID C 0 200
FID C 0 196
FID C 0 193
FID C 0 189
FID C 0 188
FID C 0 192
FID C 0 195
FID C 0 199
FID C 0 202
FID C 0 198
#

### steps/pcb/netlists/cadnet/netlist
H optimize n staggered n
$0 $NONE$
$1 +3.3V
$2 +3.3V_CLEAN
$3 +3.3V_PCIE
$4 +5.0V
$5 +12V
$6 +12V_PCIE
$7 5721_STATUS
$8 ANT1
$9 ANT2
$10 ANT3
$11 ANT4
$12 CSN
$13 DCXO1
$14 DCXO2
$15 FPGA_TCK
$16 FPGA_TDI
$17 FPGA_TDO
$18 FPGA_TMS
$19 GND
$20 GPS1_RST
$21 GPS1_RX
$22 GPS1_TP1
$23 GPS1_TP2
$24 GPS1_TX
$25 GPS2_RST
$26 GPS2_RX
$27 GPS2_TP1
$28 GPS2_TP2
$29 GPS2_TX
$30 IMU_BOOT
$31 IMU_CLKSEL0
$32 IMU_ENV_SCL
$33 IMU_ENV_SDA
$34 IMU_INT
$35 IMU_NRST
$36 IMU_PS0
$37 IMU_PS1
$38 KEY1
$39 KEY2
$40 LED1
$41 LED2
$42 LED3
$43 LED4
$44 MAC_10Mout
$45 MAC_ALARM
$46 MAC_BITE
$47 MAC_PPS_IN0+
$48 MAC_PPS_IN0-
$49 MAC_PPS_IN1+
$50 MAC_PPS_IN1-
$51 MAC_PPS_OUT+
$52 MAC_PPS_OUT-
$53 MAC_RX
$54 MAC_TX
$55 MAC_USB_PWR
$56 MAC_USB+
$57 MAC_USB-
$58 MISO
$59 MOSI
$60 NetBT1_2
$61 NetC3_1
$62 NetC3_2
$63 NetC4_1
$64 NetC4_2
$65 NetC19_2
$66 NetC20_1
$67 NetC20_2
$68 NetC21_2
$69 NetC22_1
$70 NetC22_2
$71 NetC44_1
$72 NetC45_1
$73 NetC46_1
$74 NetC47_1
$75 NetC48_1
$76 NetC49_1
$77 NetC50_1
$78 NetC51_1
$79 NetC52_1
$80 NetC53_1
$81 NetC72_2
$82 NetC85_2
$83 NetC86_2
$84 NetD1_1
$85 NetD1_2
$86 NetD2_1
$87 NetD2_2
$88 NetD4_1
$89 NetD9_1
$90 NetD10_1
$91 NetD11_1
$92 NetD12_1
$93 NetD13_1
$94 NetD14_1
$95 NetJ3_2
$96 NetJ3_3
$97 NetJ4_2
$98 NetJ4_3
$99 NetJP1_2
$100 NetJP1_3
$101 NetJP2_2
$102 NetJP2_3
$103 NetP2_B17
$104 NetP2_B31
$105 NetR2_1
$106 NetR3_1
$107 NetR4_2
$108 NetR5_1
$109 NetR18_2
$110 NetR19_2
$111 NetR20_2
$112 NetR21_2
$113 NetR27_2
$114 NetR32_1
$115 NetR33_1
$116 NetR42_1
$117 NetR43_2
$118 NetU6_3
$119 NetU16_3
$120 OE_5356
$121 PCIE_CLK_N
$122 PCIE_CLK_P
$123 PCIE_PERST
$124 PCIE_RX0_N
$125 PCIE_RX0_P
$126 PCIE_RX1_N
$127 PCIE_RX1_P
$128 PCIE_RX2_N
$129 PCIE_RX2_P
$130 PCIE_RX3_N
$131 PCIE_RX3_P
$132 PCIE_TX0_N
$133 PCIE_TX0_P
$134 PCIE_TX1_N
$135 PCIE_TX1_P
$136 PCIE_TX2_N
$137 PCIE_TX2_P
$138 PCIE_TX3_N
$139 PCIE_TX3_P
$140 PRSNT
$141 RTC_MFP
$142 SCK
$143 SCL
$144 SDA
$145 UART1_RXD
$146 UART1_TXD
#
#Netlist points
#
0 0 2.7568898 3.2872047 T 0.0787402 0.023622 e s
0 0 2.7568898 3.1372047 T 0.0787402 0.023622 e s
0 0 2.7568898 3.0872047 T 0.0787402 0.023622 e s
0 0 2.7568898 3.0372047 T 0.0787402 0.023622 e s
0 0 2.7568898 2.9872047 T 0.0787402 0.023622 e s
0 0 2.7568898 2.9372047 T 0.0787402 0.023622 e s
0 0 3.1112205 3.0872047 T 0.0787402 0.023622 e s
0 0 3.1112205 3.0372047 T 0.0787402 0.023622 e s
0 0 3.1112205 2.9872047 T 0.0787402 0.023622 e s
0 0 3.1112205 2.9372047 T 0.0787402 0.023622 e s
0 0 2.2715433 4.275063 T 0.0393701 0.0748031 e s
0 0 2.3778425 4.275063 T 0.0708661 0.0748031 e s
0 0 2.2341417 4.1736851 T 0.0559055 0.0610236 e s
0 0 2.4309921 4.1736851 T 0.0559055 0.0610236 e s
0 0 2.383748 4.1703386 T 0.0177165 0.0543307 e s
0 0 2.3069763 4.1703386 T 0.0177165 0.0543307 e s
0 0 2.4654409 4.275063 T 0.0649606 0.0511811 e s
0 0 2.1996929 4.275063 T 0.0649606 0.0511811 e s
0 0 4.0466536 4.2441732 T 0.0787402 0.0984252 e s
0 0 4.0466536 4.0276378 T 0.0787402 0.0984252 e s
0 0 3.6962598 4.0276378 T 0.0787402 0.0984252 e s
0 0 3.6962598 4.2441732 T 0.0787402 0.0984252 e s
0 0 3.9344488 4.0237008 T 0.019685 0.0905512 e s
0 0 3.8399606 4.0237008 T 0.019685 0.0905512 e s
0 0 1.8461259 4.149563 T 0.0570866 0.0177165 e s
0 0 1.8461259 4.174563 T 0.0570866 0.0177165 e s
0 0 1.8461259 4.199563 T 0.0570866 0.0177165 e s
0 0 1.631559 4.049563 T 0.0570866 0.0177165 e s
0 0 1.631559 4.074563 T 0.0570866 0.0177165 e s
0 0 1.631559 4.174563 T 0.0570866 0.0177165 e s
0 0 6.9431102 3.1680709 T 0.0511811 0.0748031 e s
0 0 6.9431102 3.2940551 T 0.0511811 0.0748031 e s
0 0 3.4512205 3.2062205 T 0.0393701 0.0708661 e s
0 0 3.3921654 3.2062205 T 0.0393701 0.0708661 e s
0 0 3.5102756 3.2062205 T 0.0393701 0.0708661 e s
0 0 3.5693307 3.3853543 T 0.0393701 0.0905512 e s
0 0 3.4444882 2.948441 T 0.0531496 0.0275591 e s
0 0 3.5251968 2.948441 T 0.0531496 0.0275591 e s
0 0 3.5251968 2.995685 T 0.0531496 0.0275591 e s
0 0 3.2448425 4.2211417 T 0.05 0.2 e s
0 0 3.2448425 3.951063 T 0.05 0.2 e s
0 0 2.1909451 0.1377953 T 0.028 0.165 e s
0 0 1.9940951 0.1377953 T 0.028 0.165 e s
0 0 1.9547251 0.1377953 T 0.028 0.165 e s
0 0 3.0177151 0.1377953 T 0.028 0.165 e s
0 0 2.3090551 0.1377953 T 0.028 0.165 e s
0 0 2.1122051 0.1377953 T 0.028 0.165 e s
0 0 2.1515751 0.1377953 T 0.028 0.165 e s
0 0 3.9114214 1.6796232 T 0.0708661 0.0098425 e s
0 0 3.9114214 1.6996232 T 0.0708661 0.0098425 e s
0 0 4.0689017 1.6996232 T 0.0708661 0.0098425 e s
0 0 3.9114214 1.7196232 T 0.0708661 0.0098425 e s
0 0 4.0689017 1.7196232 T 0.0708661 0.0098425 e s
0 0 3.9114214 1.7396232 T 0.0708661 0.0098425 e s
0 0 3.9114214 1.7596232 T 0.0708661 0.0098425 e s
0 0 6.5113582 3.2509055 T 0.0265748 0.0098425 e s
0 0 6.5113582 3.2705906 T 0.0265748 0.0098425 e s
0 0 6.5113582 3.2902756 T 0.0265748 0.0098425 e s
0 0 6.5113582 3.3099606 T 0.0265748 0.0098425 e s
0 0 6.3883268 3.2902756 T 0.0265748 0.0098425 e s
0 0 6.3883268 3.2705906 T 0.0265748 0.0098425 e s
0 0 6.3883268 3.2115354 T 0.0265748 0.0098425 e s
0 0 6.3883268 3.1918504 T 0.0265748 0.0098425 e s
0 0 6.3883268 3.1721654 T 0.0265748 0.0098425 e s
0 0 6.5113582 3.1524803 T 0.0265748 0.0098425 e s
0 0 3.2490157 2.7849212 T 0.0098425 0.0108268 e s
0 0 3.2091732 2.7952756 T 0.0108268 0.0098425 e s
0 0 3.4920225 1.457433 T 0.06102 0.00984 e s
0 0 3.4920225 1.477113 T 0.06102 0.00984 e s
0 0 3.4920225 1.772393 T 0.06102 0.00984 e s
0 0 3.4920225 1.496803 T 0.06102 0.00984 e s
0 0 3.4920225 1.792073 T 0.06102 0.00984 e s
0 0 3.6514625 1.870813 T 0.06102 0.00984 e s
0 0 3.6514625 1.929873 T 0.06102 0.00984 e s
0 0 3.6514625 1.851133 T 0.06102 0.00984 e s
0 0 3.6514625 1.831443 T 0.06102 0.00984 e s
0 0 3.6514625 1.949553 T 0.06102 0.00984 e s
0 0 3.6514625 1.988923 T 0.06102 0.00984 e s
0 0 3.6514625 1.969243 T 0.06102 0.00984 e s
0 0 3.4920225 1.988923 T 0.06102 0.00984 e s
0 0 3.4920225 1.969243 T 0.06102 0.00984 e s
0 0 3.6514625 1.693653 T 0.06102 0.00984 e s
0 0 3.4920225 1.634593 T 0.06102 0.00984 e s
0 0 3.4920225 1.693653 T 0.06102 0.00984 e s
0 0 3.6514625 1.733023 T 0.06102 0.00984 e s
0 0 3.6514625 1.752703 T 0.06102 0.00984 e s
0 0 3.6514625 1.673963 T 0.06102 0.00984 e s
0 0 3.4920225 1.929873 T 0.06102 0.00984 e s
0 0 3.4920225 1.555853 T 0.06102 0.00984 e s
0 0 3.4920225 1.949553 T 0.06102 0.00984 e s
0 0 3.6514625 1.595223 T 0.06102 0.00984 e s
0 0 3.4920225 1.536173 T 0.06102 0.00984 e s
0 0 3.6514625 1.457433 T 0.06102 0.00984 e s
0 0 3.6514625 1.437743 T 0.06102 0.00984 e s
0 0 3.6514625 1.398373 T 0.06102 0.00984 e s
0 0 3.6514625 1.378693 T 0.06102 0.00984 e s
0 0 3.6514625 1.359003 T 0.06102 0.00984 e s
0 0 3.6514625 1.339323 T 0.06102 0.00984 e s
0 0 3.4920225 1.319633 T 0.06102 0.00984 e s
0 0 3.6514625 1.319633 T 0.06102 0.00984 e s
0 0 3.5717425 2.131643 T 0.06693 0.05315 e s
0 0 3.5717425 1.275343 T 0.06693 0.05315 e s
0 0 3.4920225 1.733023 T 0.06102 0.00984 e s
0 0 3.6514625 1.536173 T 0.06102 0.00984 e s
0 0 3.4920225 1.575543 T 0.06102 0.00984 e s
0 0 3.4920225 1.595223 T 0.06102 0.00984 e s
0 0 2.1686825 2.438533 T 0.05315 0.06693 e s
0 0 2.9413225 2.358813 T 0.00984 0.06102 e s
0 0 2.9216325 2.358813 T 0.00984 0.06102 e s
0 0 2.8428925 2.358813 T 0.00984 0.06102 e s
0 0 2.8232125 2.358813 T 0.00984 0.06102 e s
0 0 2.7444725 2.358813 T 0.00984 0.06102 e s
0 0 2.7641525 2.358813 T 0.00984 0.06102 e s
0 0 2.5082525 2.358813 T 0.00984 0.06102 e s
0 0 2.3507725 2.358813 T 0.00984 0.06102 e s
0 0 2.3704525 2.358813 T 0.00984 0.06102 e s
0 0 2.2129725 2.518253 T 0.00984 0.06102 e s
0 0 2.2326625 2.518253 T 0.00984 0.06102 e s
0 0 2.2326625 2.358813 T 0.00984 0.06102 e s
0 0 2.2129725 2.358813 T 0.00984 0.06102 e s
0 0 2.4098225 2.518253 T 0.00984 0.06102 e s
0 0 2.4295125 2.518253 T 0.00984 0.06102 e s
0 0 2.3704525 2.518253 T 0.00984 0.06102 e s
0 0 2.5082525 2.518253 T 0.00984 0.06102 e s
0 0 2.6066725 2.518253 T 0.00984 0.06102 e s
0 0 2.5476225 2.518253 T 0.00984 0.06102 e s
0 0 2.6263625 2.518253 T 0.00984 0.06102 e s
0 0 2.5673025 2.518253 T 0.00984 0.06102 e s
0 0 2.7051025 2.518253 T 0.00984 0.06102 e s
0 0 2.7247825 2.518253 T 0.00984 0.06102 e s
0 0 2.6460425 2.518253 T 0.00984 0.06102 e s
0 0 2.6657325 2.518253 T 0.00984 0.06102 e s
0 0 2.8035225 2.518253 T 0.00984 0.06102 e s
0 0 2.7444725 2.518253 T 0.00984 0.06102 e s
0 0 2.7641525 2.518253 T 0.00984 0.06102 e s
0 0 2.8428925 2.518253 T 0.00984 0.06102 e s
0 0 2.8625825 2.518253 T 0.00984 0.06102 e s
0 0 2.9413225 2.518253 T 0.00984 0.06102 e s
0 0 2.9610025 2.518253 T 0.00984 0.06102 e s
0 0 2.2523425 2.358813 T 0.00984 0.06102 e s
0 0 2.2720325 2.358813 T 0.00984 0.06102 e s
0 0 2.3114025 2.518253 T 0.00984 0.06102 e s
0 0 2.3310825 2.518253 T 0.00984 0.06102 e s
0 0 1.7765525 1.634633 T 0.06102 0.00984 e s
0 0 1.7765525 1.870853 T 0.06102 0.00984 e s
0 0 1.7765525 2.028333 T 0.06102 0.00984 e s
0 0 1.7765525 1.910223 T 0.06102 0.00984 e s
0 0 1.7765525 1.831483 T 0.06102 0.00984 e s
0 0 1.7765525 1.949593 T 0.06102 0.00984 e s
0 0 1.7765525 1.733063 T 0.06102 0.00984 e s
0 0 1.7765525 1.772433 T 0.06102 0.00984 e s
0 0 1.6171125 1.929913 T 0.06102 0.00984 e s
0 0 1.6171125 1.851173 T 0.06102 0.00984 e s
0 0 1.6171125 1.910223 T 0.06102 0.00984 e s
0 0 1.6171125 2.028333 T 0.06102 0.00984 e s
0 0 1.7765525 2.008653 T 0.06102 0.00984 e s
0 0 1.7765525 1.969283 T 0.06102 0.00984 e s
0 0 1.7765525 1.457473 T 0.06102 0.00984 e s
0 0 1.6171125 1.870853 T 0.06102 0.00984 e s
0 0 1.6171125 1.969283 T 0.06102 0.00984 e s
0 0 1.7765525 1.929913 T 0.06102 0.00984 e s
0 0 1.7765525 1.851173 T 0.06102 0.00984 e s
0 0 1.7765525 1.654323 T 0.06102 0.00984 e s
0 0 1.6171125 2.008653 T 0.06102 0.00984 e s
0 0 1.7765525 1.752743 T 0.06102 0.00984 e s
0 0 1.7765525 1.713373 T 0.06102 0.00984 e s
0 0 1.6171125 1.949593 T 0.06102 0.00984 e s
0 0 1.7765525 1.555893 T 0.06102 0.00984 e s
0 0 1.7765525 1.575583 T 0.06102 0.00984 e s
0 0 1.6171125 1.516523 T 0.06102 0.00984 e s
0 0 1.6171125 1.457473 T 0.06102 0.00984 e s
0 0 1.6171125 1.811803 T 0.06102 0.00984 e s
0 0 1.6171125 1.831483 T 0.06102 0.00984 e s
0 0 1.7765525 1.437783 T 0.06102 0.00984 e s
0 0 1.6171125 1.359043 T 0.06102 0.00984 e s
0 0 1.7765525 1.339363 T 0.06102 0.00984 e s
0 0 1.6171125 1.575583 T 0.06102 0.00984 e s
0 0 1.6171125 1.437783 T 0.06102 0.00984 e s
0 0 1.6171125 1.536213 T 0.06102 0.00984 e s
0 0 1.6171125 1.555893 T 0.06102 0.00984 e s
0 0 1.6171125 1.614953 T 0.06102 0.00984 e s
0 0 1.6171125 1.733063 T 0.06102 0.00984 e s
0 0 1.6171125 1.674003 T 0.06102 0.00984 e s
0 0 1.6171125 1.378733 T 0.06102 0.00984 e s
0 0 1.6171125 1.477153 T 0.06102 0.00984 e s
0 0 1.6171125 1.418103 T 0.06102 0.00984 e s
0 0 1.6171125 1.752743 T 0.06102 0.00984 e s
0 0 1.7765525 1.359043 T 0.06102 0.00984 e s
0 0 1.6171125 1.339363 T 0.06102 0.00984 e s
0 0 1.6171125 1.634633 T 0.06102 0.00984 e s
0 0 1.6171125 1.772433 T 0.06102 0.00984 e s
0 0 1.7765525 1.378733 T 0.06102 0.00984 e s
0 0 1.7765525 1.418103 T 0.06102 0.00984 e s
0 0 1.7765525 1.477153 T 0.06102 0.00984 e s
0 0 1.6171125 1.713373 T 0.06102 0.00984 e s
0 0 1.6171125 1.654323 T 0.06102 0.00984 e s
0 0 1.6171125 2.048023 T 0.06102 0.00984 e s
0 0 1.7765525 2.048023 T 0.06102 0.00984 e s
0 0 1.6968325 1.275383 T 0.06693 0.05315 e s
0 0 1.6968325 2.131683 T 0.06693 0.05315 e s
0 0 2.5870025 0.878873 T 0.00984 0.06102 e s
0 0 2.5870025 1.038313 T 0.00984 0.06102 e s
0 0 2.2326725 0.878873 T 0.00984 0.06102 e s
0 0 2.4295225 0.878873 T 0.00984 0.06102 e s
0 0 2.3704625 0.878873 T 0.00984 0.06102 e s
0 0 2.3507825 0.878873 T 0.00984 0.06102 e s
0 0 2.3310925 0.878873 T 0.00984 0.06102 e s
0 0 2.2917225 0.878873 T 0.00984 0.06102 e s
0 0 2.3901525 0.878873 T 0.00984 0.06102 e s
0 0 2.4885725 0.878873 T 0.00984 0.06102 e s
0 0 2.5279425 0.878873 T 0.00984 0.06102 e s
0 0 2.5476325 0.878873 T 0.00984 0.06102 e s
0 0 2.5673125 0.878873 T 0.00984 0.06102 e s
0 0 2.4492025 0.878873 T 0.00984 0.06102 e s
0 0 2.4688925 0.878873 T 0.00984 0.06102 e s
0 0 2.2523525 0.878873 T 0.00984 0.06102 e s
0 0 2.2720425 0.878873 T 0.00984 0.06102 e s
0 0 2.5673125 1.038313 T 0.00984 0.06102 e s
0 0 2.3704625 1.038313 T 0.00984 0.06102 e s
0 0 2.3901525 1.038313 T 0.00984 0.06102 e s
0 0 2.4295225 1.038313 T 0.00984 0.06102 e s
0 0 2.4688925 1.038313 T 0.00984 0.06102 e s
0 0 2.4885725 1.038313 T 0.00984 0.06102 e s
0 0 2.4492025 1.038313 T 0.00984 0.06102 e s
0 0 2.2917225 1.038313 T 0.00984 0.06102 e s
0 0 2.2720425 1.038313 T 0.00984 0.06102 e s
0 0 2.2523525 1.038313 T 0.00984 0.06102 e s
0 0 2.2326725 1.038313 T 0.00984 0.06102 e s
0 0 2.3507825 1.038313 T 0.00984 0.06102 e s
0 0 2.3310925 1.038313 T 0.00984 0.06102 e s
0 0 2.5476325 1.038313 T 0.00984 0.06102 e s
0 0 2.5279425 1.038313 T 0.00984 0.06102 e s
0 0 2.8625925 1.038313 T 0.00984 0.06102 e s
0 0 2.8822725 1.038313 T 0.00984 0.06102 e s
0 0 2.9216425 0.878873 T 0.00984 0.06102 e s
0 0 2.9216425 1.038313 T 0.00984 0.06102 e s
0 0 2.9413325 0.878873 T 0.00984 0.06102 e s
0 0 2.9413325 1.038313 T 0.00984 0.06102 e s
0 0 2.9807025 0.878873 T 0.00984 0.06102 e s
0 0 2.9807025 1.038313 T 0.00984 0.06102 e s
0 0 2.9610125 1.038313 T 0.00984 0.06102 e s
0 0 2.9610125 0.878873 T 0.00984 0.06102 e s
0 0 2.8429025 0.878873 T 0.00984 0.06102 e s
0 0 2.7838525 0.878873 T 0.00984 0.06102 e s
0 0 2.7247925 0.878873 T 0.00984 0.06102 e s
0 0 2.6657425 0.878873 T 0.00984 0.06102 e s
0 0 2.1686925 0.958593 T 0.05315 0.06693 e s
0 0 3.0249925 0.958593 T 0.05315 0.06693 e s
0 0 2.2129825 0.878873 T 0.00984 0.06102 e s
0 0 2.2129825 1.038313 T 0.00984 0.06102 e s
0 0 3.0249825 2.438533 T 0.05315 0.06693 e s
0 0 3.9871259 3.808563 T 0.0570866 0.0177165 e s
0 0 3.9871259 3.833563 T 0.0570866 0.0177165 e s
0 0 3.9871259 3.858563 T 0.0570866 0.0177165 e s
0 0 3.772559 3.708563 T 0.0570866 0.0177165 e s
0 0 3.772559 3.733563 T 0.0570866 0.0177165 e s
0 0 3.772559 3.833563 T 0.0570866 0.0177165 e s
0 0.0177166 3.9580709 4.126063 B e e staggered 0 0 0
0 0.0177166 3.7848425 4.126063 B e e staggered 0 0 0
0 0.0329922 3.2948425 4.0861024 B e e staggered 0 0 0
0 0.0329922 2.9948425 4.0861024 B e e staggered 0 0 0
0 0.0149606 2.4223425 3.0822126 B e e staggered 0 0 0
0 0.0149606 2.4223425 3.2396929 B e e staggered 0 0 0
0 0.0206693 4.3277559 1.0074803 B e e staggered 0 0 0
0 0.059055 3.6179425 2.486293 B e e staggered 0 0 0
0 0.059055 1.6529425 0.916293 B e e staggered 0 0 0
0 0.059055 1.6519425 2.486293 B e e staggered 0 0 0
0 0.059055 3.6179425 0.916293 B e e staggered 0 0 0
0 0.01083 3.5717425 2.097193 B e e staggered 0 0 0
0 0.01083 3.5717425 1.309793 B e e staggered 0 0 0
0 0.01083 2.2031325 2.438533 B e e staggered 0 0 0
0 0.01083 1.6968325 1.309833 B e e staggered 0 0 0
0 0.01083 1.6968325 2.097233 B e e staggered 0 0 0
0 0.01083 2.2031425 0.958593 B e e staggered 0 0 0
0 0.01083 2.9905425 0.958593 B e e staggered 0 0 0
0 0.01083 2.9905325 2.438533 B e e staggered 0 0 0
0 0.0590551 6.9001969 4.0934646 B e e staggered 0 0 0
0 0.0590551 6.5694882 4.0934646 B e e staggered 0 0 0
0 0.0149606 2.4223425 3.601378 B e e staggered 0 0 0
0 0.0149606 2.4223425 3.4438977 B e e staggered 0 0 0
0 0.0625984 0.285433 4.152063 B e e staggered 0 0 0
0 0.0625984 0.2854331 0.3681102 B e e staggered 0 0 0
0 0 2.5846451 0.1377953 D 0.028 0.165 e p
0 0 2.0728351 0.1377953 D 0.028 0.165 e p
0 0 2.0334651 0.1377953 D 0.028 0.165 e p
0 0 1.9940951 0.1377953 D 0.028 0.165 e p
0 0 1.9547251 0.1377953 D 0.028 0.165 e p
0 0 3.0964551 0.1377953 D 0.028 0.165 e p
0 0.004 2.2317425 2.584163 B e e staggered 0 0 0 v
0 0.004 2.2348425 3.506063 B e e staggered 0 0 0 v
0 0.004 3.5298425 3.481063 B e e staggered 0 0 0 v
1 0 4.3326771 3.6033465 T 0.0393701 0.0334646 e s
1 0 2.3348425 3.640748 T 0.082874 0.0440945 e s
1 0 3.444252 3.7503543 T 0.019685 0.0354331 e s
1 0 3.0448425 4.2211417 T 0.05 0.2 e s
1 0 3.1448425 4.2211417 T 0.05 0.2 e s
1 0 6.4598425 3.1500197 T 0.0098425 0.0226378 e s
1 0 6.5113582 3.1721654 T 0.0265748 0.0098425 e s
1 0 6.6798425 2.8020079 T 0.2125984 0.1141732 e s
1 0 1.2498423 4.2546063 T 0.0334646 0.0393701 e s
1 0 6.253937 2.7559055 T 0.0570866 0.0452756 e s
1 0 6.3720472 2.7559055 T 0.0570866 0.0452756 e s
1 0 6.3279134 2.656063 T 0.0267717 0.0251969 e s
1 0 6.3279134 2.501063 T 0.0267717 0.0251969 e s
1 0 6.3279134 2.556063 T 0.0267717 0.0251969 e s
1 0 6.3279134 2.611063 T 0.0267717 0.0251969 e s
1 0 6.5102756 3.071063 T 0.0452756 0.0570866 e s
1 0 6.5848425 3.0729921 T 0.0251969 0.0267717 e s
1 0 2.2098425 3.6456299 T 0.0570866 0.0452756 e s
1 0 2.1398425 3.6641339 T 0.0251969 0.0267717 e s
1 0 2.809252 3.7503543 T 0.019685 0.0354331 e s
1 0 2.694252 3.7503543 T 0.019685 0.0354331 e s
1 0 3.219252 3.7503543 T 0.019685 0.0354331 e s
1 0 3.5898425 3.8525197 T 0.0334646 0.0393701 e s
1 0 3.5898425 3.7846063 T 0.0334646 0.0393701 e s
1 0 0.6448425 4.2546063 T 0.0334646 0.0393701 e s
1 0 0.8465091 4.2546063 T 0.0334646 0.0393701 e s
1 0 1.0481757 4.2546063 T 0.0334646 0.0393701 e s
1 0 4.4348425 2.7898819 T 0.0385827 0.034252 e s
1 0 2.1468425 2.6792283 T 0.0393701 0.0283465 e s
1 0 4.7070078 4.206063 T 0.0283465 0.0393701 e s
1 0 5.2670078 4.206063 T 0.0283465 0.0393701 e s
1 0 6.1228425 2.4882283 T 0.0393701 0.0283465 e s
1 0 2.3274094 2.944063 D 0.0452756 0.0570866 e p
1 0 2.3519134 2.854063 D 0.0267717 0.0251969 e p
1 0.004 2.1468425 2.753063 B e e staggered 0 0 0 v
1 0.004 4.5036614 2.7898819 B e e staggered 0 0 0 v
1 0.004 2.5708425 4.283063 B e e staggered 0 0 0 v
1 0.004 3.5398425 3.806063 B e e staggered 0 0 0 v
1 0.004 3.2198425 3.806063 B e e staggered 0 0 0 v
1 0.004 2.7224094 3.7860709 B e e staggered 0 0 0 v
1 0.004 2.1398425 3.611063 B e e staggered 0 0 0 v
1 0.004 1.2948425 4.256063 B e e staggered 0 0 0 v
1 0.004 5.2748425 3.511063 B e e staggered 0 0 0 v
1 0.004 6.2848425 2.501063 B e e staggered 0 0 0 v
1 0 2.3348425 3.0428426 D 0.082874 0.0440945 e p
2 0 3.2490157 2.845 T 0.0098425 0.0108268 e s
2 0 3.2293307 2.7849212 T 0.0098425 0.0108268 e s
2 0 3.2691732 2.8346456 T 0.0108268 0.0098425 e s
2 0 2.7568898 3.2372047 T 0.0787402 0.023622 e s
2 0 3.5693307 3.2062205 T 0.0393701 0.0708661 e s
2 0 3.5311023 3.0517874 T 0.0413386 0.0452756 e s
2 0 3.5320078 2.797063 T 0.0283465 0.0393701 e s
2 0 4.1498425 2.8422441 T 0.0385827 0.034252 e s
2 0 4.0398425 3.029567 T 0.0374016 0.0393701 e s
2 0 4.1098425 3.0441338 T 0.0251969 0.0267717 e s
2 0 3.6938425 3.1884961 T 0.0570866 0.0452756 e s
2 0 3.7698425 3.2349922 T 0.0251969 0.0267717 e s
2 0 3.6888425 3.266567 T 0.0374016 0.0393701 e s
2 0 4.2802756 3.246063 T 0.0452756 0.0570866 e s
2 0 4.4548425 3.0441338 T 0.0251969 0.0267717 e s
2 0 4.3948425 3.0441338 T 0.0251969 0.0267717 e s
2 0 4.3348425 3.0441338 T 0.0251969 0.0267717 e s
2 0 4.2748425 3.0441338 T 0.0251969 0.0267717 e s
2 0 4.2198425 3.0441338 T 0.0251969 0.0267717 e s
2 0 4.1648425 3.0441338 T 0.0251969 0.0267717 e s
2 0 4.0648425 2.8514961 T 0.0570866 0.0452756 e s
2 0 3.9598425 2.8514961 T 0.0570866 0.0452756 e s
2 0.0206693 5.3277559 2.3074803 B e e staggered 0 0 0
3 0 2.0728351 0.1377953 T 0.028 0.165 e s
3 0 2.1515751 0.1377953 D 0.028 0.165 e p
3 0 2.1122051 0.1377953 D 0.028 0.165 e p
3 0.004 2.0767716 0.2559055 B e e staggered 0 0 0 v
3 0.004 2.0767716 0.2874016 B e e staggered 0 0 0 v
3 0.004 2.1122047 0.2874016 B e e staggered 0 0 0 v
3 0.004 2.1515748 0.2874016 B e e staggered 0 0 0 v
3 0.004 2.1122047 0.2559055 B e e staggered 0 0 0 v
3 0.004 2.1515748 0.2559055 B e e staggered 0 0 0 v
4 0 2.5098425 3.640748 T 0.082874 0.0440945 e s
4 0 1.8461259 4.099563 T 0.0570866 0.0177165 e s
4 0 3.6514625 2.028293 T 0.06102 0.00984 e s
4 0 3.6514625 2.047983 T 0.06102 0.00984 e s
4 0 3.6514625 2.067663 T 0.06102 0.00984 e s
4 0 3.6514625 2.087353 T 0.06102 0.00984 e s
4 0 3.4920225 2.028293 T 0.06102 0.00984 e s
4 0 3.4920225 2.047983 T 0.06102 0.00984 e s
4 0 3.4920225 2.067663 T 0.06102 0.00984 e s
4 0 3.4920225 2.087353 T 0.06102 0.00984 e s
4 0 6.7002756 1.421063 T 0.0452756 0.0570866 e s
4 0 6.7002756 1.531063 T 0.0452756 0.0570866 e s
4 0 6.6767716 1.611063 T 0.0267717 0.0251969 e s
4 0 6.6767716 1.671063 T 0.0267717 0.0251969 e s
4 0 6.6767716 1.721063 T 0.0267717 0.0251969 e s
4 0 6.6767716 1.776063 T 0.0267717 0.0251969 e s
4 0 4.1048425 3.7706299 T 0.0570866 0.0452756 e s
4 0 4.1948425 3.774567 T 0.0374016 0.0393701 e s
4 0 2.6398425 3.6064961 T 0.0570866 0.0452756 e s
4 0 2.7248425 3.5929921 T 0.0251969 0.0267717 e s
4 0 3.7302756 0.726063 T 0.0452756 0.0570866 e s
4 0 3.7167716 0.636063 T 0.0267717 0.0251969 e s
4 0 6.3198425 1.4601181 T 0.2125984 0.1141732 e s
4 0 6.8426771 1.816063 T 0.0283465 0.0393701 e s
4 0 4.1670079 3.701063 T 0.0283465 0.0393701 e s
4 0 3.9871259 3.758563 T 0.0570866 0.0177165 e s
4 0 1.9338425 4.1292284 T 0.0393701 0.0283465 e s
4 0 1.6643465 4.273063 T 0.0393701 0.0374016 e s
4 0 1.8732756 4.276063 T 0.0452756 0.0570866 e s
4 0.025 3.9797272 0.8906186 B e e staggered 0 0 0
4 0 2.7118425 3.0369921 D 0.0251969 0.0267717 e p
4 0 2.6328425 3.0424961 D 0.0570866 0.0452756 e p
4 0.004 3.5718425 2.058063 B e e staggered 0 0 0 v
4 0.004 1.5578425 4.229063 B e e staggered 0 0 0 v
4 0.004 2.7748425 3.566063 B e e staggered 0 0 0 v
4 0.004 3.5718425 2.033063 B e e staggered 0 0 0 v
4 0.004 4.2548425 3.776063 B e e staggered 0 0 0 v
4 0.004 6.8448425 1.661063 B e e staggered 0 0 0 v
4 0 2.5098425 3.0428426 D 0.082874 0.0440945 e p
5 0 6.0356772 3.556063 T 0.0283465 0.0393701 e s
5 0 6.3522834 2.291063 T 0.0775591 0.0224409 e s
5 0 5.8120079 3.3612205 T 0.0452756 0.0570866 e s
5 0 5.6344488 3.359252 T 0.0267717 0.0251969 e s
5 0 6.3348425 2.1814961 T 0.0570866 0.0452756 e s
5 0 6.6598425 2.0956299 T 0.0570866 0.0452756 e s
5 0 6.7498425 2.1432283 T 0.0393701 0.0283465 e s
5 0 6.2348425 2.1288977 T 0.0393701 0.0283465 e s
5 0 6.6374016 1.981063 T 0.0775591 0.0224409 e s
5 0.004 5.9948425 3.552063 B e e staggered 0 0 0 v
5 0.004 6.4248425 2.181063 B e e staggered 0 0 0 v
6 0 1.8759851 0.1377953 T 0.028 0.165 e s
6 0 1.8366151 0.1377953 T 0.028 0.165 e s
6 0 1.7972451 0.1377953 T 0.028 0.165 e s
6 0 6.3416929 3.701063 T 0.0255906 0.0413386 e s
6 0 1.8759851 0.1377953 D 0.028 0.165 e p
6 0 1.8366151 0.1377953 D 0.028 0.165 e p
6 0.004 1.8326771 0.2559055 B e e staggered 0 0 0 v
6 0.004 1.8523622 0.2559055 B e e staggered 0 0 0 v
6 0.004 1.8720472 0.2559055 B e e staggered 0 0 0 v
6 0.004 1.8326771 0.2874016 B e e staggered 0 0 0 v
6 0.004 1.8523622 0.2874016 B e e staggered 0 0 0 v
6 0.004 1.8720472 0.2874016 B e e staggered 0 0 0 v
6 0.004 1.8498425 3.701063 B e e staggered 0 0 0 v
6 0.004 6.2948425 3.701063 B e e staggered 0 0 0 v
7 0 3.5102756 3.3951969 T 0.0393701 0.0708661 e s
7 0 2.8232125 2.518253 T 0.00984 0.06102 e s
7 0.004 2.8218425 2.601063 B e e staggered 0 0 0 v
7 0.004 3.6238425 2.587063 B e e staggered 0 0 0 v
7 0.004 3.6228425 3.486063 B e e staggered 0 0 0 v
8 0 0.9084645 2.2844487 T 0.0275591 0.0354331 e s
8 0 2.4098225 2.358813 T 0.00984 0.06102 e s
8 0 0.5948031 2.481063 T 0.0413386 0.0393701 e s
8 0 0.9326378 2.481063 T 0.0964567 0.1240157 e s
8 0.03 0.1998425 2.481063 B e e staggered 0 0 0
8 0.004 2.4098425 2.314063 B e e staggered 0 0 0 v
8 0.004 1.0208425 2.481063 B e e staggered 0 0 0 v
9 0 0.9005905 1.7470472 T 0.0275591 0.0354331 e s
9 0 2.4295125 2.358813 T 0.00984 0.06102 e s
9 0 0.5948031 1.956063 T 0.0413386 0.0393701 e s
9 0 0.9326378 1.956063 T 0.0964567 0.1240157 e s
9 0.03 0.1998425 1.956063 B e e staggered 0 0 0
9 0.004 2.4098425 2.283063 B e e staggered 0 0 0 v
9 0.004 2.4098425 1.967063 B e e staggered 0 0 0 v
9 0.004 1.0098425 1.956063 B e e staggered 0 0 0 v
10 0 0.9045275 1.2244094 T 0.0275591 0.0354331 e s
10 0 2.4491925 2.358813 T 0.00984 0.06102 e s
10 0 0.5948031 1.431063 T 0.0413386 0.0393701 e s
10 0 0.9326378 1.431063 T 0.0964567 0.1240157 e s
10 0.03 0.1998425 1.431063 B e e staggered 0 0 0
10 0.004 2.4508425 2.282063 B e e staggered 0 0 0 v
10 0.004 2.4468425 1.437063 B e e staggered 0 0 0 v
10 0.004 1.0088425 1.430063 B e e staggered 0 0 0 v
11 0 0.9015747 0.7185038 T 0.0275591 0.0354331 e s
11 0 0.5948031 0.906063 T 0.0413386 0.0393701 e s
11 0 0.9326378 0.906063 T 0.0964567 0.1240157 e s
11 0 2.4688825 2.358813 T 0.00984 0.06102 e s
11 0.03 0.1998425 0.906063 B e e staggered 0 0 0
11 0.004 2.4758425 2.291063 B e e staggered 0 0 0 v
11 0.004 2.4788425 0.937063 B e e staggered 0 0 0 v
11 0.004 1.0048425 0.906063 B e e staggered 0 0 0 v
12 0 6.459685 3.3321063 T 0.0098425 0.0226378 e s
12 0 3.4920225 1.831443 T 0.06102 0.00984 e s
12 0.004 3.3291721 1.826063 B e e staggered 0 0 0 v
12 0.004 3.3948425 3.447063 B e e staggered 0 0 0 v
12 0.004 6.4475772 3.396063 B e e staggered 0 0 0 v
13 0 3.5311023 2.8923386 T 0.0413386 0.0452756 e s
13 0 2.5279325 2.518253 T 0.00984 0.06102 e s
14 0 3.3331103 3.2062205 T 0.0393701 0.0708661 e s
14 0 2.3507725 2.518253 T 0.00984 0.06102 e s
14 0.004 3.2755905 3.1417323 B e e staggered 0 0 0 v
14 0.004 2.394685 2.7204724 B e e staggered 0 0 0 v
15 0 1.7765525 2.067703 T 0.06102 0.00984 e s
15 0 2.8348425 3.6617716 T 0.019685 0.0354331 e s
15 0 2.9448425 3.6666929 T 0.0570866 0.0374016 e s
15 0.004 2.7998425 3.616063 B e e staggered 0 0 0 v
15 0.004 1.8848425 2.071063 B e e staggered 0 0 0 v
15 0.004 1.8848425 3.601063 B e e staggered 0 0 0 v
16 0 3.4698425 3.6617716 T 0.019685 0.0354331 e s
16 0 3.3498425 3.6666929 T 0.0570866 0.0374016 e s
16 0 1.6171125 2.067703 T 0.06102 0.00984 e s
16 0.004 1.5682025 2.067703 B e e staggered 0 0 0 v
16 0.004 3.4248425 3.636063 B e e staggered 0 0 0 v
16 0.004 1.5498425 3.621063 B e e staggered 0 0 0 v
17 0 1.7765525 2.087393 T 0.06102 0.00984 e s
17 0 2.7198425 3.6617716 T 0.019685 0.0354331 e s
17 0 3.0448425 3.6666929 T 0.0570866 0.0374016 e s
17 0.004 1.7548425 2.126063 B e e staggered 0 0 0 v
17 0.004 1.7548425 3.661063 B e e staggered 0 0 0 v
17 0.004 2.6798425 3.661063 B e e staggered 0 0 0 v
18 0 1.6171125 2.087393 T 0.06102 0.00984 e s
18 0 3.2448425 3.6617716 T 0.019685 0.0354331 e s
18 0 3.1448425 3.6666929 T 0.0570866 0.0374016 e s
18 0.004 1.6198425 2.121063 B e e staggered 0 0 0 v
18 0.004 3.2398425 3.596063 B e e staggered 0 0 0 v
18 0.004 1.5748425 3.596063 B e e staggered 0 0 0 v
19 0 3.0964551 0.1377953 T 0.028 0.165 e s
19 0 2.9783451 0.1377953 T 0.028 0.165 e s
19 0 2.8602351 0.1377953 T 0.028 0.165 e s
19 0 2.7027551 0.1377953 T 0.028 0.165 e s
19 0 2.6633851 0.1377953 T 0.028 0.165 e s
19 0 2.0334651 0.1377953 T 0.028 0.165 e s
19 0 1.9153551 0.1377953 T 0.028 0.165 e s
19 0 2.8208651 0.1377953 T 0.028 0.165 e s
19 0 2.3484251 0.1377953 T 0.028 0.165 e s
19 0 2.4665351 0.1377953 T 0.028 0.165 e s
19 0 2.5452751 0.1377953 T 0.028 0.165 e s
19 0 3.2091732 2.8346456 T 0.0108268 0.0098425 e s
19 0 3.2691732 2.7952756 T 0.0108268 0.0098425 e s
19 0 3.2691732 2.8149606 T 0.0108268 0.0098425 e s
19 0 4.1505905 3.6033465 T 0.0283465 0.0393701 e s
19 0 2.3348425 3.4045276 T 0.082874 0.0440945 e s
19 0 4.0689017 1.7396232 T 0.0708661 0.0098425 e s
19 0 4.0689017 1.6796232 T 0.0708661 0.0098425 e s
19 0 3.9114214 1.6596232 T 0.0708661 0.0098425 e s
19 0 4.9094488 3.9616142 T 0.1653543 0.1259843 e s
19 0 3.1112205 3.1372047 T 0.0787402 0.023622 e s
19 0 6.9063386 2.096063 T 0.0393701 0.0374016 e s
19 0 2.2813858 4.1703386 T 0.0177165 0.0543307 e s
19 0 3.8084646 4.0237008 T 0.019685 0.0905512 e s
19 0 0.6548425 0.8479921 T 0.0866142 0.0413386 e s
19 0 0.6548425 0.9641339 T 0.0866142 0.0413386 e s
19 0 3.4954331 3.7503543 T 0.019685 0.0354331 e s
19 0 1.631559 4.099563 T 0.0570866 0.0177165 e s
19 0 1.8461259 4.124563 T 0.0570866 0.0177165 e s
19 0 6.3522834 2.391063 T 0.0775591 0.0224409 e s
19 0 3.3331103 3.3951969 T 0.0393701 0.0708661 e s
19 0 3.4385827 2.8923386 T 0.0413386 0.0452756 e s
19 0 2.9448425 4.2211417 T 0.05 0.2 e s
19 0 3.3448425 4.2211417 T 0.05 0.2 e s
19 0 4.9579134 4.206063 T 0.0314961 0.0669291 e s
19 0 6.4793701 3.1500197 T 0.0098425 0.0226378 e s
19 0 6.5113582 3.2312205 T 0.0265748 0.0098425 e s
19 0 1.1570472 0.906063 T 0.0964567 0.1240157 e s
19 0 4.3398425 2.7806299 T 0.0570866 0.0452756 e s
19 0 4.0398425 3.0925591 T 0.0374016 0.0393701 e s
19 0 4.1098425 3.0779921 T 0.0251969 0.0267717 e s
19 0 2.3114125 0.878873 T 0.00984 0.06102 e s
19 0 2.4098325 0.878873 T 0.00984 0.06102 e s
19 0 2.5082625 0.878873 T 0.00984 0.06102 e s
19 0 2.6066825 0.878873 T 0.00984 0.06102 e s
19 0 2.9019625 0.878873 T 0.00984 0.06102 e s
19 0 2.3114125 1.038313 T 0.00984 0.06102 e s
19 0 2.4098325 1.038313 T 0.00984 0.06102 e s
19 0 2.5082625 1.038313 T 0.00984 0.06102 e s
19 0 2.6066825 1.038313 T 0.00984 0.06102 e s
19 0 2.6657425 1.038313 T 0.00984 0.06102 e s
19 0 2.7247925 1.038313 T 0.00984 0.06102 e s
19 0 2.7838525 1.038313 T 0.00984 0.06102 e s
19 0 2.8429025 1.038313 T 0.00984 0.06102 e s
19 0 2.9019625 1.038313 T 0.00984 0.06102 e s
19 0 1.6171125 1.988963 T 0.06102 0.00984 e s
19 0 1.6171125 1.890543 T 0.06102 0.00984 e s
19 0 1.6171125 1.792113 T 0.06102 0.00984 e s
19 0 1.6171125 1.693693 T 0.06102 0.00984 e s
19 0 1.6171125 1.595263 T 0.06102 0.00984 e s
19 0 1.6171125 1.496843 T 0.06102 0.00984 e s
19 0 1.6171125 1.398413 T 0.06102 0.00984 e s
19 0 1.7765525 1.988963 T 0.06102 0.00984 e s
19 0 1.7765525 1.890543 T 0.06102 0.00984 e s
19 0 1.7765525 1.792113 T 0.06102 0.00984 e s
19 0 1.7765525 1.693693 T 0.06102 0.00984 e s
19 0 1.7765525 1.595263 T 0.06102 0.00984 e s
19 0 1.7765525 1.496843 T 0.06102 0.00984 e s
19 0 1.7765525 1.398413 T 0.06102 0.00984 e s
19 0 2.2917125 2.358813 T 0.00984 0.06102 e s
19 0 2.3901425 2.358813 T 0.00984 0.06102 e s
19 0 2.4885625 2.358813 T 0.00984 0.06102 e s
19 0 2.5869925 2.358813 T 0.00984 0.06102 e s
19 0 2.6854125 2.358813 T 0.00984 0.06102 e s
19 0 2.7838425 2.358813 T 0.00984 0.06102 e s
19 0 2.8822625 2.358813 T 0.00984 0.06102 e s
19 0 2.2917125 2.518253 T 0.00984 0.06102 e s
19 0 2.3901425 2.518253 T 0.00984 0.06102 e s
19 0 2.4885625 2.518253 T 0.00984 0.06102 e s
19 0 2.5869925 2.518253 T 0.00984 0.06102 e s
19 0 2.6854125 2.518253 T 0.00984 0.06102 e s
19 0 2.7838425 2.518253 T 0.00984 0.06102 e s
19 0 2.8822625 2.518253 T 0.00984 0.06102 e s
19 0 3.6514625 1.418063 T 0.06102 0.00984 e s
19 0 3.6514625 1.516483 T 0.06102 0.00984 e s
19 0 3.6514625 1.614913 T 0.06102 0.00984 e s
19 0 3.6514625 1.713333 T 0.06102 0.00984 e s
19 0 3.6514625 1.811763 T 0.06102 0.00984 e s
19 0 3.6514625 1.910183 T 0.06102 0.00984 e s
19 0 3.6514625 2.008613 T 0.06102 0.00984 e s
19 0 3.4920225 1.418063 T 0.06102 0.00984 e s
19 0 3.4920225 1.516483 T 0.06102 0.00984 e s
19 0 3.4920225 1.614913 T 0.06102 0.00984 e s
19 0 3.4920225 1.713333 T 0.06102 0.00984 e s
19 0 3.4920225 1.811763 T 0.06102 0.00984 e s
19 0 3.4920225 1.910183 T 0.06102 0.00984 e s
19 0 3.4920225 2.008613 T 0.06102 0.00984 e s
19 0 0.6548425 2.0141339 T 0.0866142 0.0413386 e s
19 0 0.6548425 1.8979921 T 0.0866142 0.0413386 e s
19 0 0.6548425 2.5391339 T 0.0866142 0.0413386 e s
19 0 0.6548425 2.4229921 T 0.0866142 0.0413386 e s
19 0 0.6548425 1.3729921 T 0.0866142 0.0413386 e s
19 0 0.6548425 1.4891339 T 0.0866142 0.0413386 e s
19 0 5.7411417 3.3612205 T 0.0452756 0.0570866 e s
19 0 5.6683071 3.359252 T 0.0267717 0.0251969 e s
19 0 6.3348425 2.1106299 T 0.0570866 0.0452756 e s
19 0 6.6598425 2.1664961 T 0.0570866 0.0452756 e s
19 0 6.253937 2.8267717 T 0.0570866 0.0452756 e s
19 0 6.3720472 2.8267717 T 0.0570866 0.0452756 e s
19 0 6.3617717 2.656063 T 0.0267717 0.0251969 e s
19 0 6.3617717 2.501063 T 0.0267717 0.0251969 e s
19 0 6.3617717 2.556063 T 0.0267717 0.0251969 e s
19 0 6.3617717 2.611063 T 0.0267717 0.0251969 e s
19 0 6.6294094 1.421063 T 0.0452756 0.0570866 e s
19 0 6.6294094 1.531063 T 0.0452756 0.0570866 e s
19 0 6.6429133 1.611063 T 0.0267717 0.0251969 e s
19 0 6.6429133 1.671063 T 0.0267717 0.0251969 e s
19 0 6.6429133 1.721063 T 0.0267717 0.0251969 e s
19 0 6.6429133 1.776063 T 0.0267717 0.0251969 e s
19 0 6.0933464 2.171063 T 0.0393701 0.0374016 e s
19 0 4.1048425 3.8414961 T 0.0570866 0.0452756 e s
19 0 4.1948425 3.8375591 T 0.0374016 0.0393701 e s
19 0 6.4394094 3.071063 T 0.0452756 0.0570866 e s
19 0 6.5848425 3.0391338 T 0.0251969 0.0267717 e s
19 0 2.2098425 3.7164961 T 0.0570866 0.0452756 e s
19 0 2.1398425 3.6979922 T 0.0251969 0.0267717 e s
19 0 2.6398425 3.5356299 T 0.0570866 0.0452756 e s
19 0 2.7248425 3.5591338 T 0.0251969 0.0267717 e s
19 0 3.6594094 0.726063 T 0.0452756 0.0570866 e s
19 0 3.6829133 0.636063 T 0.0267717 0.0251969 e s
19 0 3.6938425 3.1176299 T 0.0570866 0.0452756 e s
19 0 3.7698425 3.2011339 T 0.0251969 0.0267717 e s
19 0 3.6888425 3.3295591 T 0.0374016 0.0393701 e s
19 0 2.8604331 3.7503543 T 0.019685 0.0354331 e s
19 0 2.7454331 3.7503543 T 0.019685 0.0354331 e s
19 0 3.2704331 3.7503543 T 0.019685 0.0354331 e s
19 0 1.1570472 1.956063 T 0.0964567 0.1240157 e s
19 0 1.1570472 2.481063 T 0.0964567 0.1240157 e s
19 0 1.1570472 1.431063 T 0.0964567 0.1240157 e s
19 0 6.7276771 1.816063 T 0.0283465 0.0393701 e s
19 0 6.3670079 2.451063 T 0.0283465 0.0393701 e s
19 0 7.0098425 1.9382284 T 0.0393701 0.0283465 e s
19 0 6.0048425 2.3932284 T 0.0393701 0.0283465 e s
19 0 4.4329134 4.206063 T 0.0314961 0.0669291 e s
19 0 6.6374016 1.881063 T 0.0775591 0.0224409 e s
19 0 3.772559 3.758563 T 0.0570866 0.0177165 e s
19 0 3.9871259 3.783563 T 0.0570866 0.0177165 e s
19 0 1.7273386 4.273063 T 0.0393701 0.0374016 e s
19 0 1.8024094 4.276063 T 0.0452756 0.0570866 e s
19 0 6.6048425 3.3275591 T 0.0374016 0.0393701 e s
19 0 6.6048425 3.1295669 T 0.0374016 0.0393701 e s
19 0 4.2094094 3.246063 T 0.0452756 0.0570866 e s
19 0 4.4548425 3.0779921 T 0.0251969 0.0267717 e s
19 0 4.3948425 3.0779921 T 0.0251969 0.0267717 e s
19 0 4.3348425 3.0779921 T 0.0251969 0.0267717 e s
19 0 4.2748425 3.0779921 T 0.0251969 0.0267717 e s
19 0 4.2198425 3.0779921 T 0.0251969 0.0267717 e s
19 0 4.1648425 3.0779921 T 0.0251969 0.0267717 e s
19 0 4.0648425 2.7806299 T 0.0570866 0.0452756 e s
19 0 3.9598425 2.7806299 T 0.0570866 0.0452756 e s
19 0 4.2348425 2.7806299 T 0.0570866 0.0452756 e s
19 0.025 3.9797272 2.4890438 B e e staggered 0 0 0
19 0.025 5.5781524 1.6898312 B e e staggered 0 0 0
19 0.0206693 5.1277559 2.3074803 B e e staggered 0 0 0
19 0.019685 6.1198425 4.056063 B e e staggered 0 0 0
19 0.019685 5.9348031 3.9379527 B e e staggered 0 0 0
19 0.034 0.0998425 1.006063 B e e staggered 0 0 0
19 0.034 0.0998425 0.806063 B e e staggered 0 0 0
19 0.034 0.2998425 0.806063 B e e staggered 0 0 0
19 0.034 0.2998425 1.006063 B e e staggered 0 0 0
19 0.035433 6.5694882 3.5895276 B e e staggered 0 0 0
19 0.035433 6.7348425 3.5895276 B e e staggered 0 0 0
19 0.035433 6.9001969 3.5895276 B e e staggered 0 0 0
19 0.034 0.0998425 2.581063 B e e staggered 0 0 0
19 0.034 0.0998425 2.381063 B e e staggered 0 0 0
19 0.034 0.2998425 2.381063 B e e staggered 0 0 0
19 0.034 0.2998425 2.581063 B e e staggered 0 0 0
19 0.034 0.0998425 2.056063 B e e staggered 0 0 0
19 0.034 0.0998425 1.856063 B e e staggered 0 0 0
19 0.034 0.2998425 1.856063 B e e staggered 0 0 0
19 0.034 0.2998425 2.056063 B e e staggered 0 0 0
19 0.034 0.0998425 1.531063 B e e staggered 0 0 0
19 0.034 0.0998425 1.331063 B e e staggered 0 0 0
19 0.034 0.2998425 1.331063 B e e staggered 0 0 0
19 0.034 0.2998425 1.531063 B e e staggered 0 0 0
19 0 2.4271651 0.1377953 D 0.028 0.165 e p
19 0 2.3090551 0.1377953 D 0.028 0.165 e p
19 0 2.7814951 0.1377953 D 0.028 0.165 e p
19 0 2.9389751 0.1377953 D 0.028 0.165 e p
19 0 2.7421251 0.1377953 D 0.028 0.165 e p
19 0 3.0570851 0.1377953 D 0.028 0.165 e p
19 0 2.8996051 0.1377953 D 0.028 0.165 e p
19 0 2.6240151 0.1377953 D 0.028 0.165 e p
19 0 2.5452751 0.1377953 D 0.028 0.165 e p
19 0 1.9153551 0.1377953 D 0.028 0.165 e p
19 0 2.3982756 2.944063 D 0.0452756 0.0570866 e p
19 0 2.7118425 3.0031338 D 0.0251969 0.0267717 e p
19 0 2.6328425 2.9716299 D 0.0570866 0.0452756 e p
19 0 2.3857717 2.854063 D 0.0267717 0.0251969 e p
19 0.004 2.0348425 0.246063 B e e staggered 0 0 0 v
19 0.004 1.9161425 0.244763 B e e staggered 0 0 0 v
19 0.004 2.3098425 0.246063 B e e staggered 0 0 0 v
19 0.004 3.3308425 3.301063 B e e staggered 0 0 0 v
19 0.004 4.1203866 3.5941508 B e e staggered 0 0 0 v
19 0.004 1.6758425 1.891063 B e e staggered 0 0 0 v
19 0.004 1.7218425 1.890063 B e e staggered 0 0 0 v
19 0.004 3.1830708 3.1358268 B e e staggered 0 0 0 v
19 0.004 3.277559 2.9635827 B e e staggered 0 0 0 v
19 0.004 2.4192759 2.7886295 B e e staggered 0 0 0 v
19 0.004 2.4138425 3.295063 B e e staggered 0 0 0 v
19 0.004 2.3215354 3.361063 B e e staggered 0 0 0 v
19 0.004 2.6318425 2.876063 B e e staggered 0 0 0 v
19 0.004 2.6858425 2.568063 B e e staggered 0 0 0 v
19 0.004 2.5868425 2.569063 B e e staggered 0 0 0 v
19 0.004 2.5818425 2.308063 B e e staggered 0 0 0 v
19 0.004 2.3215354 2.586063 B e e staggered 0 0 0 v
19 0.004 2.4738425 2.980063 B e e staggered 0 0 0 v
19 0.004 0.9370078 2.3179133 B e e staggered 0 0 0 v
19 0.004 1.7268425 4.329374 B e e staggered 0 0 0 v
19 0.004 1.7888425 4.329374 B e e staggered 0 0 0 v
19 0.004 4.4778425 3.135063 B e e staggered 0 0 0 v
19 0.004 4.0648425 2.722063 B e e staggered 0 0 0 v
19 0.004 6.6288425 1.372063 B e e staggered 0 0 0 v
19 0.004 6.9744094 1.9399606 B e e staggered 0 0 0 v
19 0.004 3.9688425 1.671063 B e e staggered 0 0 0 v
19 0.004 4.1318425 1.686063 B e e staggered 0 0 0 v
19 0.004 3.9968425 1.711063 B e e staggered 0 0 0 v
19 0.004 3.9608425 2.724063 B e e staggered 0 0 0 v
19 0.004 6.253937 2.9094488 B e e staggered 0 0 0 v
19 0.004 6.6476378 3.1299213 B e e staggered 0 0 0 v
19 0.004 4.3398425 2.725063 B e e staggered 0 0 0 v
19 0.004 3.4144661 1.805063 B e e staggered 0 0 0 v
19 0.004 3.5908425 1.662063 B e e staggered 0 0 0 v
19 0.004 2.7838425 2.568063 B e e staggered 0 0 0 v
19 0.004 1.7218425 1.989063 B e e staggered 0 0 0 v
19 0.004 2.6658425 1.092063 B e e staggered 0 0 0 v
19 0.004 3.8308425 3.762063 B e e staggered 0 0 0 v
19 0.004 1.6718425 1.792063 B e e staggered 0 0 0 v
19 0.004 3.3958425 4.222063 B e e staggered 0 0 0 v
19 0.004 4.2728425 3.135063 B e e staggered 0 0 0 v
19 0.004 3.7198425 1.996063 B e e staggered 0 0 0 v
19 0.004 3.4108425 1.7136509 B e e staggered 0 0 0 v
19 0.004 1.7148425 1.595063 B e e staggered 0 0 0 v
19 0.004 2.1398425 3.738063 B e e staggered 0 0 0 v
19 0.004 2.4888425 2.413063 B e e staggered 0 0 0 v
19 0.004 4.2088425 3.135063 B e e staggered 0 0 0 v
19 0.004 3.5948425 1.514063 B e e staggered 0 0 0 v
19 0.004 1.6718425 1.399063 B e e staggered 0 0 0 v
19 0.004 6.6268425 3.032063 B e e staggered 0 0 0 v
19 0.004 4.1528425 3.135063 B e e staggered 0 0 0 v
19 0.004 2.7248425 3.521063 B e e staggered 0 0 0 v
19 0.004 2.3118425 0.934063 B e e staggered 0 0 0 v
19 0.004 2.8718425 2.297063 B e e staggered 0 0 0 v
19 0.004 1.2488425 2.000063 B e e staggered 0 0 0 v
19 0.004 3.7198425 1.921063 B e e staggered 0 0 0 v
19 0.004 3.4138425 1.573063 B e e staggered 0 0 0 v
19 0.004 1.7218425 1.694063 B e e staggered 0 0 0 v
19 0.004 4.0688425 3.135063 B e e staggered 0 0 0 v
19 0.004 2.6748425 3.501063 B e e staggered 0 0 0 v
19 0.004 4.2348425 2.725063 B e e staggered 0 0 0 v
19 0.004 2.4048425 2.412063 B e e staggered 0 0 0 v
19 0.004 3.7328425 1.418063 B e e staggered 0 0 0 v
19 0.004 1.6718425 1.497063 B e e staggered 0 0 0 v
19 0.004 3.5548425 1.991063 B e e staggered 0 0 0 v
19 0.004 6.4568425 3.009063 B e e staggered 0 0 0 v
19 0.004 1.6918425 4.079063 B e e staggered 0 0 0 v
19 0.004 3.6428425 0.636063 B e e staggered 0 0 0 v
19 0.004 2.7838425 2.429063 B e e staggered 0 0 0 v
19 0.004 1.6748425 1.989063 B e e staggered 0 0 0 v
19 0.004 4.0398425 3.784063 B e e staggered 0 0 0 v
19 0.004 6.4768425 3.231063 B e e staggered 0 0 0 v
19 0.004 4.3338425 3.135063 B e e staggered 0 0 0 v
19 0.004 3.5548425 1.841063 B e e staggered 0 0 0 v
19 0.004 3.4068425 1.461063 B e e staggered 0 0 0 v
19 0.004 1.7168425 1.399063 B e e staggered 0 0 0 v
19 0.004 1.7188425 1.792063 B e e staggered 0 0 0 v
19 0.004 2.2538425 2.279063 B e e staggered 0 0 0 v
19 0.004 2.9338425 0.953063 B e e staggered 0 0 0 v
19 0.004 2.4758425 2.456063 B e e staggered 0 0 0 v
19 0.004 1.6708425 1.595063 B e e staggered 0 0 0 v
19 0.004 2.9018425 1.095063 B e e staggered 0 0 0 v
19 0.004 3.5548425 1.941063 B e e staggered 0 0 0 v
19 0.004 2.6858425 2.311063 B e e staggered 0 0 0 v
19 0.004 2.6068425 1.091063 B e e staggered 0 0 0 v
19 0.004 1.2618425 2.482063 B e e staggered 0 0 0 v
19 0.004 3.7188425 1.713063 B e e staggered 0 0 0 v
19 0.004 3.5498425 1.413063 B e e staggered 0 0 0 v
19 0.004 2.8818425 2.566063 B e e staggered 0 0 0 v
19 0.004 1.7188425 1.497063 B e e staggered 0 0 0 v
19 0.004 4.1148425 3.135063 B e e staggered 0 0 0 v
19 0.004 6.6488425 3.341063 B e e staggered 0 0 0 v
19 0.004 2.8888425 4.221063 B e e staggered 0 0 0 v
19 0.004 3.3708425 2.888063 B e e staggered 0 0 0 v
19 0.004 2.4098425 2.579063 B e e staggered 0 0 0 v
19 0.004 1.6708425 1.694063 B e e staggered 0 0 0 v
19 0.004 2.2588425 3.741063 B e e staggered 0 0 0 v
19 0.004 2.5088425 1.090063 B e e staggered 0 0 0 v
19 0.004 1.7498425 4.110063 B e e staggered 0 0 0 v
19 0.004 2.2908425 4.217063 B e e staggered 0 0 0 v
19 0.004 3.8808425 3.109063 B e e staggered 0 0 0 v
19 0.004 3.7448425 3.342063 B e e staggered 0 0 0 v
19 0.004 3.7178425 3.072063 B e e staggered 0 0 0 v
19 0.004 5.7338425 3.556063 B e e staggered 0 0 0 v
19 0.004 5.6768425 3.546063 B e e staggered 0 0 0 v
19 0.004 3.6038425 0.682063 B e e staggered 0 0 0 v
19 0.004 6.5488425 1.531063 B e e staggered 0 0 0 v
19 0.004 6.6028425 1.612063 B e e staggered 0 0 0 v
19 0.004 6.6028425 1.672063 B e e staggered 0 0 0 v
19 0.004 6.6028425 1.722063 B e e staggered 0 0 0 v
19 0.004 6.6018425 1.777063 B e e staggered 0 0 0 v
19 0.004 6.6858425 1.828063 B e e staggered 0 0 0 v
19 0.004 6.6998425 1.881063 B e e staggered 0 0 0 v
19 0.004 6.9498425 2.095063 B e e staggered 0 0 0 v
19 0.004 6.6078425 2.176063 B e e staggered 0 0 0 v
19 0.004 6.3958425 2.111063 B e e staggered 0 0 0 v
19 0.004 6.0488425 2.171063 B e e staggered 0 0 0 v
19 0.004 6.0048425 2.434063 B e e staggered 0 0 0 v
19 0.004 6.2748425 2.391063 B e e staggered 0 0 0 v
19 0.004 6.3988425 2.453063 B e e staggered 0 0 0 v
19 0.004 6.3978425 2.501063 B e e staggered 0 0 0 v
19 0.004 6.3968425 2.556063 B e e staggered 0 0 0 v
19 0.004 6.3978425 2.610063 B e e staggered 0 0 0 v
19 0.004 6.3988425 2.657063 B e e staggered 0 0 0 v
19 0.004 6.3720472 2.9094488 B e e staggered 0 0 0 v
19 0.004 4.9108425 4.203063 B e e staggered 0 0 0 v
19 0.004 4.3878425 4.206063 B e e staggered 0 0 0 v
19 0.004 3.7778425 4.023063 B e e staggered 0 0 0 v
19 0.004 4.0858425 3.892063 B e e staggered 0 0 0 v
19 0.004 4.1948425 3.884063 B e e staggered 0 0 0 v
19 0.004 4.4318425 3.135063 B e e staggered 0 0 0 v
19 0.004 2.8608425 3.787063 B e e staggered 0 0 0 v
19 0.004 2.7248425 3.729063 B e e staggered 0 0 0 v
19 0.004 3.5318425 3.660063 B e e staggered 0 0 0 v
19 0.004 3.2698425 3.788063 B e e staggered 0 0 0 v
19 0.004 1.2428425 1.472063 B e e staggered 0 0 0 v
19 0.004 1.2568425 0.942063 B e e staggered 0 0 0 v
19 0.004 0.6548425 0.790063 B e e staggered 0 0 0 v
19 0.004 0.6558425 1.028063 B e e staggered 0 0 0 v
19 0.004 0.6548425 1.314063 B e e staggered 0 0 0 v
19 0.004 0.6538425 1.551063 B e e staggered 0 0 0 v
19 0.004 0.6548425 1.839063 B e e staggered 0 0 0 v
19 0.004 0.6548425 2.073063 B e e staggered 0 0 0 v
19 0.004 0.6548425 2.365063 B e e staggered 0 0 0 v
19 0.004 0.6539669 2.5938902 B e e staggered 0 0 0 v
19 0 2.3348425 3.279063 D 0.082874 0.0440945 e p
19 0.004 3.0974409 0.2519685 B e e staggered 0 0 0 v
19 0.004 2.5460625 0.244843 B e e staggered 0 0 0 v
19 0.004 2.8428425 1.095063 B e e staggered 0 0 0 v
19 0.004 2.7841625 1.094063 B e e staggered 0 0 0 v
19 0.004 2.7244825 1.093063 B e e staggered 0 0 0 v
19 0.004 2.4098325 0.932053 B e e staggered 0 0 0 v
19 0.004 2.5082625 0.931483 B e e staggered 0 0 0 v
19 0.004 2.3114125 1.0900094 B e e staggered 0 0 0 v
19 0.004 2.4098325 1.088053 B e e staggered 0 0 0 v
19 0.004 2.7999951 0.2519685 B e e staggered 0 0 0 v
19 0.004 2.636874 0.2479055 B e e staggered 0 0 0 v
19 0.004 2.6066825 0.931903 B e e staggered 0 0 0 v
19 0.004 2.4470546 0.2425914 B e e staggered 0 0 0 v
19 0.004 2.9574751 0.2519685 B e e staggered 0 0 0 v
19 0.004 2.8782843 0.2495967 B e e staggered 0 0 0 v
19 0.0629922 0.149508 3.853669 B e e staggered 0 0 0 v
19 0.0629922 2.531398 2.830047 B e e staggered 0 0 0 v
19 0.0629922 0.149508 2.830047 B e e staggered 0 0 0 v
19 0.0629922 2.531398 3.853669 B e e staggered 0 0 0 v
20 0 2.3348425 3.5620079 T 0.082874 0.0440945 e s
20 0 3.6514625 1.890503 T 0.06102 0.00984 e s
20 0.004 2.2548425 3.536063 B e e staggered 0 0 0 v
20 0.004 2.2998425 1.916063 B e e staggered 0 0 0 v
20 0.004 3.5548425 1.891063 B e e staggered 0 0 0 v
21 0 2.5098425 3.4832677 T 0.082874 0.0440945 e s
21 0 2.9806925 2.358813 T 0.00984 0.06102 e s
21 0.015 2.0433071 4.257874 B e e staggered 0 0 0
21 0.004 2.5798425 3.486063 B e e staggered 0 0 0 v
21 0.004 2.9488425 2.456063 B e e staggered 0 0 0 v
21 0.004 2.5258425 2.463063 B e e staggered 0 0 0 v
22 0 0.9606298 0.7185038 T 0.0275591 0.0354331 e s
22 0 2.3348425 3.4832677 T 0.082874 0.0440945 e s
22 0 2.3877954 2.9586614 T 0.0354331 0.0275591 e s
22 0 3.6514625 1.792073 T 0.06102 0.00984 e s
22 0.004 1.3937008 1.8169291 B e e staggered 0 0 0 v
22 0.004 0.9901575 0.6870079 B e e staggered 0 0 0 v
22 0.004 2.3898425 3.481063 B e e staggered 0 0 0 v
22 0.004 2.3848425 1.941063 B e e staggered 0 0 0 v
22 0.004 3.8048425 1.840063 B e e staggered 0 0 0 v
23 0 2.5098425 3.4045276 T 0.082874 0.0440945 e s
23 0 3.6514625 1.772393 T 0.06102 0.00984 e s
23 0.004 2.6348425 3.406063 B e e staggered 0 0 0 v
23 0.004 2.5498425 1.755063 B e e staggered 0 0 0 v
23 0.004 3.7198425 1.766063 B e e staggered 0 0 0 v
24 0 2.5098425 3.5620079 T 0.082874 0.0440945 e s
24 0 2.9806925 2.518253 T 0.00984 0.06102 e s
24 0.015 1.4576771 4.253937 B e e staggered 0 0 0
24 0.004 2.4348425 3.546063 B e e staggered 0 0 0 v
24 0.004 2.9588425 2.621063 B e e staggered 0 0 0 v
24 0.004 1.4408425 3.557063 B e e staggered 0 0 0 v
24 0.004 2.4291925 2.621063 B e e staggered 0 0 0 v
25 0 3.4920225 1.752703 T 0.06102 0.00984 e s
25 0.004 3.1978425 2.970063 B e e staggered 0 0 0 v
25 0.004 2.4187174 3.1185066 B e e staggered 0 0 0 v
25 0.004 3.1972633 1.714063 B e e staggered 0 0 0 v
25 0 2.3348425 3.1215827 D 0.082874 0.0440945 e p
26 0.004 1.7982283 1.3041339 B e e staggered 0 0 0 v
26 0.004 1.4598425 3.147063 B e e staggered 0 0 0 v
26 0 1.7765525 1.319673 T 0.06102 0.00984 e s
26 0.004 2.5028425 1.316063 B e e staggered 0 0 0 v
26 0 2.1515748 4.0748032 T 0.0354331 0.0275591 e s
26 0.004 2.1460663 4.1037909 B e e staggered 0 0 0 v
26 0.004 2.462374 3.1722441 B e e staggered 0 0 0 v
26 0 2.5098425 3.2003229 D 0.082874 0.0440945 e p
27 0 3.4920225 1.673963 T 0.06102 0.00984 e s
27 0.004 3.2308425 3.235063 B e e staggered 0 0 0 v
27 0.004 2.4140551 3.1998504 B e e staggered 0 0 0 v
27 0.004 3.2248425 1.6613472 B e e staggered 0 0 0 v
27 0 2.3348425 3.2003229 D 0.082874 0.0440945 e p
28 0 3.4920225 1.654283 T 0.06102 0.00984 e s
28 0.004 2.5908425 3.288063 B e e staggered 0 0 0 v
28 0.004 3.2636972 3.3039177 B e e staggered 0 0 0 v
28 0.004 3.2528425 1.661063 B e e staggered 0 0 0 v
28 0 2.5098425 3.279063 D 0.082874 0.0440945 e p
29 0 1.3464567 4.1417323 T 0.0354331 0.0275591 e s
29 0 1.6171125 1.319673 T 0.06102 0.00984 e s
29 0.004 2.5918425 3.1862205 B e e staggered 0 0 0 v
29 0.004 1.5679134 1.2854331 B e e staggered 0 0 0 v
29 0.004 1.3454724 4.1751969 B e e staggered 0 0 0 v
29 0.004 2.2068425 1.298063 B e e staggered 0 0 0 v
29 0.004 2.2058425 3.200063 B e e staggered 0 0 0 v
29 0 2.5098425 3.1215827 D 0.082874 0.0440945 e p
30 0 6.44 3.1500197 T 0.0098425 0.0226378 e s
30 0 3.6514625 1.496803 T 0.06102 0.00984 e s
30 0.004 3.8648425 1.511063 B e e staggered 0 0 0 v
30 0.004 3.8298425 3.176063 B e e staggered 0 0 0 v
30 0.004 6.4398425 3.191063 B e e staggered 0 0 0 v
31 0 6.3883268 3.2312205 T 0.0265748 0.0098425 e s
31 0 3.6514625 1.477113 T 0.06102 0.00984 e s
31 0.004 3.8348425 1.481063 B e e staggered 0 0 0 v
31 0.004 6.3094161 3.199063 B e e staggered 0 0 0 v
31 0.004 3.7998425 3.201063 B e e staggered 0 0 0 v
32 0 6.3883268 3.3296457 T 0.0265748 0.0098425 e s
32 0 1.7765525 1.614953 T 0.06102 0.00984 e s
32 0.004 3.542865 3.3190405 B e e staggered 0 0 0 v
32 0.004 1.8938425 1.693063 B e e staggered 0 0 0 v
32 0.004 3.5898425 1.711063 B e e staggered 0 0 0 v
32 0.004 6.3547483 3.3311384 B e e staggered 0 0 0 v
33 0 6.4203149 3.3321063 T 0.0098425 0.0226378 e s
33 0 1.7765525 1.674003 T 0.06102 0.00984 e s
33 0.004 1.8227825 1.674003 B e e staggered 0 0 0 v
33 0.004 3.6538425 3.293063 B e e staggered 0 0 0 v
33 0.004 3.7248425 1.675063 B e e staggered 0 0 0 v
33 0.004 6.4448425 3.291063 B e e staggered 0 0 0 v
34 0 6.3883268 3.3099606 T 0.0265748 0.0098425 e s
34 0 3.6514625 1.654283 T 0.06102 0.00984 e s
34 0.004 6.3348425 3.266063 B e e staggered 0 0 0 v
34 0.004 3.7448425 3.261063 B e e staggered 0 0 0 v
34 0.004 3.7738632 1.6661021 B e e staggered 0 0 0 v
35 0 6.3883268 3.2509055 T 0.0265748 0.0098425 e s
35 0 3.6514625 1.634593 T 0.06102 0.00984 e s
35 0.004 6.2824161 3.226063 B e e staggered 0 0 0 v
35 0.004 3.8068425 3.235063 B e e staggered 0 0 0 v
35 0.004 3.8038425 1.691063 B e e staggered 0 0 0 v
36 0 6.3883268 3.1524803 T 0.0265748 0.0098425 e s
36 0 3.6514625 1.575543 T 0.06102 0.00984 e s
36 0.004 3.8948425 1.566063 B e e staggered 0 0 0 v
36 0.004 6.3398425 3.151063 B e e staggered 0 0 0 v
36 0.004 3.8548425 3.151063 B e e staggered 0 0 0 v
37 0 6.4203149 3.1500197 T 0.0098425 0.0226378 e s
37 0 3.6514625 1.555853 T 0.06102 0.00984 e s
37 0.004 6.3048425 3.121063 B e e staggered 0 0 0 v
37 0.004 3.9398425 3.121063 B e e staggered 0 0 0 v
37 0.004 3.9248425 1.536063 B e e staggered 0 0 0 v
38 0 1.7765525 1.536213 T 0.06102 0.00984 e s
38 0 4.7070079 4.121063 T 0.0283465 0.0393701 e s
38 0.004 1.7198425 1.536063 B e e staggered 0 0 0 v
38 0.004 4.7547119 4.1159324 B e e staggered 0 0 0 v
38 0.004 1.7798425 4.156063 B e e staggered 0 0 0 v
39 0 3.4920225 1.437743 T 0.06102 0.00984 e s
39 0 5.2670079 4.126063 T 0.0283465 0.0393701 e s
39 0.004 5.2670079 4.0888976 B e e staggered 0 0 0 v
39 0.004 3.5498425 1.441063 B e e staggered 0 0 0 v
39 0.004 3.5048425 4.086063 B e e staggered 0 0 0 v
40 0 3.4920225 1.339323 T 0.06102 0.00984 e s
40 0 0.6389685 4.0388976 T 0.0393701 0.0283465 e s
40 0.004 2.0048425 1.336063 B e e staggered 0 0 0 v
40 0.004 3.3798425 1.336063 B e e staggered 0 0 0 v
40 0.004 2.0048425 3.816063 B e e staggered 0 0 0 v
41 0 3.4920225 1.359003 T 0.06102 0.00984 e s
41 0 0.8406351 4.0388976 T 0.0393701 0.0283465 e s
41 0.004 2.0288425 1.361663 B e e staggered 0 0 0 v
41 0.004 3.4048425 1.363323 B e e staggered 0 0 0 v
41 0.004 2.0298425 3.836063 B e e staggered 0 0 0 v
42 0 3.4920225 1.378693 T 0.06102 0.00984 e s
42 0 1.0423017 4.0388976 T 0.0393701 0.0283465 e s
42 0.004 3.3798425 1.386063 B e e staggered 0 0 0 v
42 0.004 2.0598425 1.386063 B e e staggered 0 0 0 v
42 0.004 2.0598425 3.871063 B e e staggered 0 0 0 v
43 0 3.4920225 1.398373 T 0.06102 0.00984 e s
43 0 1.2439683 4.0388976 T 0.0393701 0.0283465 e s
43 0.004 3.4072822 1.411323 B e e staggered 0 0 0 v
43 0.004 2.0848425 3.896063 B e e staggered 0 0 0 v
43 0.004 2.0838425 1.411663 B e e staggered 0 0 0 v
44 0 0.9635826 1.2244094 T 0.0275591 0.0354331 e s
44 0 2.3310825 2.358813 T 0.00984 0.06102 e s
44 0 2.3114025 2.358813 T 0.00984 0.06102 e s
44 0 2.5279325 2.358813 T 0.00984 0.06102 e s
44 0.025 5.5781524 2.4890438 B e e staggered 0 0 0
44 0.025 5.5781524 0.8906186 B e e staggered 0 0 0
44 0.0206693 4.3277559 2.3074803 B e e staggered 0 0 0
44 0.004 0.996063 1.1870079 B e e staggered 0 0 0 v
44 0.004 2.3308425 2.215063 B e e staggered 0 0 0 v
44 0.004 5.5778425 2.214063 B e e staggered 0 0 0 v
44 0.004 2.4998425 2.236063 B e e staggered 0 0 0 v
44 0.004 5.6348425 2.236063 B e e staggered 0 0 0 v
45 0 3.9114214 1.7796232 T 0.0708661 0.0098425 e s
45 0 2.5476225 2.358813 T 0.00984 0.06102 e s
45 0.004 2.5798425 2.281063 B e e staggered 0 0 0 v
45 0.004 3.9448425 1.816063 B e e staggered 0 0 0 v
45 0.004 2.5798425 1.790063 B e e staggered 0 0 0 v
46 0 2.5673025 2.358813 T 0.00984 0.06102 e s
46 0.025 4.0624044 2.595343 B e e staggered 0 0 0
46 0.0206693 4.9277559 1.0074803 B e e staggered 0 0 0
46 0.004 4.0398425 2.406063 B e e staggered 0 0 0 v
46 0.004 2.5758425 2.412063 B e e staggered 0 0 0 v
47 0 0.9675196 2.2844487 T 0.0275591 0.0354331 e s
47 0 2.3877954 2.8996063 T 0.0354331 0.0275591 e s
47 0 4.0689017 1.6396232 T 0.0708661 0.0098425 e s
47 0 2.6460425 2.358813 T 0.00984 0.06102 e s
47 0.0206693 4.9277559 2.3074803 B e e staggered 0 0 0
47 0.004 0.9968357 2.256036 B e e staggered 0 0 0 v
47 0.004 4.1513063 1.6236232 B e e staggered 0 0 0 v
47 0.004 2.6458425 2.274063 B e e staggered 0 0 0 v
47 0.004 2.6438425 1.616063 B e e staggered 0 0 0 v
47 0.004 2.6929134 2.7214567 B e e staggered 0 0 0 v
48 0 4.0689017 1.6596232 T 0.0708661 0.0098425 e s
48 0 2.6657325 2.358813 T 0.00984 0.06102 e s
48 0.004 4.1348425 1.651063 B e e staggered 0 0 0 v
48 0.004 2.6658425 2.291063 B e e staggered 0 0 0 v
48 0.004 2.6668425 1.640063 B e e staggered 0 0 0 v
49 0 4.0689017 1.5996232 T 0.0708661 0.0098425 e s
49 0 2.7051025 2.358813 T 0.00984 0.06102 e s
49 0.004 4.0648425 1.511063 B e e staggered 0 0 0 v
49 0.004 2.7028425 2.289063 B e e staggered 0 0 0 v
49 0.004 2.6948425 1.481063 B e e staggered 0 0 0 v
50 0 4.0689017 1.6196232 T 0.0708661 0.0098425 e s
50 0 2.7247825 2.358813 T 0.00984 0.06102 e s
50 0.004 4.1798425 1.601063 B e e staggered 0 0 0 v
50 0.004 2.7268425 2.293063 B e e staggered 0 0 0 v
50 0.004 2.7198425 1.591063 B e e staggered 0 0 0 v
51 0.004 0.988189 1.7175197 B e e staggered 0 0 0 v
51 0.004 2.6048425 1.734063 B e e staggered 0 0 0 v
51 0 0.9596456 1.7470472 T 0.0275591 0.0354331 e s
51 0 2.6066725 2.358813 T 0.00984 0.06102 e s
51 0.004 2.5998425 2.436063 B e e staggered 0 0 0 v
51 0.004 4.1348425 1.751063 B e e staggered 0 0 0 v
51 0 4.0689017 1.7596232 T 0.0708661 0.0098425 e s
51 0.0206693 4.7277559 2.3074803 B e e staggered 0 0 0
52 0 4.0689017 1.7796232 T 0.0708661 0.0098425 e s
52 0 2.6263625 2.358813 T 0.00984 0.06102 e s
52 0.004 2.6248425 2.461063 B e e staggered 0 0 0 v
52 0.004 4.0648425 1.796063 B e e staggered 0 0 0 v
52 0.004 2.6268425 1.770063 B e e staggered 0 0 0 v
53 0 2.2125984 4.0748032 T 0.0354331 0.0275591 e s
53 0 2.4688825 2.518253 T 0.00984 0.06102 e s
53 0.025 4.1805146 2.595343 B e e staggered 0 0 0
53 0.0206693 5.3277559 1.0074803 B e e staggered 0 0 0
53 0.004 2.253937 4.0866142 B e e staggered 0 0 0 v
53 0.004 2.4948425 2.661063 B e e staggered 0 0 0 v
54 0 1.3464567 3.9783465 T 0.0354331 0.0275591 e s
54 0 2.4491925 2.518253 T 0.00984 0.06102 e s
54 0.025 4.2986248 2.595343 B e e staggered 0 0 0
54 0.0206693 5.1277559 1.0074803 B e e staggered 0 0 0
54 0.004 2.4948425 2.696063 B e e staggered 0 0 0 v
54 0.004 1.4084645 3.980315 B e e staggered 0 0 0 v
55 0 3.9114214 1.6396232 T 0.0708661 0.0098425 e s
55 0 2.2720325 2.518253 T 0.00984 0.06102 e s
55 0.004 4.0348425 1.546063 B e e staggered 0 0 0 v
55 0.004 2.2720325 2.463873 B e e staggered 0 0 0 v
55 0.004 2.2748425 1.506063 B e e staggered 0 0 0 v
56 0 3.9114214 1.5996232 T 0.0708661 0.0098425 e s
56 0 2.9019525 2.518253 T 0.00984 0.06102 e s
56 0.004 3.9698425 1.552063 B e e staggered 0 0 0 v
56 0.004 2.8948425 2.431063 B e e staggered 0 0 0 v
56 0.004 2.8948425 1.561063 B e e staggered 0 0 0 v
57 0 3.9114214 1.6196232 T 0.0708661 0.0098425 e s
57 0 2.9216325 2.518253 T 0.00984 0.06102 e s
57 0.004 3.9948425 1.551063 B e e staggered 0 0 0 v
57 0.004 2.9208425 2.428063 B e e staggered 0 0 0 v
57 0.004 2.9198425 1.536063 B e e staggered 0 0 0 v
58 0 6.5113582 3.3296457 T 0.0265748 0.0098425 e s
58 0 3.4920225 1.870813 T 0.06102 0.00984 e s
58 0.004 3.4392507 1.870938 B e e staggered 0 0 0 v
58 0.004 6.5098425 3.456063 B e e staggered 0 0 0 v
58 0.004 3.4698425 3.456063 B e e staggered 0 0 0 v
59 0 6.44 3.3321063 T 0.0098425 0.0226378 e s
59 0 3.4920225 1.890503 T 0.06102 0.00984 e s
59 0.004 3.2988425 1.971063 B e e staggered 0 0 0 v
59 0.004 3.3028425 3.344063 B e e staggered 0 0 0 v
59 0.004 6.4098425 3.371063 B e e staggered 0 0 0 v
60 0 4.9094488 2.8080708 T 0.1653543 0.1259843 e s
60 0 3.1112205 3.1872047 T 0.0787402 0.023622 e s
60 0.004 4.7942913 2.8080709 B e e staggered 0 0 0 v
60 0.004 3.1889764 3.1870079 B e e staggered 0 0 0 v
61 0 6.3522834 2.241063 T 0.0775591 0.0224409 e s
61 0 6.4698425 2.2395669 T 0.0374016 0.0393701 e s
62 0 6.3522834 2.341063 T 0.0775591 0.0224409 e s
62 0 6.6798425 2.4201181 T 0.2125984 0.1141732 e s
62 0 6.4698425 2.302559 T 0.0374016 0.0393701 e s
63 0 6.5198425 2.0175591 T 0.0374016 0.0393701 e s
63 0 6.6374016 2.031063 T 0.0775591 0.0224409 e s
64 0 6.5198425 1.954567 T 0.0374016 0.0393701 e s
64 0 6.3198425 1.8420079 T 0.2125984 0.1141732 e s
64 0 6.6374016 1.931063 T 0.0775591 0.0224409 e s
65 0 6.8433465 2.096063 T 0.0393701 0.0374016 e s
65 0 6.8322834 2.031063 T 0.0775591 0.0224409 e s
66 0 6.9398425 1.9229921 T 0.0251969 0.0267717 e s
66 0 6.8322834 1.931063 T 0.0775591 0.0224409 e s
67 0 6.9398425 1.8891338 T 0.0251969 0.0267717 e s
67 0 7.0098425 1.8838977 T 0.0393701 0.0283465 e s
68 0 6.1574016 2.241063 T 0.0775591 0.0224409 e s
68 0 6.1563385 2.171063 T 0.0393701 0.0374016 e s
69 0 6.1574016 2.341063 T 0.0775591 0.0224409 e s
69 0 6.0648425 2.3441339 T 0.0251969 0.0267717 e s
70 0 6.0648425 2.3779922 T 0.0251969 0.0267717 e s
70 0 6.0048425 2.3388977 T 0.0393701 0.0283465 e s
71 0 2.3484251 0.1377953 D 0.028 0.165 e p
71 0 2.3498425 0.3291339 D 0.0251969 0.0267717 e p
72 0 2.3877951 0.1377953 D 0.028 0.165 e p
72 0 2.3898425 0.3291339 D 0.0251969 0.0267717 e p
73 0 2.4665351 0.1377953 D 0.028 0.165 e p
73 0 2.4688425 0.3291339 D 0.0251969 0.0267717 e p
74 0 2.5059051 0.1377953 D 0.028 0.165 e p
74 0 2.5118425 0.3291339 D 0.0251969 0.0267717 e p
75 0 2.6633851 0.1377953 D 0.028 0.165 e p
75 0 2.6648425 0.3291339 D 0.0251969 0.0267717 e p
76 0 2.7027551 0.1377953 D 0.028 0.165 e p
76 0 2.7048425 0.3291339 D 0.0251969 0.0267717 e p
77 0 2.8208651 0.1377953 D 0.028 0.165 e p
77 0 2.8198425 0.3291339 D 0.0251969 0.0267717 e p
78 0 2.8602351 0.1377953 D 0.028 0.165 e p
78 0 2.8548425 0.3291339 D 0.0251969 0.0267717 e p
79 0 2.9783451 0.1377953 D 0.028 0.165 e p
79 0 2.9798425 0.3291339 D 0.0251969 0.0267717 e p
80 0 3.0177151 0.1377953 D 0.028 0.165 e p
80 0 3.0198425 0.3291339 D 0.0251969 0.0267717 e p
81 0 4.1498425 2.7898819 T 0.0385827 0.034252 e s
81 0 4.3398425 2.8514961 T 0.0570866 0.0452756 e s
81 0 4.4348425 2.8422441 T 0.0385827 0.034252 e s
81 0 4.2348425 2.8514961 T 0.0570866 0.0452756 e s
82 0 6.7265748 3.1680709 T 0.0511811 0.0748031 e s
82 0 6.5113582 3.1918504 T 0.0265748 0.0098425 e s
82 0 6.6048425 3.192559 T 0.0374016 0.0393701 e s
83 0 6.7265748 3.2940551 T 0.0511811 0.0748031 e s
83 0 6.5113582 3.2115354 T 0.0265748 0.0098425 e s
83 0 6.6048425 3.264567 T 0.0374016 0.0393701 e s
84 0 5.8879921 3.701063 T 0.0255906 0.0413386 e s
84 0.0324803 5.7234252 3.8444882 B e e staggered 0 0 0
85 0 6.0316929 3.701063 T 0.0255906 0.0413386 e s
85 0.019685 6.1198425 3.8198425 B e e staggered 0 0 0
86 0 6.2029921 3.566063 T 0.0255906 0.0413386 e s
86 0 6.0900079 3.556063 T 0.0283465 0.0393701 e s
86 0 6.1979921 3.701063 T 0.0255906 0.0413386 e s
86 0.0324803 5.7234252 4.0255906 B e e staggered 0 0 0
87 0 6.3466929 3.566063 T 0.0255906 0.0413386 e s
87 0.035433 6.5694882 3.806063 B e e staggered 0 0 0
87 0.035433 6.9001969 3.806063 B e e staggered 0 0 0
87 0.035433 6.7348425 3.806063 B e e staggered 0 0 0
88 0 4.2049212 3.6033465 T 0.0283465 0.0393701 e s
88 0 4.2755905 3.6033465 T 0.0393701 0.0334646 e s
89 0 3.5898425 3.9096063 T 0.0334646 0.0393701 e s
89 0 3.6681102 3.861063 T 0.0255906 0.023622 e s
90 0 3.5898425 3.7275197 T 0.0334646 0.0393701 e s
90 0 3.6681102 3.786063 T 0.0255906 0.023622 e s
91 0 0.6448425 4.1975197 T 0.0334646 0.0393701 e s
91 0 0.6389685 4.0932283 T 0.0393701 0.0283465 e s
92 0 0.8465091 4.1975197 T 0.0334646 0.0393701 e s
92 0 0.8406351 4.0932283 T 0.0393701 0.0283465 e s
93 0 1.0481757 4.1975197 T 0.0334646 0.0393701 e s
93 0 1.0423017 4.0932283 T 0.0393701 0.0283465 e s
94 0 1.2498423 4.1975197 T 0.0334646 0.0393701 e s
94 0 1.2439683 4.0932283 T 0.0393701 0.0283465 e s
95 0 3.9029528 4.0237008 T 0.019685 0.0905512 e s
95 0 3.9871259 3.683563 T 0.0570866 0.0177165 e s
96 0 3.8714567 4.0237008 T 0.019685 0.0905512 e s
96 0 3.772559 3.683563 T 0.0570866 0.0177165 e s
97 0 2.3581575 4.1703386 T 0.0177165 0.0543307 e s
97 0 1.8461259 4.024563 T 0.0570866 0.0177165 e s
97 0.004 2.3533464 4.0177165 B e e staggered 0 0 0 v
97 0.004 1.9038425 4.018063 B e e staggered 0 0 0 v
98 0 2.3325669 4.1703386 T 0.0177165 0.0543307 e s
98 0 1.631559 4.024563 T 0.0570866 0.0177165 e s
99 0 1.631559 4.124563 T 0.0570866 0.0177165 e s
99 0.015 1.4576771 4.153937 B e e staggered 0 0 0
100 0 1.3464567 4.0826772 T 0.0354331 0.0275591 e s
100 0 1.3464567 4.0374016 T 0.0354331 0.0275591 e s
100 0.015 1.4576771 4.053937 B e e staggered 0 0 0
101 0 1.631559 4.199563 T 0.0570866 0.0177165 e s
101 0.015 2.0433071 4.157874 B e e staggered 0 0 0
101 0.004 1.5698819 4.1712599 B e e staggered 0 0 0 v
102 0 2.1515748 4.0157481 T 0.0354331 0.0275591 e s
102 0 2.2125984 4.0157481 T 0.0354331 0.0275591 e s
102 0.015 2.0433071 4.057874 B e e staggered 0 0 0
103 0 2.5059051 0.1377953 T 0.028 0.165 e s
103 0 2.503937 0.5738189 T 0.023622 0.0255906 e s
104 0 3.0570851 0.1572953 T 0.028 0.126 e s
104 0 3.0551181 0.5738189 T 0.023622 0.0255906 e s
105 0 6.7498425 2.0888976 T 0.0393701 0.0283465 e s
105 0 6.8322834 1.981063 T 0.0775591 0.0224409 e s
106 0 6.1574016 2.291063 T 0.0775591 0.0224409 e s
106 0 6.2348425 2.1832284 T 0.0393701 0.0283465 e s
107 0 6.8970078 1.816063 T 0.0283465 0.0393701 e s
107 0 6.7820078 1.816063 T 0.0283465 0.0393701 e s
107 0 6.8322834 1.881063 T 0.0775591 0.0224409 e s
108 0 6.1574016 2.391063 T 0.0775591 0.0224409 e s
108 0 6.3126772 2.451063 T 0.0283465 0.0393701 e s
108 0 6.1228425 2.4338976 T 0.0393701 0.0283465 e s
109 0 2.9448425 3.951063 T 0.05 0.2 e s
109 0 2.9448425 3.7454331 T 0.0570866 0.0374016 e s
110 0 3.0448425 3.951063 T 0.05 0.2 e s
110 0 3.0448425 3.7454331 T 0.0570866 0.0374016 e s
111 0 3.1448425 3.951063 T 0.05 0.2 e s
111 0 3.1448425 3.7454331 T 0.0570866 0.0374016 e s
112 0 3.3448425 3.951063 T 0.05 0.2 e s
112 0 3.3498425 3.7454331 T 0.0570866 0.0374016 e s
113 0 4.1126772 3.701063 T 0.0283465 0.0393701 e s
113 0 3.9871259 3.733563 T 0.0570866 0.0177165 e s
114 0 4.6526771 4.206063 T 0.0283465 0.0393701 e s
114 0 4.6526772 4.121063 T 0.0283465 0.0393701 e s
114 0 4.5667716 4.206063 T 0.0314961 0.0669291 e s
115 0 5.0917716 4.206063 T 0.0314961 0.0669291 e s
115 0 5.2126771 4.206063 T 0.0283465 0.0393701 e s
115 0 5.2126772 4.126063 T 0.0283465 0.0393701 e s
116 0 3.4848425 2.8923386 T 0.0275591 0.0452756 e s
116 0 3.4776771 2.797063 T 0.0283465 0.0393701 e s
117 0 1.8461259 4.074563 T 0.0570866 0.0177165 e s
117 0 1.9338425 4.0748977 T 0.0393701 0.0283465 e s
118 0 3.772559 3.808563 T 0.0570866 0.0177165 e s
118 0 3.9871259 3.708563 T 0.0570866 0.0177165 e s
118 0.004 4.0498425 3.665063 B e e staggered 0 0 0 v
118 0.004 3.8298425 3.806063 B e e staggered 0 0 0 v
119 0 1.631559 4.149563 T 0.0570866 0.0177165 e s
119 0 1.8461259 4.049563 T 0.0570866 0.0177165 e s
120 0 3.4385827 3.0517874 T 0.0413386 0.0452756 e s
120 0 2.2523425 2.518253 T 0.00984 0.06102 e s
120 0.004 2.2523425 2.613563 B e e staggered 0 0 0 v
120 0.004 2.2598425 3.261063 B e e staggered 0 0 0 v
120 0.004 3.3748425 3.273063 B e e staggered 0 0 0 v
120 0.004 3.3688425 3.050063 B e e staggered 0 0 0 v
121 0 2.3898425 0.3629922 D 0.0251969 0.0267717 e p
121 0.004 2.3897638 0.4055118 B e e staggered 0 0 0 v
121 0.004 2.5984252 0.7952756 B e e staggered 0 0 0 v
121 0 2.6263725 0.878873 T 0.00984 0.06102 e s
122 0 2.3498425 0.3629922 D 0.0251969 0.0267717 e p
122 0.004 2.3503937 0.4055118 B e e staggered 0 0 0 v
122 0.004 2.6259843 0.7952756 B e e staggered 0 0 0 v
122 0 2.6460525 0.878873 T 0.00984 0.06102 e s
123 0 1.7765525 1.516523 T 0.06102 0.00984 e s
123 0 2.1468425 2.6248976 T 0.0393701 0.0283465 e s
123 0 2.1909451 0.1377953 D 0.028 0.165 e p
123 0.004 1.8973025 1.516523 B e e staggered 0 0 0 v
124 0 2.4271651 0.1377953 T 0.028 0.165 e s
124 0.004 2.4448819 0.2795276 B e e staggered 0 0 0 v
124 0.004 2.6220472 0.976378 B e e staggered 0 0 0 v
124 0 2.6263725 1.038313 T 0.00984 0.06102 e s
125 0 2.3877951 0.1377953 T 0.028 0.165 e s
125 0.004 2.4133858 0.2795276 B e e staggered 0 0 0 v
125 0 2.6460525 1.038313 T 0.00984 0.06102 e s
125 0.004 2.6496063 0.976378 B e e staggered 0 0 0 v
126 0 2.6240151 0.1377953 T 0.028 0.165 e s
126 0.004 2.6653543 0.7952756 B e e staggered 0 0 0 v
126 0 2.6854225 0.878873 T 0.00984 0.06102 e s
126 0.004 2.6102362 0.2795276 B e e staggered 0 0 0 v
127 0 2.5846451 0.1377953 T 0.028 0.165 e s
127 0.004 2.6929134 0.7952756 B e e staggered 0 0 0 v
127 0 2.7051125 0.878873 T 0.00984 0.06102 e s
127 0.004 2.5787402 0.2795276 B e e staggered 0 0 0 v
128 0 2.7814951 0.1377953 T 0.028 0.165 e s
128 0.004 2.7795276 0.2795276 B e e staggered 0 0 0 v
128 0.004 2.7992126 0.7952756 B e e staggered 0 0 0 v
128 0 2.8035325 0.878873 T 0.00984 0.06102 e s
129 0 2.7421251 0.1377953 T 0.028 0.165 e s
129 0 2.8232225 0.878873 T 0.00984 0.06102 e s
129 0.004 2.8267717 0.7952756 B e e staggered 0 0 0 v
129 0.004 2.74882 0.282312 B e e staggered 0 0 0 v
130 0.004 2.7401575 0.976378 B e e staggered 0 0 0 v
130 0 2.7444825 1.038313 T 0.00984 0.06102 e s
130 0 2.9389751 0.1377953 T 0.028 0.165 e s
130 0.004 2.9370079 0.2795276 B e e staggered 0 0 0 v
131 0 2.8996051 0.1377953 T 0.028 0.165 e s
131 0.004 2.9054946 0.2795104 B e e staggered 0 0 0 v
131 0 2.7641625 1.038313 T 0.00984 0.06102 e s
131 0.004 2.7677165 0.976378 B e e staggered 0 0 0 v
132 0 2.5118425 0.3629922 D 0.0251969 0.0267717 e p
132 0.004 2.6811024 0.976378 B e e staggered 0 0 0 v
132 0 2.6854225 1.038313 T 0.00984 0.06102 e s
132 0.004 2.511811 0.4055118 B e e staggered 0 0 0 v
133 0 2.4688425 0.3629922 D 0.0251969 0.0267717 e p
133 0.004 2.4698827 0.4109883 B e e staggered 0 0 0 v
133 0 2.7051125 1.038313 T 0.00984 0.06102 e s
133 0.004 2.7086614 0.976378 B e e staggered 0 0 0 v
134 0.004 2.7047244 0.4055118 B e e staggered 0 0 0 v
134 0 2.7048425 0.3629922 D 0.0251969 0.0267717 e p
134 0.004 2.7322835 0.7952756 B e e staggered 0 0 0 v
134 0 2.7444825 0.878873 T 0.00984 0.06102 e s
135 0 2.6648425 0.3629922 D 0.0251969 0.0267717 e p
135 0.004 2.6653543 0.4055118 B e e staggered 0 0 0 v
135 0.004 2.7598425 0.7952756 B e e staggered 0 0 0 v
135 0 2.7641625 0.878873 T 0.00984 0.06102 e s
136 0 2.8548425 0.3629922 D 0.0251969 0.0267717 e p
136 0.004 2.8543307 0.4055118 B e e staggered 0 0 0 v
136 0 2.8625925 0.878873 T 0.00984 0.06102 e s
136 0.004 2.8622047 0.7952756 B e e staggered 0 0 0 v
137 0 2.8198425 0.3629922 D 0.0251969 0.0267717 e p
137 0.004 2.8219832 0.4078519 B e e staggered 0 0 0 v
137 0 2.8822725 0.878873 T 0.00984 0.06102 e s
137 0.004 2.8937008 0.7952756 B e e staggered 0 0 0 v
138 0.004 2.7992126 0.976378 B e e staggered 0 0 0 v
138 0 2.8035325 1.038313 T 0.00984 0.06102 e s
138 0 3.0198425 0.3629922 D 0.0251969 0.0267717 e p
138 0.004 3.019685 0.4055118 B e e staggered 0 0 0 v
139 0 2.8232225 1.038313 T 0.00984 0.06102 e s
139 0.004 2.8267717 0.976378 B e e staggered 0 0 0 v
139 0 2.9798425 0.3629922 D 0.0251969 0.0267717 e p
139 0.004 2.980457 0.4091539 B e e staggered 0 0 0 v
140 0 1.7972451 0.1572953 D 0.028 0.126 e p
140 0.004 1.7978425 0.355063 B e e staggered 0 0 0 v
140 0 3.0551181 0.6072835 T 0.023622 0.0255906 e s
140 0 2.503937 0.6072835 T 0.023622 0.0255906 e s
141 0 2.7568898 3.1872047 T 0.0787402 0.023622 e s
141 0 1.7765525 1.811803 T 0.06102 0.00984 e s
141 0.004 3.0688976 3.3956693 B e e staggered 0 0 0 v
141 0.004 3.0568817 1.811803 B e e staggered 0 0 0 v
141 0.004 1.8799377 1.811803 B e e staggered 0 0 0 v
142 0 6.4793701 3.3321063 T 0.0098425 0.0226378 e s
142 0 3.4920225 1.851133 T 0.06102 0.00984 e s
142 0.004 3.4368425 3.457063 B e e staggered 0 0 0 v
142 0.004 3.3928425 1.871063 B e e staggered 0 0 0 v
142 0.004 6.4798425 3.426063 B e e staggered 0 0 0 v
143 0 3.2293307 2.845 T 0.0098425 0.0108268 e s
143 0 3.1112205 3.2872047 T 0.0787402 0.023622 e s
143 0 3.4512205 3.3951969 T 0.0393701 0.0708661 e s
143 0 3.4444882 2.995685 T 0.0531496 0.0275591 e s
143 0 2.8625825 2.358813 T 0.00984 0.06102 e s
143 0.004 3.3588425 3.448063 B e e staggered 0 0 0 v
143 0.004 3.3448425 2.996063 B e e staggered 0 0 0 v
143 0.004 2.8418425 2.263063 B e e staggered 0 0 0 v
143 0.004 3.3428425 2.263063 B e e staggered 0 0 0 v
144 0 3.2091732 2.8149606 T 0.0108268 0.0098425 e s
144 0 3.1112205 3.2372047 T 0.0787402 0.023622 e s
144 0 3.3921654 3.3951969 T 0.0393701 0.0708661 e s
144 0 3.4848425 3.0517874 T 0.0275591 0.0452756 e s
144 0 2.8035225 2.358813 T 0.00984 0.06102 e s
144 0.004 3.4918425 3.103063 B e e staggered 0 0 0 v
144 0.004 3.4918425 3.297063 B e e staggered 0 0 0 v
144 0.004 2.8038425 2.307063 B e e staggered 0 0 0 v
144 0.004 3.4988425 2.341063 B e e staggered 0 0 0 v
145 0 2.9610025 2.358813 T 0.00984 0.06102 e s
145 0 3.7015748 3.861063 T 0.0255906 0.023622 e s
145 0 3.772559 3.858563 T 0.0570866 0.0177165 e s
145 0.004 2.9858425 2.287063 B e e staggered 0 0 0 v
145 0.004 3.0148425 3.831063 B e e staggered 0 0 0 v
145 0.004 3.6998425 3.836063 B e e staggered 0 0 0 v
146 0 2.9019525 2.358813 T 0.00984 0.06102 e s
146 0 3.7015748 3.786063 T 0.0255906 0.023622 e s
146 0 3.772559 3.783563 T 0.0570866 0.0177165 e s
146 0.004 2.9428425 2.286063 B e e staggered 0 0 0 v
146 0.004 2.9933858 3.751063 B e e staggered 0 0 0 v
146 0.004 3.6998425 3.751063 B e e staggered 0 0 0 v

### steps/pcb/layers/bottom/features
#Layer_Physical_Order=6
#Layer_Color=16711680
#
#Feature symbol names
#
$0 r5
$1 r20
$2 rect82.874x44.0945
$3 rect28x165
$4 rect28x126
$5 rect45.2756x57.0866
$6 rect25.1969x26.7717
$7 rect57.0866x45.2756
$8 rect26.7717x25.1969
$9 r8
$10 r10
$11 rect73.8189x67.9134
$12 r3.937
$13 r1
$14 r21.66
$15 r250
$16 r55
$17 s55
$18 r75
$19 r61.0236
$20 s61.0236
$21 r31.4961
$22 r65.9843
$23 r98.4252
$24 oval196.8504x98.4252
$25 oval177.1654x88.5827
$26 oval88.5827x177.1654
$27 r120
$28 r112
$29 r50
$30 r16
$31 r200

#
#Feature attribute names
#
@0 .geometry
@1 .pad_usage
@2 .smd

#
#Feature attribute text strings
#
&0 SMD_RoundX82.8740Y44.0945
&1 SMD_RoundX28.0000Y165.0000
&2 SMD_RoundX28.0000Y126.0000
&3 SMD_RoundX45.2756Y57.0866
&4 SMD_RoundX25.1969Y26.7717
&5 SMD_RoundX57.0866Y45.2756
&6 SMD_RoundX26.7717Y25.1969
&7 Pad_Simple_X21.6600Y21.6600H21.6600C61.6600
&8 Pad_Simple_X250.0000Y250.0000H125.1969C165.1969
&9 Pad_Simple_X55.0000Y55.0000H30.0000C70.0000
&10 Pad_Simple_X75.0000Y75.0000H50.0000C90.0000
&11 Pad_Simple_X61.0236Y61.0236H41.3386C81.3386
&12 Pad_Simple_X31.4961Y31.4961H35.4331C75.4331
&13 Pad_Simple_X65.9843Y65.9843H65.9843C105.9843
&14 Pad_Simple_X98.4252Y98.4252H64.9606C104.9606
&15 Pad_Simple_X196.8504Y98.4252H39.3701C79.3701
&16 Pad_Simple_X177.1654Y88.5827H39.3701C79.3701
&17 Pad_Simple_X88.5827Y177.1654H39.3701C79.3701
&18 Pad_Simple_X120.0000Y120.0000H68.0000C108.0000
&19 Pad_Simple_X112.0000Y112.0000H60.0000C100.0000
&20 Pad_Complex_X50.0000Y50.0000H118.1102C158.1102
&21 Pad_Simple_X98.4252Y98.4252H70.8661C110.8661
&22 Pad_Simple_X50.0000Y50.0000H118.1102C158.1102
&23 VIA_RoundD16.0000H8.0000C48.0000
&24 VIA_RoundD200.0000H125.9843C165.9843

#
#Layer features
#
A 1.7712204 0.4310709 1.6275196 0.4310709 1.69937 0.4310709 12 P 0 N
A 2.3484251 0.1377953 2.3498425 0.1412172 2.3450032 0.1412172 0 P 0 N
A 2.3498425 0.3291339 2.3492125 0.3276129 2.3513635 0.3276129 0 P 0 N
A 2.3498425 0.3629922 2.3503937 0.3643229 2.3485118 0.3643229 0 P 0 N
A 2.3877951 0.1377953 2.3898425 0.1427382 2.3828522 0.1427382 0 P 0 N
A 2.4365786 0.2353319 2.4279525 0.2188809 2.4479528 0.2188808 1 P 0 N
A 2.4665351 0.1377953 2.4688425 0.1433659 2.4609645 0.1433659 0 P 0 N
A 2.4673225 0.111063 2.4673256 0.1110661 2.4636529 0.1147326 0 P 0 N
A 2.4673256 0.1110661 2.4688425 0.1147326 2.4636529 0.1147326 0 P 0 N
A 2.4698188 0.4109188 2.4685313 0.4076215 2.473531 0.4075692 0 P 0 N
A 2.5059051 0.1377953 2.5118425 0.1521295 2.4915709 0.1521295 0 P 0 N
A 2.6633851 0.1377953 2.6648425 0.1413138 2.6598666 0.1413138 0 P 0 N
A 2.6641725 0.111063 2.6648425 0.1126805 2.662555 0.1126805 0 P 0 N
A 2.6648425 0.3629922 2.6653543 0.3642278 2.6636069 0.3642278 0 P 0 N
A 2.7027551 0.1377953 2.7048425 0.1428347 2.6977157 0.1428347 0 P 0 N
A 2.7035425 0.111063 2.7048425 0.1142015 2.700404 0.1142015 0 P 0 N
A 2.8188976 0.3652734 2.8198425 0.3629922 2.8221237 0.3652734 0 P 0 N
A 2.8198425 0.1402641 2.8208651 0.1377953 2.8233339 0.1402641 0 P 0 N
A 2.8216525 0.3247642 2.8198425 0.3291339 2.8154728 0.3247642 0 P 0 N
A 2.8219832 0.407852 2.8188977 0.4032734 2.8238976 0.4032329 0 P 0 N
A 2.8543307 0.3642278 2.8548425 0.3629922 2.8560781 0.3642278 0 P 0 N
A 2.8548425 0.1259828 2.8610038 0.1110817 2.8759423 0.1259828 0 P 0 N
A 2.8548425 0.1508142 2.8602351 0.1377953 2.873254 0.1508142 0 P 0 N
A 2.8610038 0.1110817 2.8610225 0.111063 2.8759423 0.1259828 0 P 0 N
A 2.8910408 0.2438013 2.878307 0.249595 2.8769142 0.2296433 1 P 0 N
A 2.9783451 0.1377953 2.9798425 0.1414103 2.9747301 0.1414103 0 P 0 N
A 2.9791325 0.111063 2.9798425 0.1127771 2.9774184 0.1127771 0 P 0 N
A 2.9798425 0.3291339 2.9791325 0.3274198 2.9815566 0.3274198 0 P 0 N
A 2.9798425 0.3629922 2.980315 0.3641329 2.9787018 0.3641329 0 P 0 N
A 2.9803932 0.4088515 2.980315 0.4079707 2.985315 0.4079707 0 P 0 N
A 3.0177151 0.1377953 3.0198425 0.1429313 3.0125791 0.1429313 0 P 0 N
A 3.0198425 0.3291339 3.0185025 0.3258989 3.0230775 0.3258989 0 P 0 N
L -0.0001175 0.177913 0.5908825 0.177913 13 P 0
L -0.0004331 0.1781182 0.5901181 0.1781182 12 P 0
L 0.5901181 0.1781182 0.5901181 0.5029213 12 P 0
L 0.5901181 0.5029213 1.312559 0.5029213 12 P 0
L 0.5908825 0.177913 0.5908825 0.502913 13 P 0
L 1.312559 0.313945 1.312559 0.5029213 12 P 0
L 1.312559 0.313945 1.6275197 0.313945 12 P 0
L 1.6275197 0.313945 1.6275197 0.4310709 12 P 0
L 1.7980325 0.130563 1.7980325 0.355063 9 P 0
L 1.8374025 0.111063 1.8374025 0.2575406 1 P 0
L 1.8374025 0.2575406 1.8498425 0.2699806 1 P 0
L 1.8498425 0.2699806 1.8767725 0.2430506 1 P 0
L 1.8767725 0.111063 1.8767725 0.2430506 1 P 0
L 1.8968425 0.735063 1.8968425 1.516063 9 P 0
L 1.8968425 0.735063 2.1917325 0.440173 9 P 0
L 1.8968425 1.516063 1.8973025 1.516523 9 P 0
L 1.9161425 0.111063 1.9161425 0.244763 1 P 0
L 2.1122047 0.2559055 2.1122051 0.2559051 1 P 0
L 2.1122051 0.1377953 2.1122051 0.2559051 1 P 0
L 2.1148425 0.2887008 2.1511393 0.252404 1 P 0
L 2.1398425 3.611063 2.3428838 3.611063 1 P 0
L 2.1511393 0.1122862 2.1511393 0.252404 1 P 0
L 2.1511393 0.1122862 2.1523625 0.111063 1 P 0
L 2.1906078 0.1121877 2.1917325 0.111063 1 P 0
L 2.1917325 0.111063 2.1917325 0.440173 9 P 0
L 2.3098425 0.111063 2.3098425 0.246063 1 P 0
L 2.3348425 3.1215827 2.4156413 3.1215827 9 P 0
L 2.3348425 3.2003229 2.335315 3.1998504 9 P 0
L 2.3348425 3.279063 2.3978425 3.279063 10 P 0
L 2.335315 3.1998504 2.4140551 3.1998504 9 P 0
L 2.3492125 0.111063 2.3498425 0.111693 9 P 0
L 2.3498425 0.1412172 2.3498425 0.3291339 0 P 0
L 2.3503937 0.3643229 2.3503937 0.4055118 0 P 0
L 2.3857717 2.854063 2.3865591 2.854063 10 P 0
L 2.3865591 2.854063 2.3941576 2.8464645 10 P 0
L 2.3897638 0.3630709 2.3897638 0.4055118 0 P 0
L 2.3897638 0.3630709 2.3898425 0.3629922 0 P 0
L 2.3898425 0.1427382 2.3898425 0.3291339 0 P 0
L 2.3941576 2.8456771 2.3941576 2.8464645 10 P 0
L 2.3941576 2.8456771 2.4158425 2.8239922 10 P 0
L 2.3978425 3.279063 2.4138425 3.295063 10 P 0
L 2.3982756 2.944063 2.3982756 2.9499685 10 P 0
L 2.3982756 2.9499685 2.4159134 2.9676063 10 P 0
L 2.4156413 3.1215827 2.4187174 3.1185066 9 P 0
L 2.4158425 2.7920629 2.4158425 2.8239922 10 P 0
L 2.4158425 2.7920629 2.4192759 2.7886295 10 P 0
L 2.4159134 2.9676063 2.4218189 2.9676063 10 P 0
L 2.4218189 2.9676063 2.4342756 2.980063 10 P 0
L 2.4279525 0.111063 2.4279525 0.2188809 1 P 0
L 2.4342756 2.980063 2.4738425 2.980063 10 P 0
L 2.4365786 0.2353319 2.4470546 0.2425914 1 P 0
L 2.462374 3.1722441 2.4904528 3.2003229 9 P 0
L 2.4685039 0.3633308 2.4685039 0.4050067 0 P 0
L 2.4685039 0.3633308 2.4688425 0.3629922 0 P 0
L 2.4685039 0.4050067 2.4685312 0.4076215 0 P 0
L 2.4688425 0.1433659 2.4688425 0.3291339 0 P 0
L 2.4698188 0.4109188 2.4698709 0.4109765 0 P 0
L 2.4698709 0.4109765 2.4698827 0.4109883 0 P 0
L 2.4904528 3.2003229 2.5098425 3.2003229 9 P 0
L 2.5098425 3.0428426 2.632496 3.0428426 1 P 0
L 2.5098425 3.1215827 2.5292322 3.1215827 9 P 0
L 2.5098425 3.279063 2.5838425 3.279063 9 P 0
L 2.511811 0.3630237 2.511811 0.4055118 0 P 0
L 2.511811 0.3630237 2.5118425 0.3629922 0 P 0
L 2.5118425 0.1521295 2.5118425 0.3291339 0 P 0
L 2.5292322 3.1215827 2.5918425 3.184193 9 P 0
L 2.5460625 0.111063 2.5460625 0.244843 1 P 0
L 2.5838425 3.279063 2.5898425 3.285063 9 P 0
L 2.5898425 3.285063 2.5898425 3.287063 9 P 0
L 2.5898425 3.287063 2.5908425 3.288063 9 P 0
L 2.5903118 3.1877512 2.5918425 3.1862205 9 P 0
L 2.5918425 3.184193 2.5918425 3.1862205 9 P 0
L 2.6248025 0.111063 2.6248025 0.235834 1 P 0
L 2.6248025 0.235834 2.636874 0.2479055 1 P 0
L 2.6318425 2.876063 2.6328425 2.877063 10 P 0
L 2.632496 3.0428426 2.6328425 3.0424961 1 P 0
L 2.6328425 2.877063 2.6328425 2.9716299 10 P 0
L 2.6328425 2.9716299 2.681126 2.9716299 9 P 0
L 2.6328425 3.0424961 2.6383465 3.0369921 1 P 0
L 2.6383465 3.0369921 2.7118425 3.0369921 1 P 0
L 2.6648425 0.1413138 2.6648425 0.3291339 0 P 0
L 2.6653543 0.3642278 2.6653543 0.4055118 0 P 0
L 2.681126 2.9716299 2.7118425 3.0023464 9 P 0
L 2.7035425 0.111063 2.7048425 0.112363 9 P 0
L 2.7047244 0.3631103 2.7047244 0.4055118 0 P 0
L 2.7047244 0.3631103 2.7048425 0.3629922 0 P 0
L 2.7048425 0.1428347 2.7048425 0.3291339 0 P 0
L 2.7118425 3.0023464 2.7118425 3.0031338 9 P 0
L 2.7198425 3.786063 2.7198504 3.7860709 1 P 0
L 2.7198504 3.7860709 2.7224094 3.7860709 1 P 0
L 2.7224094 3.7860709 2.7845147 3.7860709 1 P 0
L 2.7421251 0.1377953 2.7421251 0.2402527 1 P 0
L 2.7421251 0.2402527 2.7538409 0.2519685 1 P 0
L 2.7538409 0.2519685 2.7992126 0.2519685 1 P 0
L 2.7748425 3.5627559 2.7748425 3.566063 1 P 0
L 2.7748425 3.5627559 3.1570708 3.1805276 1 P 0
L 2.7748425 3.566063 4.0448425 3.566063 1 P 0
L 2.7814951 0.1377953 2.7827304 0.1390306 1 P 0
L 2.7827304 0.1390306 2.7827304 0.2354863 1 P 0
L 2.7827304 0.2354863 2.7992126 0.2519685 1 P 0
L 2.7845147 3.7860709 2.8095068 3.811063 1 P 0
L 2.7992126 0.2519685 2.7999951 0.2519685 1 P 0
L 2.8188976 0.3652734 2.8188976 0.4032734 0 P 0
L 2.8198425 0.1402641 2.8198425 0.3291339 0 P 0
L 2.8543307 0.3642278 2.8543307 0.4055118 0 P 0
L 2.8548425 0.1508142 2.8548425 0.3291339 0 P 0
L 2.8782843 0.2495967 2.878307 0.249595 1 P 0
L 2.8910408 0.2438013 2.8910565 0.2437858 1 P 0
L 2.8910565 0.2437858 2.898863 0.2359795 1 P 0
L 2.898863 0.1385374 2.898863 0.2359795 1 P 0
L 2.898863 0.1385374 2.8996051 0.1377953 1 P 0
L 2.898863 0.2359795 2.9232593 0.2359795 1 P 0
L 2.9232593 0.2359795 2.9349751 0.2242637 1 P 0
L 2.9349751 0.1417953 2.9349751 0.2242637 1 P 0
L 2.9349751 0.1417953 2.9357625 0.1410079 1 P 0
L 2.9357625 0.1410079 2.9389751 0.1377953 1 P 0
L 2.9798425 0.1414103 2.9798425 0.3291339 0 P 0
L 2.980315 0.3641329 2.980315 0.4079707 0 P 0
L 2.9803931 0.4088515 2.9804452 0.4091421 0 P 0
L 2.9804452 0.4091421 2.980457 0.4091539 0 P 0
L 2.998073 3.811063 3.004073 3.805063 1 P 0
L 3.004073 3.805063 3.2188425 3.805063 1 P 0
L 3.0185025 0.111063 3.0198425 0.112403 9 P 0
L 3.019685 0.3631497 3.019685 0.4055118 0 P 0
L 3.019685 0.3631497 3.0198425 0.3629922 0 P 0
L 3.0198425 0.1429313 3.0198425 0.3291339 0 P 0
L 3.0570851 0.1377953 3.0583207 0.1390309 1 P 0
L 3.0578725 0.111063 3.0583207 0.1115112 1 P 0
L 3.0583207 0.1115112 3.0583207 0.1390309 1 P 0
L 3.0583207 0.1390309 3.0593049 0.1400151 1 P 0
L 3.0593049 0.1400151 3.0593049 0.2313944 1 P 0
L 3.0593049 0.2313944 3.079879 0.2519685 1 P 0
L 3.079879 0.2519685 3.0974409 0.2519685 1 P 0
L 3.1570708 2.4856042 3.1570708 3.1805276 1 P 0
L 3.1570708 2.4856042 3.3688425 2.2738325 1 P 0
L 3.2188425 3.805063 3.2198425 3.806063 1 P 0
L 3.2198425 3.806063 3.2248425 3.811063 1 P 0
L 3.3688425 2.2520629 3.3688425 2.2738325 1 P 0
L 3.3688425 2.2520629 3.5498425 2.0710629 1 P 0
L 3.5348425 3.811063 3.5398425 3.806063 1 P 0
L 3.5598425 1.4734894 3.5598425 1.7392351 1 P 0
L 3.5598425 1.4734894 3.6005725 1.4327594 1 P 0
L 3.5598425 1.7392351 3.6398425 1.8192351 1 P 0
L 3.5718425 2.0108325 3.5718425 2.033063 1 P 0
L 3.5718425 2.0108325 3.5808425 2.0018325 1 P 0
L 3.5718425 2.033063 3.5718425 2.058063 1 P 0
L 3.5808425 1.8782351 3.5808425 2.0018325 1 P 0
L 3.5808425 1.8782351 3.6398425 1.8192351 1 P 0
L 3.6005725 1.060333 3.6005725 1.4327594 1 P 0
L 3.6005725 1.060333 3.8898425 0.771063 1 P 0
L 3.8298425 3.806063 3.9448425 3.806063 9 P 0
L 3.8898425 0.771063 4.3397218 1.2209423 1 P 0
L 3.9448425 3.806063 4.0498425 3.701063 9 P 0
L 4.0448425 3.566063 4.2548425 3.776063 1 P 0
L 4.0498425 3.665063 4.0498425 3.701063 9 P 0
L 4.3397218 1.2209423 6.4047218 1.2209423 1 P 0
L 4.5036614 2.7898819 4.5114724 2.7820709 1 P 0
L 4.5114724 2.7820709 5.9858504 2.7820709 1 P 0
L 5.2748425 3.511063 5.9948425 2.791063 1 P 0
L 5.9858504 2.7820709 5.9948425 2.791063 1 P 0
L 5.9948425 2.791063 6.2848425 2.501063 1 P 0
L 5.9948425 3.556063 6.4248425 3.126063 1 P 0
L 6.4047218 1.2209423 6.8448425 1.661063 1 P 0
L 6.4248425 2.181063 6.4248425 3.126063 1 P 0
L 6.4248425 3.126063 7.0048425 2.546063 1 P 0
L 6.7298425 1.336063 7.0048425 1.611063 1 P 0
L 7.0048425 1.611063 7.0048425 2.546063 1 P 0
P 0.0998425 0.806063 27 P 0 0 ;0=18,1=0
P 0.0998425 1.006063 27 P 0 0 ;0=18,1=0
P 0.0998425 1.331063 27 P 0 0 ;0=18,1=0
P 0.0998425 1.531063 27 P 0 0 ;0=18,1=0
P 0.0998425 1.856063 27 P 0 0 ;0=18,1=0
P 0.0998425 2.056063 27 P 0 0 ;0=18,1=0
P 0.0998425 2.381063 27 P 0 0 ;0=18,1=0
P 0.0998425 2.581063 27 P 0 0 ;0=18,1=0
P 0.1998425 0.906063 28 P 0 0 ;0=19,1=0
P 0.1998425 1.431063 28 P 0 0 ;0=19,1=0
P 0.1998425 1.956063 28 P 0 0 ;0=19,1=0
P 0.1998425 2.481063 28 P 0 0 ;0=19,1=0
P 0.285433 4.152063 15 P 0 0 ;0=8,1=0
P 0.2854331 0.3681102 15 P 0 0 ;0=8,1=0
P 0.2998425 0.806063 27 P 0 0 ;0=18,1=0
P 0.2998425 1.006063 27 P 0 0 ;0=18,1=0
P 0.2998425 1.331063 27 P 0 0 ;0=18,1=0
P 0.2998425 1.531063 27 P 0 0 ;0=18,1=0
P 0.2998425 1.856063 27 P 0 0 ;0=18,1=0
P 0.2998425 2.056063 27 P 0 0 ;0=18,1=0
P 0.2998425 2.381063 27 P 0 0 ;0=18,1=0
P 0.2998425 2.581063 27 P 0 0 ;0=18,1=0
P 1.4576771 4.053937 16 P 0 0 ;0=9,1=0
P 1.4576771 4.153937 16 P 0 0 ;0=9,1=0
P 1.4576771 4.253937 17 P 0 0 ;0=9,1=0
P 1.6968325 1.309833 14 P 0 0 ;0=7,1=0
P 1.6968325 2.097233 14 P 0 0 ;0=7,1=0
P 1.7972451 0.1572953 4 P 0 0 ;0=2,1=0,2
P 1.8366151 0.1377953 3 P 0 0 ;0=1,1=0,2
P 1.85187 0.2691929 11 P 0 0
P 1.8759851 0.1377953 3 P 0 0 ;0=1,1=0,2
P 1.9153551 0.1377953 3 P 0 0 ;0=1,1=0,2
P 1.9547251 0.1377953 3 P 0 0 ;0=1,1=0,2
P 1.9940951 0.1377953 3 P 0 0 ;0=1,1=0,2
P 2.0334651 0.1377953 3 P 0 0 ;0=1,1=0,2
P 2.0433071 4.057874 16 P 0 0 ;0=9,1=0
P 2.0433071 4.157874 16 P 0 0 ;0=9,1=0
P 2.0433071 4.257874 17 P 0 0 ;0=9,1=0
P 2.0728351 0.1377953 3 P 0 0 ;0=1,1=0,2
P 2.1122051 0.1377953 3 P 0 0 ;0=1,1=0,2
P 2.1306094 0.2685243 11 P 0 0
P 2.1515751 0.1377953 3 P 0 0 ;0=1,1=0,2
P 2.1909451 0.1377953 3 P 0 0 ;0=1,1=0,2
P 2.2031325 2.438533 14 P 0 0 ;0=7,1=0
P 2.2031425 0.958593 14 P 0 0 ;0=7,1=0
P 2.3090551 0.1377953 3 P 0 0 ;0=1,1=0,2
P 2.3274094 2.944063 5 P 0 0 ;0=3,1=0,2
P 2.3348425 3.0428426 2 P 0 0 ;0=0,1=0,2
P 2.3348425 3.1215827 2 P 0 0 ;0=0,1=0,2
P 2.3348425 3.2003229 2 P 0 0 ;0=0,1=0,2
P 2.3348425 3.279063 2 P 0 0 ;0=0,1=0,2
P 2.3484251 0.1377953 3 P 0 0 ;0=1,1=0,2
P 2.3498425 0.3291339 6 P 0 0 ;0=4,1=0,2
P 2.3498425 0.3629922 6 P 0 0 ;0=4,1=0,2
P 2.3519134 2.854063 8 P 0 0 ;0=6,1=0,2
P 2.3857717 2.854063 8 P 0 0 ;0=6,1=0,2
P 2.3877951 0.1377953 3 P 0 0 ;0=1,1=0,2
P 2.3898425 0.3291339 6 P 0 0 ;0=4,1=0,2
P 2.3898425 0.3629922 6 P 0 0 ;0=4,1=0,2
P 2.3982756 2.944063 5 P 0 0 ;0=3,1=0,2
P 2.4271651 0.1377953 3 P 0 0 ;0=1,1=0,2
P 2.4665351 0.1377953 3 P 0 0 ;0=1,1=0,2
P 2.4688425 0.3291339 6 P 0 0 ;0=4,1=0,2
P 2.4688425 0.3629922 6 P 0 0 ;0=4,1=0,2
P 2.5059051 0.1377953 3 P 0 0 ;0=1,1=0,2
P 2.5098425 3.0428426 2 P 0 0 ;0=0,1=0,2
P 2.5098425 3.1215827 2 P 0 0 ;0=0,1=0,2
P 2.5098425 3.2003229 2 P 0 0 ;0=0,1=0,2
P 2.5098425 3.279063 2 P 0 0 ;0=0,1=0,2
P 2.5118425 0.3291339 6 P 0 0 ;0=4,1=0,2
P 2.5118425 0.3629922 6 P 0 0 ;0=4,1=0,2
P 2.5452751 0.1377953 3 P 0 0 ;0=1,1=0,2
P 2.5846451 0.1377953 3 P 0 0 ;0=1,1=0,2
P 2.6240151 0.1377953 3 P 0 0 ;0=1,1=0,2
P 2.6328425 2.9716299 7 P 0 0 ;0=5,1=0,2
P 2.6328425 3.0424961 7 P 0 0 ;0=5,1=0,2
P 2.6633851 0.1377953 3 P 0 0 ;0=1,1=0,2
P 2.6648425 0.3291339 6 P 0 0 ;0=4,1=0,2
P 2.6648425 0.3629922 6 P 0 0 ;0=4,1=0,2
P 2.7027551 0.1377953 3 P 0 0 ;0=1,1=0,2
P 2.7048425 0.3291339 6 P 0 0 ;0=4,1=0,2
P 2.7048425 0.3629922 6 P 0 0 ;0=4,1=0,2
P 2.7118425 3.0031338 6 P 0 0 ;0=4,1=0,2
P 2.7118425 3.0369921 6 P 0 0 ;0=4,1=0,2
P 2.7421251 0.1377953 3 P 0 0 ;0=1,1=0,2
P 2.7814951 0.1377953 3 P 0 0 ;0=1,1=0,2
P 2.8198425 0.3291339 6 P 0 0 ;0=4,1=0,2
P 2.8198425 0.3629922 6 P 0 0 ;0=4,1=0,2
P 2.8208651 0.1377953 3 P 0 0 ;0=1,1=0,2
P 2.8548425 0.3291339 6 P 0 0 ;0=4,1=0,2
P 2.8548425 0.3629922 6 P 0 0 ;0=4,1=0,2
P 2.8602351 0.1377953 3 P 0 0 ;0=1,1=0,2
P 2.8996051 0.1377953 3 P 0 0 ;0=1,1=0,2
P 2.9389751 0.1377953 3 P 0 0 ;0=1,1=0,2
P 2.9783451 0.1377953 3 P 0 0 ;0=1,1=0,2
P 2.9798425 0.3291339 6 P 0 0 ;0=4,1=0,2
P 2.9798425 0.3629922 6 P 0 0 ;0=4,1=0,2
P 2.9905325 2.438533 14 P 0 0 ;0=7,1=0
P 2.9905425 0.958593 14 P 0 0 ;0=7,1=0
P 2.9948425 4.0861024 22 P 0 0 ;0=13,1=0
P 3.0177151 0.1377953 3 P 0 0 ;0=1,1=0,2
P 3.0198425 0.3291339 6 P 0 0 ;0=4,1=0,2
P 3.0198425 0.3629922 6 P 0 0 ;0=4,1=0,2
P 3.0570851 0.1377953 3 P 0 0 ;0=1,1=0,2
P 3.0964551 0.1377953 3 P 0 0 ;0=1,1=0,2
P 3.2948425 4.0861024 22 P 0 0 ;0=13,1=0
P 3.5717425 1.309793 14 P 0 0 ;0=7,1=0
P 3.5717425 2.097193 14 P 0 0 ;0=7,1=0
P 3.7848425 4.126063 21 P 0 0 ;0=12,1=0
P 3.9580709 4.126063 21 P 0 0 ;0=12,1=0
P 3.9797272 0.8906186 18 P 0 0 ;0=10,1=0
P 3.9797272 2.4890438 18 P 0 0 ;0=10,1=0
P 4.0624044 2.595343 18 P 0 0 ;0=10,1=0
P 4.1805146 2.595343 18 P 0 0 ;0=10,1=0
P 4.2986248 2.595343 18 P 0 0 ;0=10,1=0
P 4.3277559 1.0074803 20 P 0 0 ;0=11,1=0
P 4.3277559 2.3074803 19 P 0 0 ;0=11,1=0
P 4.7277559 2.3074803 19 P 0 0 ;0=11,1=0
P 4.9277559 1.0074803 19 P 0 0 ;0=11,1=0
P 4.9277559 2.3074803 19 P 0 0 ;0=11,1=0
P 5.1277559 1.0074803 19 P 0 0 ;0=11,1=0
P 5.1277559 2.3074803 19 P 0 0 ;0=11,1=0
P 5.3277559 1.0074803 19 P 0 0 ;0=11,1=0
P 5.3277559 2.3074803 19 P 0 0 ;0=11,1=0
P 5.5781524 0.8906186 18 P 0 0 ;0=10,1=0
P 5.5781524 1.6898312 18 P 0 0 ;0=10,1=0
P 5.5781524 2.4890438 18 P 0 0 ;0=10,1=0
P 5.7234252 3.8444882 23 P 0 0 ;0=14,1=0
P 5.7234252 4.0255906 23 P 0 0 ;0=14,1=0
P 5.9348031 3.9379527 26 P 0 0 ;0=17,1=0
P 6.1198425 3.8198425 24 P 0 0 ;0=15,1=0
P 6.1198425 4.056063 25 P 0 0 ;0=16,1=0
P 6.5694882 3.5895276 23 P 0 0 ;0=21,1=0
P 6.5694882 3.806063 23 P 0 0 ;0=21,1=0
P 6.5694882 4.0934646 29 P 0 0 ;0=20,1=0
P 6.7348425 3.5895276 23 P 0 0 ;0=21,1=0
P 6.7348425 3.806063 23 P 0 0 ;0=21,1=0
P 6.9001969 3.5895276 23 P 0 0 ;0=21,1=0
P 6.9001969 3.806063 23 P 0 0 ;0=21,1=0
P 6.9001969 4.0934646 29 P 0 0 ;0=22,1=0
S P 0
OB 4.3498425 4.3342197 I
OS 2.0148425 4.3342197
OS 2.0117211 4.3335988
OS 2.0090748 4.3318307
OS 2.0073067 4.3291844
OS 2.0066858 4.326063
OS 2.0066858 4.293374
OS 2.0073067 4.2902526
OS 2.0078071 4.2895037
OS 2.0078071 4.2262443
OS 2.0073067 4.2254954
OS 2.0066858 4.222374
OS 2.0066858 4.1869833
OS 2.0069573 4.1856183
OS 2.0071613 4.1842387
OS 2.0072668 4.1840625
OS 2.0073067 4.1838619
OS 2.0080802 4.1827043
OS 2.0087964 4.1815082
OS 2.0089609 4.1813861
OS 2.0090748 4.1812156
OS 2.0097978 4.1807325
OS 2.0104583 4.1799335
OS 2.0122979 4.1757771
OS 2.0087209 4.1671414
OS 2.0075008 4.157874
OS 2.0087209 4.1486066
OS 2.0122979 4.1399709
OS 2.0104583 4.1358145
OS 2.0097978 4.1350155
OS 2.0090748 4.1345324
OS 2.0089609 4.1343619
OS 2.0087964 4.1342398
OS 2.0080806 4.1330444
OS 2.0073067 4.1318861
OS 2.0072667 4.1316852
OS 2.0071614 4.1315093
OS 2.0069575 4.1301308
OS 2.0066858 4.1287647
OS 2.0066858 4.0869833
OS 2.0069573 4.0856183
OS 2.0071613 4.0842387
OS 2.0072668 4.0840625
OS 2.0073067 4.0838619
OS 2.0080802 4.0827043
OS 2.0087964 4.0815082
OS 2.0089609 4.0813861
OS 2.0090748 4.0812156
OS 2.0097978 4.0807325
OS 2.0104583 4.0799335
OS 2.0122979 4.0757771
OS 2.0087209 4.0671414
OS 2.0075008 4.057874
OS 2.0087209 4.0486066
OS 2.0122979 4.0399709
OS 2.0104583 4.0358145
OS 2.0097978 4.0350155
OS 2.0090748 4.0345324
OS 2.0089609 4.0343619
OS 2.0087964 4.0342398
OS 2.0080806 4.0330444
OS 2.0073067 4.0318861
OS 2.0072667 4.0316852
OS 2.0071614 4.0315093
OS 2.0069575 4.0301308
OS 2.0066858 4.0287647
OS 2.0066858 3.850728
OS 2.0069918 3.8491898
OS 2.0072894 3.8476485
OS 2.0073022 3.8476291
OS 2.0073067 3.8476066
OS 2.008179 3.846301
OS 2.0090429 3.8449925
OS 2.0090618 3.8449797
OS 2.0090748 3.8449603
OS 2.0103831 3.8440861
OS 2.0116793 3.8432096
OS 2.0146979 3.8419396
OS 2.013529 3.836063
OS 2.0136749 3.8353296
OS 2.0130932 3.8343873
OS 2.0093423 3.8314814
OS 2.0048425 3.8323765
OS 1.9985996 3.8311347
OS 1.9933071 3.8275984
OS 1.9897708 3.8223059
OS 1.988529 3.816063
OS 1.9897708 3.8098201
OS 1.9933071 3.8045276
OS 1.9985996 3.8009913
OS 2.0048424 3.7997495
OS 2.0066858 3.7982367
OS 2.0066858 2.718063
OS 2.0073067 2.7149416
OS 2.0090748 2.7122953
OS 2.0117211 2.7105272
OS 2.0148425 2.7099063
OS 2.3498425 2.7099063
OS 2.3529639 2.7105272
OS 2.3556102 2.7122953
OS 2.3573783 2.7149416
OS 2.3579992 2.718063
OS 2.3579992 2.8334646
OS 2.3876251 2.8334646
OS 2.4025878 2.8185019
OS 2.4025878 2.7920629
OS 2.4031166 2.7894046
OS 2.4029624 2.7886295
OS 2.4042042 2.7823866
OS 2.4077405 2.7770941
OS 2.413033 2.7735578
OS 2.4192759 2.772316
OS 2.4255188 2.7735578
OS 2.4308113 2.7770941
OS 2.4310756 2.7774896
OS 2.4370112 2.7773731
OS 2.443754 2.7663699
OS 2.4547943 2.7534433
OS 2.4677209 2.742403
OS 2.4822154 2.7335207
OS 2.497921 2.7270152
OS 2.5144508 2.7230468
OS 2.531398 2.721713
OS 2.5483452 2.7230468
OS 2.564875 2.7270152
OS 2.5805806 2.7335207
OS 2.5950751 2.742403
OS 2.6080017 2.7534433
OS 2.619042 2.7663699
OS 2.6279243 2.7808644
OS 2.6344298 2.79657
OS 2.6383982 2.8130998
OS 2.639732 2.830047
OS 2.6383982 2.8469942
OS 2.6358691 2.857529
OS 2.6380855 2.8609914
OS 2.6433779 2.8645276
OS 2.6469142 2.8698201
OS 2.648156 2.876063
OS 2.6469142 2.8823059
OS 2.6460972 2.8835286
OS 2.6460972 2.9409921
OS 2.6693858 2.9409921
OS 2.6693858 2.9593948
OS 2.681126 2.9593948
OS 2.6858082 2.9603261
OS 2.6897775 2.9629784
OS 2.7085471 2.981748
OS 2.7324409 2.981748
OS 2.7324409 3.0245196
OS 2.6912441 3.0245196
OS 2.6912441 2.999051
OS 2.6760581 2.983865
OS 2.6693858 2.983865
OS 2.6693858 3.0022677
OS 2.5962992 3.0022677
OS 2.5962992 2.9409921
OS 2.6195878 2.9409921
OS 2.6195878 2.900784
OS 2.6145878 2.8989394
OS 2.6080017 2.9066507
OS 2.5950751 2.917691
OS 2.5805806 2.9265733
OS 2.564875 2.9330788
OS 2.5483452 2.9370472
OS 2.531398 2.938381
OS 2.5144508 2.9370472
OS 2.497921 2.9330788
OS 2.4822154 2.9265733
OS 2.4677209 2.917691
OS 2.4547943 2.9066507
OS 2.443754 2.8937241
OS 2.4348717 2.8792296
OS 2.4283662 2.863524
OS 2.4243978 2.8469942
OS 2.4239315 2.8410698
OS 2.4192405 2.8393392
OS 2.4071575 2.8514222
OS 2.4071575 2.8746614
OS 2.3579992 2.8746614
OS 2.3579992 2.9075197
OS 2.3580472 2.9075197
OS 2.3580472 2.9806063
OS 2.3579992 2.9806063
OS 2.3579992 3.0127954
OS 2.3842795 3.0127954
OS 2.3842795 3.0728898
OS 2.3579992 3.0728898
OS 2.3579992 3.0915355
OS 2.3842795 3.0915355
OS 2.3842795 3.1093476
OS 2.4055942 3.1093476
OS 2.407182 3.1069712
OS 2.4081253 3.1063409
OS 2.4081253 3.1003275
OS 2.4057888 3.0987663
OS 2.4007141 3.0911714
OS 2.3989321 3.0822126
OS 2.4007141 3.0732538
OS 2.4057888 3.0656589
OS 2.4133837 3.0605842
OS 2.4223425 3.0588022
OS 2.4313013 3.0605842
OS 2.4388962 3.0656589
OS 2.4439709 3.0732538
OS 2.4457529 3.0822126
OS 2.4439709 3.0911714
OS 2.4388962 3.0987663
OS 2.4329346 3.1027496
OS 2.4313655 3.1052197
OS 2.4315364 3.1088922
OS 2.4337891 3.1122637
OS 2.4350309 3.1185066
OS 2.4337891 3.1247495
OS 2.4302528 3.130042
OS 2.4249603 3.1335783
OS 2.4187174 3.1348201
OS 2.4136785 3.1338178
OS 2.3842795 3.1338178
OS 2.3842795 3.1516299
OS 2.3579992 3.1516299
OS 2.3579992 3.1702757
OS 2.3842795 3.1702757
OS 2.3842795 3.1876153
OS 2.4035669 3.1876153
OS 2.4078122 3.1847787
OS 2.4140551 3.1835369
OS 2.420298 3.1847787
OS 2.4255905 3.188315
OS 2.4291268 3.1936075
OS 2.4303686 3.1998504
OS 2.4291268 3.2060933
OS 2.4255905 3.2113858
OS 2.4250776 3.2117285
OS 2.4261334 3.2170365
OS 2.4313013 3.2180645
OS 2.4388962 3.2231392
OS 2.4439709 3.2307341
OS 2.4457529 3.2396929
OS 2.4439709 3.2486517
OS 2.4388962 3.2562466
OS 2.4313013 3.2613213
OS 2.4223425 3.2631033
OS 2.4133837 3.2613213
OS 2.4057888 3.2562466
OS 2.4007141 3.2486517
OS 2.3989321 3.2396929
OS 2.4007141 3.2307341
OS 2.4057888 3.2231392
OS 2.4098502 3.2204255
OS 2.4087944 3.2151175
OS 2.4078122 3.2149221
OS 2.4035669 3.2120855
OS 2.3842795 3.2120855
OS 2.3842795 3.2303701
OS 2.3579992 3.2303701
OS 2.3579992 3.2490158
OS 2.3842795 3.2490158
OS 2.3842795 3.2658083
OS 2.3978425 3.2658083
OS 2.4029149 3.2668173
OS 2.407215 3.2696905
OS 2.4168778 3.2793533
OS 2.4200854 3.2799913
OS 2.4253779 3.2835276
OS 2.4289142 3.2888201
OS 2.430156 3.295063
OS 2.4289142 3.3013059
OS 2.4253779 3.3065984
OS 2.4200854 3.3101347
OS 2.4138425 3.3113765
OS 2.4075996 3.3101347
OS 2.4023071 3.3065984
OS 2.3987708 3.3013059
OS 2.3981328 3.2980983
OS 2.3923522 3.2923177
OS 2.3842795 3.2923177
OS 2.3842795 3.3091102
OS 2.3579992 3.3091102
OS 2.3579992 3.3226844
OS 2.6745231 3.6392082
OS 2.674748 3.6395448
OS 2.6750608 3.6398015
OS 2.6756255 3.6408581
OS 2.6762912 3.6418544
OS 2.6763702 3.6422515
OS 2.6765609 3.6426082
OS 2.6798424 3.6447494
OS 2.6860854 3.6459913
OS 2.6913779 3.6495276
OS 2.6949142 3.6548201
OS 2.6957968 3.659257
OS 2.6961561 3.661063
OS 2.6982973 3.6643446
OS 2.698654 3.6645353
OS 2.6990511 3.6646143
OS 2.7000469 3.6652797
OS 2.7011041 3.6658447
OS 2.7013611 3.6661578
OS 2.7016973 3.6663825
OS 2.7132212 3.6779063
OS 3.5207477 3.6779063
OS 3.5222645 3.6729063
OS 3.5203071 3.6715984
OS 3.5167708 3.6663059
OS 3.515529 3.660063
OS 3.5167708 3.6538201
OS 3.5203071 3.6485276
OS 3.5255996 3.6449913
OS 3.5318425 3.6437495
OS 3.5380854 3.6449913
OS 3.5433779 3.6485276
OS 3.5469142 3.6538201
OS 3.548156 3.660063
OS 3.5469142 3.6663059
OS 3.5433779 3.6715984
OS 3.5414205 3.6729063
OS 3.5429373 3.6779063
OS 3.804842 3.6779063
OS 3.8048425 3.6779062
OS 3.8079639 3.6785272
OS 3.8106102 3.6802953
OS 3.8106104 3.6802956
OS 3.9137557 3.7834408
OS 3.9155239 3.7860872
OS 3.9161448 3.7892084
OS 3.9200787 3.7938279
OS 3.9397746 3.7938279
OS 4.0376074 3.6959951
OS 4.0376074 3.6755512
OS 4.0347708 3.6713059
OS 4.033529 3.665063
OS 4.0347708 3.6588201
OS 4.0383071 3.6535276
OS 4.0435996 3.6499913
OS 4.0498425 3.6487495
OS 4.0560854 3.6499913
OS 4.0613779 3.6535276
OS 4.0649142 3.6588201
OS 4.066156 3.665063
OS 4.0649142 3.6713059
OS 4.0620776 3.6755512
OS 4.0620776 3.701063
OS 4.0611463 3.7057452
OS 4.058494 3.7097145
OS 3.953494 3.8147145
OS 3.9526586 3.8152727
OS 3.9519159 3.8216011
OS 4.0682212 3.9379063
OS 4.1814639 3.9379063
OS 4.3416858 3.7776843
OS 4.3416858 3.6629063
OS 3.8503629 3.1715834
OS 3.8457549 3.1740465
OS 3.846156 3.176063
OS 3.8449142 3.1823059
OS 3.8413779 3.1875984
OS 3.8360854 3.1911347
OS 3.8298425 3.1923765
OS 3.8235996 3.1911347
OS 3.8183071 3.1875984
OS 3.8147708 3.1823059
OS 3.813529 3.176063
OS 3.8147708 3.1698201
OS 3.8183071 3.1645276
OS 3.8235996 3.1609913
OS 3.8298425 3.1597495
OS 3.831859 3.1601506
OS 3.8343221 3.1555426
OS 3.8248425 3.146063
OS 3.8248425 2.201063
OS 4.1548425 1.871063
OS 6.6872812 1.871063
OS 6.6883071 1.8695276
OS 6.6935996 1.8659913
OS 6.6998425 1.8647495
OS 6.7060854 1.8659913
OS 6.7113779 1.8695276
OS 6.7124038 1.871063
OS 6.9016858 1.871063
OS 6.9016858 1.6494416
OS 6.6376591 1.385415
OS 6.6350854 1.3871347
OS 6.6288425 1.3883765
OS 6.6225996 1.3871347
OS 6.6173071 1.3835984
OS 6.6137708 1.3783059
OS 6.612529 1.372063
OS 6.6137708 1.3658201
OS 6.6154905 1.3632463
OS 6.5840748 1.3318307
OS 6.5823067 1.3291845
OS 6.5816857 1.326063
OS 6.5816858 1.3260625
OS 6.5816858 1.241063
OS 6.5823067 1.2379415
OS 6.5840748 1.2352953
OS 6.5840751 1.2352951
OS 6.6440748 1.1752953
OS 6.646721 1.1735272
OS 6.6498425 1.1729062
OS 6.649843 1.1729063
OS 6.779842 1.1729063
OS 6.7798425 1.1729062
OS 6.7829639 1.1735272
OS 6.7856102 1.1752953
OS 6.9302231 1.3199082
OS 6.9348425 1.3179947
OS 6.9348425 1.216063
OS 6.3298425 0.611063
OS 3.7848425 0.611063
OS 2.6382883 1.7576175
OS 2.638378 1.7585277
OS 2.6419142 1.7638201
OS 2.643156 1.770063
OS 2.6419142 1.7763059
OS 2.6383779 1.7815984
OS 2.6330854 1.7851347
OS 2.6268425 1.7863765
OS 2.6205996 1.7851347
OS 2.6153072 1.7815985
OS 2.614397 1.7815088
OS 2.4254888 1.970417
OS 2.4249142 1.9733059
OS 2.4213779 1.9785984
OS 2.4160854 1.9821347
OS 2.4131965 1.9827093
OS 1.3558428 3.0400633
OS 1.3558428 4.1628831
OS 1.3570078 4.1636615
OS 1.3605441 4.168954
OS 1.3617859 4.1751969
OS 1.3605441 4.1814398
OS 1.3570078 4.1867323
OS 1.3558428 4.1875107
OS 1.3558428 4.341063
OS 1.7093962 4.341063
OS 1.7120688 4.336063
OS 1.7117708 4.3356169
OS 1.710529 4.329374
OS 1.7117708 4.3231311
OS 1.7153071 4.3178386
OS 1.7205996 4.3143023
OS 1.7268425 4.3130605
OS 1.7330854 4.3143023
OS 1.7383779 4.3178386
OS 1.7419142 4.3231311
OS 1.743156 4.329374
OS 1.7419142 4.3356169
OS 1.7416162 4.336063
OS 1.7442888 4.341063
OS 1.7713962 4.341063
OS 1.7740688 4.336063
OS 1.7737708 4.3356169
OS 1.772529 4.329374
OS 1.7737708 4.3231311
OS 1.7773071 4.3178386
OS 1.7825996 4.3143023
OS 1.7888425 4.3130605
OS 1.7950854 4.3143023
OS 1.8003779 4.3178386
OS 1.8039142 4.3231311
OS 1.805156 4.329374
OS 1.8039142 4.3356169
OS 1.8036162 4.336063
OS 1.8062888 4.341063
OS 4.3498425 4.341063
OS 4.3498425 4.3342197
OE
OB 1.4931771 4.289437 H
OS 1.4221771 4.289437
OS 1.4221771 4.218437
OS 1.4931771 4.218437
OS 1.4931771 4.289437
OE
OB 1.5698819 4.1875734 H
OS 1.563639 4.1863316
OS 1.5583465 4.1827953
OS 1.5548102 4.1775028
OS 1.5535684 4.1712599
OS 1.5548102 4.165017
OS 1.5583465 4.1597245
OS 1.563639 4.1561882
OS 1.5698819 4.1549464
OS 1.5761248 4.1561882
OS 1.5814173 4.1597245
OS 1.5849536 4.165017
OS 1.5861954 4.1712599
OS 1.5849536 4.1775028
OS 1.5814173 4.1827953
OS 1.5761248 4.1863316
OS 1.5698819 4.1875734
OE
OB 1.7798425 4.1723765 H
OS 1.7735996 4.1711347
OS 1.7683071 4.1675984
OS 1.7647708 4.1623059
OS 1.763529 4.156063
OS 1.7647708 4.1498201
OS 1.7683071 4.1445276
OS 1.7735996 4.1409913
OS 1.7798425 4.1397495
OS 1.7860854 4.1409913
OS 1.7913779 4.1445276
OS 1.7949142 4.1498201
OS 1.796156 4.156063
OS 1.7949142 4.1623059
OS 1.7913779 4.1675984
OS 1.7860854 4.1711347
OS 1.7798425 4.1723765
OE
OB 1.4576771 4.1897433 H
OS 1.4484097 4.1885232
OS 1.4397739 4.1849462
OS 1.4323582 4.1792559
OS 1.4266679 4.1718402
OS 1.4230909 4.1632044
OS 1.4218708 4.153937
OS 1.4230909 4.1446696
OS 1.4266679 4.1360338
OS 1.4323582 4.1286181
OS 1.4397739 4.1229278
OS 1.4484097 4.1193508
OS 1.4576771 4.1181307
OS 1.4669445 4.1193508
OS 1.4755803 4.1229278
OS 1.482996 4.1286181
OS 1.4886863 4.1360338
OS 1.4922633 4.1446696
OS 1.4934834 4.153937
OS 1.4922633 4.1632044
OS 1.4886863 4.1718402
OS 1.482996 4.1792559
OS 1.4755803 4.1849462
OS 1.4669445 4.1885232
OS 1.4576771 4.1897433
OE
OB 1.7498425 4.1263765 H
OS 1.7435996 4.1251347
OS 1.7383071 4.1215984
OS 1.7347708 4.1163059
OS 1.733529 4.110063
OS 1.7347708 4.1038201
OS 1.7383071 4.0985276
OS 1.7435996 4.0949913
OS 1.7498425 4.0937495
OS 1.7560854 4.0949913
OS 1.7613779 4.0985276
OS 1.7649142 4.1038201
OS 1.766156 4.110063
OS 1.7649142 4.1163059
OS 1.7613779 4.1215984
OS 1.7560854 4.1251347
OS 1.7498425 4.1263765
OE
OB 1.6918425 4.0953765 H
OS 1.6855996 4.0941347
OS 1.6803071 4.0905984
OS 1.6767708 4.0853059
OS 1.675529 4.079063
OS 1.6767708 4.0728201
OS 1.6803071 4.0675276
OS 1.6855996 4.0639913
OS 1.6918425 4.0627495
OS 1.6980854 4.0639913
OS 1.7033779 4.0675276
OS 1.7069142 4.0728201
OS 1.708156 4.079063
OS 1.7069142 4.0853059
OS 1.7033779 4.0905984
OS 1.6980854 4.0941347
OS 1.6918425 4.0953765
OE
OB 1.4576771 4.0897433 H
OS 1.4484097 4.0885232
OS 1.4397739 4.0849462
OS 1.4323582 4.0792559
OS 1.4266679 4.0718402
OS 1.4230909 4.0632044
OS 1.4218708 4.053937
OS 1.4230909 4.0446696
OS 1.4266679 4.0360338
OS 1.4323582 4.0286181
OS 1.4397739 4.0229278
OS 1.4484097 4.0193508
OS 1.4576771 4.0181307
OS 1.4669445 4.0193508
OS 1.4755803 4.0229278
OS 1.482996 4.0286181
OS 1.4886863 4.0360338
OS 1.4922633 4.0446696
OS 1.4934834 4.053937
OS 1.4922633 4.0632044
OS 1.4886863 4.0718402
OS 1.482996 4.0792559
OS 1.4755803 4.0849462
OS 1.4669445 4.0885232
OS 1.4576771 4.0897433
OE
OB 1.9038425 4.0343765 H
OS 1.8975996 4.0331347
OS 1.8923071 4.0295984
OS 1.8887708 4.0243059
OS 1.887529 4.018063
OS 1.8887708 4.0118201
OS 1.8923071 4.0065276
OS 1.8975996 4.0029913
OS 1.9038425 4.0017495
OS 1.9100854 4.0029913
OS 1.9153779 4.0065276
OS 1.9189142 4.0118201
OS 1.920156 4.018063
OS 1.9189142 4.0243059
OS 1.9153779 4.0295984
OS 1.9100854 4.0331347
OS 1.9038425 4.0343765
OE
OB 1.4084645 3.9966285 H
OS 1.4022216 3.9953867
OS 1.3969291 3.9918504
OS 1.3933928 3.9865579
OS 1.392151 3.980315
OS 1.3933928 3.9740721
OS 1.3969291 3.9687796
OS 1.4022216 3.9652433
OS 1.4084645 3.9640015
OS 1.4147074 3.9652433
OS 1.4199999 3.9687796
OS 1.4235362 3.9740721
OS 1.424778 3.980315
OS 1.4235362 3.9865579
OS 1.4199999 3.9918504
OS 1.4147074 3.9953867
OS 1.4084645 3.9966285
OE
OB 4.0858425 3.9083765 H
OS 4.0795996 3.9071347
OS 4.0743071 3.9035984
OS 4.0707708 3.8983059
OS 4.069529 3.892063
OS 4.0707708 3.8858201
OS 4.0743071 3.8805276
OS 4.0795996 3.8769913
OS 4.0858425 3.8757495
OS 4.0920854 3.8769913
OS 4.0973779 3.8805276
OS 4.1009142 3.8858201
OS 4.102156 3.892063
OS 4.1009142 3.8983059
OS 4.0973779 3.9035984
OS 4.0920854 3.9071347
OS 4.0858425 3.9083765
OE
OB 4.1948425 3.9003765 H
OS 4.1885996 3.8991347
OS 4.1833071 3.8955984
OS 4.1797708 3.8903059
OS 4.178529 3.884063
OS 4.1797708 3.8778201
OS 4.1833071 3.8725276
OS 4.1885996 3.8689913
OS 4.1948425 3.8677495
OS 4.2010854 3.8689913
OS 4.2063779 3.8725276
OS 4.2099142 3.8778201
OS 4.211156 3.884063
OS 4.2099142 3.8903059
OS 4.2063779 3.8955984
OS 4.2010854 3.8991347
OS 4.1948425 3.9003765
OE
OB 4.0398425 3.8003765 H
OS 4.0335996 3.7991347
OS 4.0283071 3.7955984
OS 4.0247708 3.7903059
OS 4.023529 3.784063
OS 4.0247708 3.7778201
OS 4.0283071 3.7725276
OS 4.0335996 3.7689913
OS 4.0398425 3.7677495
OS 4.0460854 3.7689913
OS 4.0513779 3.7725276
OS 4.0549142 3.7778201
OS 4.056156 3.784063
OS 4.0549142 3.7903059
OS 4.0513779 3.7955984
OS 4.0460854 3.7991347
OS 4.0398425 3.8003765
OE
OB 1.8498425 3.7173765 H
OS 1.8435996 3.7161347
OS 1.8383071 3.7125984
OS 1.8347708 3.7073059
OS 1.833529 3.701063
OS 1.8347708 3.6948201
OS 1.8383071 3.6895276
OS 1.8435996 3.6859913
OS 1.8498425 3.6847495
OS 1.8560854 3.6859913
OS 1.8613779 3.6895276
OS 1.8649142 3.6948201
OS 1.866156 3.701063
OS 1.8649142 3.7073059
OS 1.8613779 3.7125984
OS 1.8560854 3.7161347
OS 1.8498425 3.7173765
OE
OB 1.7548425 3.6773765 H
OS 1.7485996 3.6761347
OS 1.7433071 3.6725984
OS 1.7397708 3.6673059
OS 1.738529 3.661063
OS 1.7397708 3.6548201
OS 1.7433071 3.6495276
OS 1.7485996 3.6459913
OS 1.7548425 3.6447495
OS 1.7610854 3.6459913
OS 1.7663779 3.6495276
OS 1.7699142 3.6548201
OS 1.771156 3.661063
OS 1.7699142 3.6673059
OS 1.7663779 3.6725984
OS 1.7610854 3.6761347
OS 1.7548425 3.6773765
OE
OB 3.4248425 3.6523765 H
OS 3.4185996 3.6511347
OS 3.4133071 3.6475984
OS 3.4097708 3.6423059
OS 3.408529 3.636063
OS 3.4097708 3.6298201
OS 3.4133071 3.6245276
OS 3.4185996 3.6209913
OS 3.4248425 3.6197495
OS 3.4310854 3.6209913
OS 3.4363779 3.6245276
OS 3.4399142 3.6298201
OS 3.441156 3.636063
OS 3.4399142 3.6423059
OS 3.4363779 3.6475984
OS 3.4310854 3.6511347
OS 3.4248425 3.6523765
OE
OB 2.7998425 3.6323765 H
OS 2.7935996 3.6311347
OS 2.7883071 3.6275984
OS 2.7847708 3.6223059
OS 2.783529 3.616063
OS 2.7847708 3.6098201
OS 2.7883071 3.6045276
OS 2.7935996 3.6009913
OS 2.7998425 3.5997495
OS 2.8060854 3.6009913
OS 2.8113779 3.6045276
OS 2.8149142 3.6098201
OS 2.816156 3.616063
OS 2.8149142 3.6223059
OS 2.8113779 3.6275984
OS 2.8060854 3.6311347
OS 2.7998425 3.6323765
OE
OB 1.8848425 3.6173765 H
OS 1.8785996 3.6161347
OS 1.8733071 3.6125984
OS 1.8697708 3.6073059
OS 1.868529 3.601063
OS 1.8697708 3.5948201
OS 1.8733071 3.5895276
OS 1.8785996 3.5859913
OS 1.8848425 3.5847495
OS 1.8910854 3.5859913
OS 1.8963779 3.5895276
OS 1.8999142 3.5948201
OS 1.901156 3.601063
OS 1.8999142 3.6073059
OS 1.8963779 3.6125984
OS 1.8910854 3.6161347
OS 1.8848425 3.6173765
OE
OB 3.2398425 3.6123765 H
OS 3.2335996 3.6111347
OS 3.2283071 3.6075984
OS 3.2247708 3.6023059
OS 3.223529 3.596063
OS 3.2247708 3.5898201
OS 3.2283071 3.5845276
OS 3.2335996 3.5809913
OS 3.2398425 3.5797495
OS 3.2460854 3.5809913
OS 3.2513779 3.5845276
OS 3.2549142 3.5898201
OS 3.256156 3.596063
OS 3.2549142 3.6023059
OS 3.2513779 3.6075984
OS 3.2460854 3.6111347
OS 3.2398425 3.6123765
OE
OB 1.5498425 3.6373765 H
OS 1.5435996 3.6361347
OS 1.5383071 3.6325984
OS 1.5347708 3.6273059
OS 1.533529 3.621063
OS 1.5347708 3.6148201
OS 1.5383071 3.6095276
OS 1.5435996 3.6059913
OS 1.5498425 3.6047495
OS 1.5560854 3.6059913
OS 1.5563282 3.6061536
OS 1.5599331 3.6025487
OS 1.5597708 3.6023059
OS 1.558529 3.596063
OS 1.5597708 3.5898201
OS 1.5633071 3.5845276
OS 1.5685996 3.5809913
OS 1.5748425 3.5797495
OS 1.5810854 3.5809913
OS 1.5863779 3.5845276
OS 1.5899142 3.5898201
OS 1.591156 3.596063
OS 1.5899142 3.6023059
OS 1.5863779 3.6075984
OS 1.5810854 3.6111347
OS 1.5748425 3.6123765
OS 1.5685996 3.6111347
OS 1.5683568 3.6109724
OS 1.5647519 3.6145773
OS 1.5649142 3.6148201
OS 1.566156 3.621063
OS 1.5649142 3.6273059
OS 1.5613779 3.6325984
OS 1.5560854 3.6361347
OS 1.5498425 3.6373765
OE
OB 4.1203866 3.6104643 H
OS 4.1141437 3.6092225
OS 4.1088512 3.6056862
OS 4.1053149 3.6003937
OS 4.1040731 3.5941508
OS 4.1053149 3.5879079
OS 4.1088512 3.5826154
OS 4.1141437 3.5790791
OS 4.1203866 3.5778373
OS 4.1266295 3.5790791
OS 4.131922 3.5826154
OS 4.1354583 3.5879079
OS 4.1367001 3.5941508
OS 4.1354583 3.6003937
OS 4.131922 3.6056862
OS 4.1266295 3.6092225
OS 4.1203866 3.6104643
OE
OB 1.4408425 3.5733765 H
OS 1.4345996 3.5721347
OS 1.4293071 3.5685984
OS 1.4257708 3.5633059
OS 1.424529 3.557063
OS 1.4257708 3.5508201
OS 1.4293071 3.5455276
OS 1.4345996 3.5419913
OS 1.4408425 3.5407495
OS 1.4470854 3.5419913
OS 1.4523779 3.5455276
OS 1.4559142 3.5508201
OS 1.457156 3.557063
OS 1.4559142 3.5633059
OS 1.4523779 3.5685984
OS 1.4470854 3.5721347
OS 1.4408425 3.5733765
OE
OB 2.7248425 3.5373765 H
OS 2.7185996 3.5361347
OS 2.7133071 3.5325984
OS 2.7097708 3.5273059
OS 2.708529 3.521063
OS 2.7097708 3.5148201
OS 2.7133071 3.5095276
OS 2.7185996 3.5059913
OS 2.7248425 3.5047495
OS 2.7310854 3.5059913
OS 2.7363779 3.5095276
OS 2.7399142 3.5148201
OS 2.741156 3.521063
OS 2.7399142 3.5273059
OS 2.7363779 3.5325984
OS 2.7310854 3.5361347
OS 2.7248425 3.5373765
OE
OB 2.6748425 3.5173765 H
OS 2.6685996 3.5161347
OS 2.6633071 3.5125984
OS 2.6597708 3.5073059
OS 2.658529 3.501063
OS 2.6597708 3.4948201
OS 2.6633071 3.4895276
OS 2.6685996 3.4859913
OS 2.6748425 3.4847495
OS 2.6810854 3.4859913
OS 2.6863779 3.4895276
OS 2.6899142 3.4948201
OS 2.691156 3.501063
OS 2.6899142 3.5073059
OS 2.6863779 3.5125984
OS 2.6810854 3.5161347
OS 2.6748425 3.5173765
OE
OB 3.6228425 3.5023765 H
OS 3.6165996 3.5011347
OS 3.6113071 3.4975984
OS 3.6077708 3.4923059
OS 3.606529 3.486063
OS 3.6077708 3.4798201
OS 3.6113071 3.4745276
OS 3.6165996 3.4709913
OS 3.6228425 3.4697495
OS 3.6290854 3.4709913
OS 3.6343779 3.4745276
OS 3.6379142 3.4798201
OS 3.639156 3.486063
OS 3.6379142 3.4923059
OS 3.6343779 3.4975984
OS 3.6290854 3.5011347
OS 3.6228425 3.5023765
OE
OB 2.5798425 3.5023765 H
OS 2.5735996 3.5011347
OS 2.5683071 3.4975984
OS 2.5647708 3.4923059
OS 2.563529 3.486063
OS 2.5647708 3.4798201
OS 2.5683071 3.4745276
OS 2.5735996 3.4709913
OS 2.5798425 3.4697495
OS 2.5860854 3.4709913
OS 2.5913779 3.4745276
OS 2.5949142 3.4798201
OS 2.596156 3.486063
OS 2.5949142 3.4923059
OS 2.5913779 3.4975984
OS 2.5860854 3.5011347
OS 2.5798425 3.5023765
OE
OB 3.5298425 3.4973765 H
OS 3.5235996 3.4961347
OS 3.5183071 3.4925984
OS 3.5147708 3.4873059
OS 3.513529 3.481063
OS 3.5147708 3.4748201
OS 3.5183071 3.4695276
OS 3.5235996 3.4659913
OS 3.5298425 3.4647495
OS 3.5360854 3.4659913
OS 3.5413779 3.4695276
OS 3.5449142 3.4748201
OS 3.546156 3.481063
OS 3.5449142 3.4873059
OS 3.5413779 3.4925984
OS 3.5360854 3.4961347
OS 3.5298425 3.4973765
OE
OB 3.4368425 3.4733765 H
OS 3.4305996 3.4721347
OS 3.4253071 3.4685984
OS 3.4217708 3.4633059
OS 3.420529 3.457063
OS 3.4217708 3.4508201
OS 3.4253071 3.4455276
OS 3.4305996 3.4419913
OS 3.4368425 3.4407495
OS 3.4430854 3.4419913
OS 3.4483779 3.4455276
OS 3.4502305 3.4483003
OS 3.4506142 3.4484287
OS 3.4560152 3.4479578
OS 3.4583071 3.4445276
OS 3.4635996 3.4409913
OS 3.4698425 3.4397495
OS 3.4760854 3.4409913
OS 3.4813779 3.4445276
OS 3.4849142 3.4498201
OS 3.486156 3.456063
OS 3.4849142 3.4623059
OS 3.4813779 3.4675984
OS 3.4760854 3.4711347
OS 3.4698425 3.4723765
OS 3.4635996 3.4711347
OS 3.4583071 3.4675984
OS 3.4564545 3.4648257
OS 3.4560708 3.4646973
OS 3.4506698 3.4651682
OS 3.4483779 3.4685984
OS 3.4430854 3.4721347
OS 3.4368425 3.4733765
OE
OB 3.3588425 3.4643765 H
OS 3.3525996 3.4631347
OS 3.3473071 3.4595984
OS 3.3437708 3.4543059
OS 3.342529 3.448063
OS 3.3437708 3.4418201
OS 3.3473071 3.4365276
OS 3.3525996 3.4329913
OS 3.3588425 3.4317495
OS 3.3650854 3.4329913
OS 3.3703779 3.4365276
OS 3.3739142 3.4418201
OS 3.3741941 3.443227
OS 3.379292 3.443227
OS 3.3797708 3.4408201
OS 3.3833071 3.4355276
OS 3.3885996 3.4319913
OS 3.3948425 3.4307495
OS 3.4010854 3.4319913
OS 3.4063779 3.4355276
OS 3.4099142 3.4408201
OS 3.411156 3.447063
OS 3.4099142 3.4533059
OS 3.4063779 3.4585984
OS 3.4010854 3.4621347
OS 3.3948425 3.4633765
OS 3.3885996 3.4621347
OS 3.3833071 3.4585984
OS 3.3797708 3.4533059
OS 3.3794909 3.451899
OS 3.374393 3.451899
OS 3.3739142 3.4543059
OS 3.3703779 3.4595984
OS 3.3650854 3.4631347
OS 3.3588425 3.4643765
OE
OB 2.6348425 3.4223765 H
OS 2.6285996 3.4211347
OS 2.6233071 3.4175984
OS 2.6197708 3.4123059
OS 2.618529 3.406063
OS 2.6197708 3.3998201
OS 2.6233071 3.3945276
OS 2.6285996 3.3909913
OS 2.6348425 3.3897495
OS 2.6410854 3.3909913
OS 2.6463779 3.3945276
OS 2.6499142 3.3998201
OS 2.651156 3.406063
OS 2.6499142 3.4123059
OS 2.6463779 3.4175984
OS 2.6410854 3.4211347
OS 2.6348425 3.4223765
OE
OB 3.0688976 3.4119828 H
OS 3.0626547 3.410741
OS 3.0573622 3.4072047
OS 3.0538259 3.4019122
OS 3.0525841 3.3956693
OS 3.0538259 3.3894264
OS 3.0573622 3.3841339
OS 3.0626547 3.3805976
OS 3.0688976 3.3793558
OS 3.0751405 3.3805976
OS 3.080433 3.3841339
OS 3.0839693 3.3894264
OS 3.0852111 3.3956693
OS 3.0839693 3.4019122
OS 3.080433 3.4072047
OS 3.0751405 3.410741
OS 3.0688976 3.4119828
OE
OB 3.3028425 3.3603765 H
OS 3.2965996 3.3591347
OS 3.2913071 3.3555984
OS 3.2877708 3.3503059
OS 3.286529 3.344063
OS 3.2877708 3.3378201
OS 3.2913071 3.3325276
OS 3.2965996 3.3289913
OS 3.3028425 3.3277495
OS 3.3090854 3.3289913
OS 3.3143779 3.3325276
OS 3.3179142 3.3378201
OS 3.319156 3.344063
OS 3.3179142 3.3503059
OS 3.3143779 3.3555984
OS 3.3090854 3.3591347
OS 3.3028425 3.3603765
OE
OB 3.7448425 3.3583765 H
OS 3.7385996 3.3571347
OS 3.7333071 3.3535984
OS 3.7297708 3.3483059
OS 3.728529 3.342063
OS 3.7297708 3.3358201
OS 3.7333071 3.3305276
OS 3.7385996 3.3269913
OS 3.7448425 3.3257495
OS 3.7510854 3.3269913
OS 3.7563779 3.3305276
OS 3.7599142 3.3358201
OS 3.761156 3.342063
OS 3.7599142 3.3483059
OS 3.7563779 3.3535984
OS 3.7510854 3.3571347
OS 3.7448425 3.3583765
OE
OB 3.542865 3.335354 H
OS 3.5366221 3.3341122
OS 3.5313296 3.3305759
OS 3.5277933 3.3252834
OS 3.5265515 3.3190405
OS 3.5277933 3.3127976
OS 3.5313296 3.3075051
OS 3.5366221 3.3039688
OS 3.542865 3.302727
OS 3.5491079 3.3039688
OS 3.5544004 3.3075051
OS 3.5579367 3.3127976
OS 3.5591785 3.3190405
OS 3.5579367 3.3252834
OS 3.5544004 3.3305759
OS 3.5491079 3.3341122
OS 3.542865 3.335354
OE
OB 3.2636972 3.3202312 H
OS 3.2574543 3.3189894
OS 3.2521618 3.3154531
OS 3.2486255 3.3101606
OS 3.2473837 3.3039177
OS 3.2486255 3.2976748
OS 3.2521618 3.2923823
OS 3.2574543 3.288846
OS 3.2636972 3.2876042
OS 3.2699401 3.288846
OS 3.2752326 3.2923823
OS 3.2787689 3.2976748
OS 3.2800107 3.3039177
OS 3.2787689 3.3101606
OS 3.2752326 3.3154531
OS 3.2699401 3.3189894
OS 3.2636972 3.3202312
OE
OB 3.3308425 3.3173765 H
OS 3.3245996 3.3161347
OS 3.3193071 3.3125984
OS 3.3157708 3.3073059
OS 3.314529 3.301063
OS 3.3157708 3.2948201
OS 3.3193071 3.2895276
OS 3.3245996 3.2859913
OS 3.3308425 3.2847495
OS 3.3370854 3.2859913
OS 3.3423779 3.2895276
OS 3.3459142 3.2948201
OS 3.347156 3.301063
OS 3.3459142 3.3073059
OS 3.3423779 3.3125984
OS 3.3370854 3.3161347
OS 3.3308425 3.3173765
OE
OB 3.4918425 3.3133765 H
OS 3.4855996 3.3121347
OS 3.4803071 3.3085984
OS 3.4767708 3.3033059
OS 3.475529 3.297063
OS 3.4767708 3.2908201
OS 3.4803071 3.2855276
OS 3.4855996 3.2819913
OS 3.4918425 3.2807495
OS 3.4980854 3.2819913
OS 3.5033779 3.2855276
OS 3.5069142 3.2908201
OS 3.508156 3.297063
OS 3.5069142 3.3033059
OS 3.5033779 3.3085984
OS 3.4980854 3.3121347
OS 3.4918425 3.3133765
OE
OB 3.6538425 3.3093765 H
OS 3.6475996 3.3081347
OS 3.6423071 3.3045984
OS 3.6387708 3.2993059
OS 3.637529 3.293063
OS 3.6387708 3.2868201
OS 3.6423071 3.2815276
OS 3.6475996 3.2779913
OS 3.6538425 3.2767495
OS 3.6600854 3.2779913
OS 3.6653779 3.2815276
OS 3.6689142 3.2868201
OS 3.670156 3.293063
OS 3.6689142 3.2993059
OS 3.6653779 3.3045984
OS 3.6600854 3.3081347
OS 3.6538425 3.3093765
OE
OB 3.3748425 3.2893765 H
OS 3.3685996 3.2881347
OS 3.3633071 3.2845984
OS 3.3597708 3.2793059
OS 3.358529 3.273063
OS 3.3597708 3.2668201
OS 3.3633071 3.2615276
OS 3.3685996 3.2579913
OS 3.3748425 3.2567495
OS 3.3810854 3.2579913
OS 3.3863779 3.2615276
OS 3.3899142 3.2668201
OS 3.391156 3.273063
OS 3.3899142 3.2793059
OS 3.3863779 3.2845984
OS 3.3810854 3.2881347
OS 3.3748425 3.2893765
OE
OB 2.5592795 3.3091102 H
OS 2.4604055 3.3091102
OS 2.4604055 3.2490158
OS 2.5592795 3.2490158
OS 2.5592795 3.2668279
OS 2.5838425 3.2668279
OS 2.5885247 3.2677592
OS 2.592494 3.2704115
OS 2.5945743 3.2724918
OS 2.5970854 3.2729913
OS 2.6023779 3.2765276
OS 2.6059142 3.2818201
OS 2.607156 3.288063
OS 2.6059142 3.2943059
OS 2.6023779 3.2995984
OS 2.5970854 3.3031347
OS 2.5908425 3.3043765
OS 2.5845996 3.3031347
OS 2.5793071 3.2995984
OS 2.5757708 3.2943059
OS 2.5751725 3.2912981
OS 2.5592795 3.2912981
OS 2.5592795 3.3091102
OE
OB 3.7448425 3.2773765 H
OS 3.7385996 3.2761347
OS 3.7333071 3.2725984
OS 3.7297708 3.2673059
OS 3.728529 3.261063
OS 3.7297708 3.2548201
OS 3.7333071 3.2495276
OS 3.7385996 3.2459913
OS 3.7448425 3.2447495
OS 3.7510854 3.2459913
OS 3.7563779 3.2495276
OS 3.7599142 3.2548201
OS 3.761156 3.261063
OS 3.7599142 3.2673059
OS 3.7563779 3.2725984
OS 3.7510854 3.2761347
OS 3.7448425 3.2773765
OE
OB 3.2308425 3.2513765 H
OS 3.2245996 3.2501347
OS 3.2193071 3.2465984
OS 3.2157708 3.2413059
OS 3.214529 3.235063
OS 3.2157708 3.2288201
OS 3.2193071 3.2235276
OS 3.2245996 3.2199913
OS 3.2308425 3.2187495
OS 3.2370854 3.2199913
OS 3.2423779 3.2235276
OS 3.2459142 3.2288201
OS 3.247156 3.235063
OS 3.2459142 3.2413059
OS 3.2423779 3.2465984
OS 3.2370854 3.2501347
OS 3.2308425 3.2513765
OE
OB 3.8068425 3.2513765 H
OS 3.8005996 3.2501347
OS 3.7953071 3.2465984
OS 3.7917708 3.2413059
OS 3.790529 3.235063
OS 3.7917708 3.2288201
OS 3.7953071 3.2235276
OS 3.7975621 3.2220209
OS 3.7965063 3.2167129
OS 3.7935996 3.2161347
OS 3.7883071 3.2125984
OS 3.7847708 3.2073059
OS 3.783529 3.201063
OS 3.7847708 3.1948201
OS 3.7883071 3.1895276
OS 3.7935996 3.1859913
OS 3.7998425 3.1847495
OS 3.8060854 3.1859913
OS 3.8113779 3.1895276
OS 3.8149142 3.1948201
OS 3.816156 3.201063
OS 3.8149142 3.2073059
OS 3.8113779 3.2125984
OS 3.8091229 3.2141051
OS 3.8101787 3.2194131
OS 3.8130854 3.2199913
OS 3.8183779 3.2235276
OS 3.8219142 3.2288201
OS 3.823156 3.235063
OS 3.8219142 3.2413059
OS 3.8183779 3.2465984
OS 3.8130854 3.2501347
OS 3.8068425 3.2513765
OE
OB 3.1889764 3.2033214 H
OS 3.1827335 3.2020796
OS 3.177441 3.1985433
OS 3.1739047 3.1932508
OS 3.1726629 3.1870079
OS 3.1739047 3.180765
OS 3.177441 3.1754725
OS 3.1827335 3.1719362
OS 3.1889764 3.1706944
OS 3.1952193 3.1719362
OS 3.2005118 3.1754725
OS 3.2040481 3.180765
OS 3.2052899 3.1870079
OS 3.2040481 3.1932508
OS 3.2005118 3.1985433
OS 3.1952193 3.2020796
OS 3.1889764 3.2033214
OE
OB 1.4598425 3.1633765 H
OS 1.4535996 3.1621347
OS 1.4483071 3.1585984
OS 1.4447708 3.1533059
OS 1.443529 3.147063
OS 1.4447708 3.1408201
OS 1.4483071 3.1355276
OS 1.4535996 3.1319913
OS 1.4598425 3.1307495
OS 1.4660854 3.1319913
OS 1.4713779 3.1355276
OS 1.4749142 3.1408201
OS 1.476156 3.147063
OS 1.4749142 3.1533059
OS 1.4713779 3.1585984
OS 1.4660854 3.1621347
OS 1.4598425 3.1633765
OE
OB 3.2755905 3.1580458 H
OS 3.2693476 3.156804
OS 3.2640551 3.1532677
OS 3.2605188 3.1479752
OS 3.259277 3.1417323
OS 3.2605188 3.1354894
OS 3.2640551 3.1301969
OS 3.2693476 3.1266606
OS 3.2755905 3.1254188
OS 3.2818334 3.1266606
OS 3.2871259 3.1301969
OS 3.2906622 3.1354894
OS 3.291904 3.1417323
OS 3.2906622 3.1479752
OS 3.2871259 3.1532677
OS 3.2818334 3.156804
OS 3.2755905 3.1580458
OE
OB 3.1830708 3.1521403 H
OS 3.1768279 3.1508985
OS 3.1715354 3.1473622
OS 3.1679991 3.1420697
OS 3.1667573 3.1358268
OS 3.1679991 3.1295839
OS 3.1715354 3.1242914
OS 3.1768279 3.1207551
OS 3.1830708 3.1195133
OS 3.1893137 3.1207551
OS 3.1946062 3.1242914
OS 3.1981425 3.1295839
OS 3.1993843 3.1358268
OS 3.1981425 3.1420697
OS 3.1946062 3.1473622
OS 3.1893137 3.1508985
OS 3.1830708 3.1521403
OE
OB 2.5592795 3.2303701 H
OS 2.4604055 3.2303701
OS 2.4604055 3.188166
OS 2.4561311 3.1873158
OS 2.4508386 3.1837795
OS 2.4473023 3.178487
OS 2.4460605 3.1722441
OS 2.4473023 3.1660012
OS 2.4508386 3.1607087
OS 2.4561311 3.1571724
OS 2.4599035 3.156422
OS 2.4604054 3.1516299
OS 2.4604055 3.1512242
OS 2.4604055 3.0915355
OS 2.5592795 3.0915355
OS 2.5592795 3.134327
OS 2.5956086 3.1706561
OS 2.5980854 3.1711488
OS 2.6033779 3.1746851
OS 2.6069142 3.1799776
OS 2.608156 3.1862205
OS 2.6069142 3.1924634
OS 2.6033779 3.1977559
OS 2.5980854 3.2012922
OS 2.5918425 3.202534
OS 2.5855996 3.2012922
OS 2.5803071 3.1977559
OS 2.5767708 3.1924634
OS 2.575529 3.1862205
OS 2.5757012 3.1853547
OS 2.5642795 3.173933
OS 2.5592795 3.1760041
OS 2.5592795 3.2303701
OE
OB 3.4918425 3.1193765 H
OS 3.4855996 3.1181347
OS 3.4803071 3.1145984
OS 3.4767708 3.1093059
OS 3.475529 3.103063
OS 3.4767708 3.0968201
OS 3.4803071 3.0915276
OS 3.4855996 3.0879913
OS 3.4918425 3.0867495
OS 3.4980854 3.0879913
OS 3.5033779 3.0915276
OS 3.5069142 3.0968201
OS 3.508156 3.103063
OS 3.5069142 3.1093059
OS 3.5033779 3.1145984
OS 3.4980854 3.1181347
OS 3.4918425 3.1193765
OE
OB 3.7178425 3.0883765 H
OS 3.7115996 3.0871347
OS 3.7063071 3.0835984
OS 3.7027708 3.0783059
OS 3.701529 3.072063
OS 3.7027708 3.0658201
OS 3.7063071 3.0605276
OS 3.7115996 3.0569913
OS 3.7178425 3.0557495
OS 3.7240854 3.0569913
OS 3.7293779 3.0605276
OS 3.7329142 3.0658201
OS 3.734156 3.072063
OS 3.7329142 3.0783059
OS 3.7293779 3.0835984
OS 3.7240854 3.0871347
OS 3.7178425 3.0883765
OE
OB 3.3688425 3.0663765 H
OS 3.3625996 3.0651347
OS 3.3573071 3.0615984
OS 3.3537708 3.0563059
OS 3.352529 3.050063
OS 3.3537708 3.0438201
OS 3.3573071 3.0385276
OS 3.3625996 3.0349913
OS 3.3688425 3.0337495
OS 3.3750854 3.0349913
OS 3.3803779 3.0385276
OS 3.3839142 3.0438201
OS 3.385156 3.050063
OS 3.3839142 3.0563059
OS 3.3803779 3.0615984
OS 3.3750854 3.0651347
OS 3.3688425 3.0663765
OE
OB 3.3448425 3.0123765 H
OS 3.3385996 3.0111347
OS 3.3333071 3.0075984
OS 3.3297708 3.0023059
OS 3.328529 2.996063
OS 3.3297708 2.9898201
OS 3.3333071 2.9845276
OS 3.3385996 2.9809913
OS 3.3448425 2.9797495
OS 3.3510854 2.9809913
OS 3.3563779 2.9845276
OS 3.3599142 2.9898201
OS 3.361156 2.996063
OS 3.3599142 3.0023059
OS 3.3563779 3.0075984
OS 3.3510854 3.0111347
OS 3.3448425 3.0123765
OE
OB 2.4738425 2.9963765 H
OS 2.4675996 2.9951347
OS 2.4648802 2.9933177
OS 2.4342756 2.9933177
OS 2.4292032 2.9923087
OS 2.4249031 2.9894355
OS 2.4163286 2.980861
OS 2.4159134 2.980861
OS 2.414633 2.9806063
OS 2.3676378 2.9806063
OS 2.3676378 2.9075197
OS 2.4289134 2.9075197
OS 2.4289134 2.9567117
OS 2.4311914 2.9582338
OS 2.4397659 2.9668083
OS 2.4648802 2.9668083
OS 2.4675996 2.9649913
OS 2.4738425 2.9637495
OS 2.4800854 2.9649913
OS 2.4853779 2.9685276
OS 2.4889142 2.9738201
OS 2.490156 2.980063
OS 2.4889142 2.9863059
OS 2.4853779 2.9915984
OS 2.4800854 2.9951347
OS 2.4738425 2.9963765
OE
OB 3.1978425 2.9863765 H
OS 3.1915996 2.9851347
OS 3.1863071 2.9815984
OS 3.1827708 2.9763059
OS 3.181529 2.970063
OS 3.1827708 2.9638201
OS 3.1863071 2.9585276
OS 3.1915996 2.9549913
OS 3.1978425 2.9537495
OS 3.2040854 2.9549913
OS 3.2093779 2.9585276
OS 3.2129142 2.9638201
OS 3.214156 2.970063
OS 3.2129142 2.9763059
OS 3.2093779 2.9815984
OS 3.2040854 2.9851347
OS 3.1978425 2.9863765
OE
OB 3.277559 2.9798962 H
OS 3.2713161 2.9786544
OS 3.2660236 2.9751181
OS 3.2624873 2.9698256
OS 3.2612455 2.9635827
OS 3.2624873 2.9573398
OS 3.2660236 2.9520473
OS 3.2713161 2.948511
OS 3.277559 2.9472692
OS 3.2838019 2.948511
OS 3.2890944 2.9520473
OS 3.2926307 2.9573398
OS 3.2938725 2.9635827
OS 3.2926307 2.9698256
OS 3.2890944 2.9751181
OS 3.2838019 2.9786544
OS 3.277559 2.9798962
OE
OB 3.3708425 2.9043765 H
OS 3.3645996 2.9031347
OS 3.3593071 2.8995984
OS 3.3557708 2.8943059
OS 3.354529 2.888063
OS 3.3557708 2.8818201
OS 3.3593071 2.8765276
OS 3.3645996 2.8729913
OS 3.3708425 2.8717495
OS 3.3770854 2.8729913
OS 3.3823779 2.8765276
OS 3.3859142 2.8818201
OS 3.387156 2.888063
OS 3.3859142 2.8943059
OS 3.3823779 2.8995984
OS 3.3770854 2.9031347
OS 3.3708425 2.9043765
OE
OB 2.6929134 2.7377702 H
OS 2.6866705 2.7365284
OS 2.681378 2.7329921
OS 2.6778417 2.7276996
OS 2.6765999 2.7214567
OS 2.6778417 2.7152138
OS 2.681378 2.7099213
OS 2.6866705 2.706385
OS 2.6929134 2.7051432
OS 2.6991563 2.706385
OS 2.7044488 2.7099213
OS 2.7079851 2.7152138
OS 2.7092269 2.7214567
OS 2.7079851 2.7276996
OS 2.7044488 2.7329921
OS 2.6991563 2.7365284
OS 2.6929134 2.7377702
OE
OB 2.394685 2.7367859 H
OS 2.3884421 2.7355441
OS 2.3831496 2.7320078
OS 2.3796133 2.7267153
OS 2.3783715 2.7204724
OS 2.3796133 2.7142295
OS 2.3831496 2.708937
OS 2.3884421 2.7054007
OS 2.394685 2.7041589
OS 2.4009279 2.7054007
OS 2.4062204 2.708937
OS 2.4097567 2.7142295
OS 2.4109985 2.7204724
OS 2.4097567 2.7267153
OS 2.4062204 2.7320078
OS 2.4009279 2.7355441
OS 2.394685 2.7367859
OE
OB 2.4948425 2.7123765 H
OS 2.4885996 2.7111347
OS 2.4833071 2.7075984
OS 2.4797708 2.7023059
OS 2.478529 2.696063
OS 2.4797708 2.6898201
OS 2.4833071 2.6845276
OS 2.4883212 2.6811773
OS 2.4885995 2.6790399
OS 2.4885995 2.6780861
OS 2.4883212 2.6759487
OS 2.4833071 2.6725984
OS 2.4797708 2.6673059
OS 2.478529 2.661063
OS 2.4797708 2.6548201
OS 2.4833071 2.6495276
OS 2.4885996 2.6459913
OS 2.4948425 2.6447495
OS 2.5010854 2.6459913
OS 2.5063779 2.6495276
OS 2.5099142 2.6548201
OS 2.511156 2.661063
OS 2.5099142 2.6673059
OS 2.5063779 2.6725984
OS 2.5013638 2.6759487
OS 2.5010855 2.6780861
OS 2.5010855 2.6790399
OS 2.5013638 2.6811773
OS 2.5063779 2.6845276
OS 2.5099142 2.6898201
OS 2.511156 2.696063
OS 2.5099142 2.7023059
OS 2.5063779 2.7075984
OS 2.5010854 2.7111347
OS 2.4948425 2.7123765
OE
OB 2.9588425 2.6373765 H
OS 2.9525996 2.6361347
OS 2.9473071 2.6325984
OS 2.9437708 2.6273059
OS 2.942529 2.621063
OS 2.9437708 2.6148201
OS 2.9473071 2.6095276
OS 2.9525996 2.6059913
OS 2.9588425 2.6047495
OS 2.9650854 2.6059913
OS 2.9703779 2.6095276
OS 2.9739142 2.6148201
OS 2.975156 2.621063
OS 2.9739142 2.6273059
OS 2.9703779 2.6325984
OS 2.9650854 2.6361347
OS 2.9588425 2.6373765
OE
OB 2.4291925 2.6373765 H
OS 2.4229496 2.6361347
OS 2.4176571 2.6325984
OS 2.4141208 2.6273059
OS 2.412879 2.621063
OS 2.4141208 2.6148201
OS 2.4176571 2.6095276
OS 2.4229496 2.6059913
OS 2.4291925 2.6047495
OS 2.4354354 2.6059913
OS 2.4407279 2.6095276
OS 2.4442642 2.6148201
OS 2.445506 2.621063
OS 2.4442642 2.6273059
OS 2.4407279 2.6325984
OS 2.4354354 2.6361347
OS 2.4291925 2.6373765
OE
OB 2.2523425 2.6298765 H
OS 2.2460996 2.6286347
OS 2.2408071 2.6250984
OS 2.2372708 2.6198059
OS 2.236029 2.613563
OS 2.2372708 2.6073201
OS 2.239748 2.6036127
OS 2.2364566 2.5995388
OS 2.2317425 2.6004765
OS 2.2254996 2.5992347
OS 2.2202071 2.5956984
OS 2.2166708 2.5904059
OS 2.215429 2.584163
OS 2.2166708 2.5779201
OS 2.2202071 2.5726276
OS 2.2254996 2.5690913
OS 2.2317425 2.5678495
OS 2.2379854 2.5690913
OS 2.2432779 2.5726276
OS 2.2468142 2.5779201
OS 2.248056 2.584163
OS 2.2468142 2.5904059
OS 2.244337 2.5941133
OS 2.2476284 2.5981872
OS 2.2523425 2.5972495
OS 2.2585854 2.5984913
OS 2.2638779 2.6020276
OS 2.2674142 2.6073201
OS 2.268656 2.613563
OS 2.2674142 2.6198059
OS 2.2638779 2.6250984
OS 2.2585854 2.6286347
OS 2.2523425 2.6298765
OE
OB 2.8218425 2.6173765 H
OS 2.8155996 2.6161347
OS 2.8103071 2.6125984
OS 2.8067708 2.6073059
OS 2.805529 2.601063
OS 2.8067708 2.5948201
OS 2.8103071 2.5895276
OS 2.8155996 2.5859913
OS 2.8218425 2.5847495
OS 2.8280854 2.5859913
OS 2.8333779 2.5895276
OS 2.8369142 2.5948201
OS 2.838156 2.601063
OS 2.8369142 2.6073059
OS 2.8333779 2.6125984
OS 2.8280854 2.6161347
OS 2.8218425 2.6173765
OE
OB 3.6238425 2.6033765 H
OS 3.6175996 2.6021347
OS 3.6123071 2.5985984
OS 3.6087708 2.5933059
OS 3.607529 2.587063
OS 3.6087708 2.5808201
OS 3.6123071 2.5755276
OS 3.6175996 2.5719913
OS 3.6238425 2.5707495
OS 3.6300854 2.5719913
OS 3.6353779 2.5755276
OS 3.6389142 2.5808201
OS 3.640156 2.587063
OS 3.6389142 2.5933059
OS 3.6353779 2.5985984
OS 3.6300854 2.6021347
OS 3.6238425 2.6033765
OE
OB 2.3215354 2.6023765 H
OS 2.3152925 2.6011347
OS 2.31 2.5975984
OS 2.3064637 2.5923059
OS 2.3052219 2.586063
OS 2.3064637 2.5798201
OS 2.31 2.5745276
OS 2.3152925 2.5709913
OS 2.3215354 2.5697495
OS 2.3277783 2.5709913
OS 2.3330708 2.5745276
OS 2.3366071 2.5798201
OS 2.3378489 2.586063
OS 2.3366071 2.5923059
OS 2.3330708 2.5975984
OS 2.3277783 2.6011347
OS 2.3215354 2.6023765
OE
OB 2.4098425 2.5953765 H
OS 2.4035996 2.5941347
OS 2.3983071 2.5905984
OS 2.3947708 2.5853059
OS 2.393529 2.579063
OS 2.3947708 2.5728201
OS 2.3983071 2.5675276
OS 2.4035996 2.5639913
OS 2.4098425 2.5627495
OS 2.4160854 2.5639913
OS 2.4213779 2.5675276
OS 2.4249142 2.5728201
OS 2.426156 2.579063
OS 2.4249142 2.5853059
OS 2.4213779 2.5905984
OS 2.4160854 2.5941347
OS 2.4098425 2.5953765
OE
OB 2.5868425 2.5853765 H
OS 2.5805996 2.5841347
OS 2.5753071 2.5805984
OS 2.5717708 2.5753059
OS 2.570529 2.569063
OS 2.5717708 2.5628201
OS 2.5753071 2.5575276
OS 2.5805996 2.5539913
OS 2.5868425 2.5527495
OS 2.5930854 2.5539913
OS 2.5983779 2.5575276
OS 2.6019142 2.5628201
OS 2.603156 2.569063
OS 2.6019142 2.5753059
OS 2.5983779 2.5805984
OS 2.5930854 2.5841347
OS 2.5868425 2.5853765
OE
OB 2.7838425 2.5843765 H
OS 2.7775996 2.5831347
OS 2.7723071 2.5795984
OS 2.7687708 2.5743059
OS 2.767529 2.568063
OS 2.7687708 2.5618201
OS 2.7723071 2.5565276
OS 2.7775996 2.5529913
OS 2.7838425 2.5517495
OS 2.7900854 2.5529913
OS 2.7953779 2.5565276
OS 2.7989142 2.5618201
OS 2.800156 2.568063
OS 2.7989142 2.5743059
OS 2.7953779 2.5795984
OS 2.7900854 2.5831347
OS 2.7838425 2.5843765
OE
OB 2.6858425 2.5843765 H
OS 2.6795996 2.5831347
OS 2.6743071 2.5795984
OS 2.6707708 2.5743059
OS 2.669529 2.568063
OS 2.6707708 2.5618201
OS 2.6743071 2.5565276
OS 2.6795996 2.5529913
OS 2.6858425 2.5517495
OS 2.6920854 2.5529913
OS 2.6973779 2.5565276
OS 2.7009142 2.5618201
OS 2.702156 2.568063
OS 2.7009142 2.5743059
OS 2.6973779 2.5795984
OS 2.6920854 2.5831347
OS 2.6858425 2.5843765
OE
OB 2.8818425 2.5823765 H
OS 2.8755996 2.5811347
OS 2.8703071 2.5775984
OS 2.8667708 2.5723059
OS 2.865529 2.566063
OS 2.8667708 2.5598201
OS 2.8703071 2.5545276
OS 2.8755996 2.5509913
OS 2.8818425 2.5497495
OS 2.8880854 2.5509913
OS 2.8933779 2.5545276
OS 2.8969142 2.5598201
OS 2.898156 2.566063
OS 2.8969142 2.5723059
OS 2.8933779 2.5775984
OS 2.8880854 2.5811347
OS 2.8818425 2.5823765
OE
OB 2.6248425 2.4773765 H
OS 2.6185996 2.4761347
OS 2.6133071 2.4725984
OS 2.6097708 2.4673059
OS 2.608529 2.461063
OS 2.6097708 2.4548201
OS 2.6099331 2.4545773
OS 2.6063282 2.4509724
OS 2.6060854 2.4511347
OS 2.5998425 2.4523765
OS 2.5935996 2.4511347
OS 2.5883071 2.4475984
OS 2.5847708 2.4423059
OS 2.583529 2.436063
OS 2.5844621 2.4313719
OS 2.583986 2.4305231
OS 2.5813824 2.4279195
OS 2.5805336 2.4274434
OS 2.5758425 2.4283765
OS 2.5695996 2.4271347
OS 2.5643071 2.4235984
OS 2.5607708 2.4183059
OS 2.559529 2.412063
OS 2.5607708 2.4058201
OS 2.5643071 2.4005276
OS 2.5695996 2.3969913
OS 2.5758425 2.3957495
OS 2.5820854 2.3969913
OS 2.5873779 2.4005276
OS 2.5909142 2.4058201
OS 2.592156 2.412063
OS 2.5912229 2.4167541
OS 2.591699 2.4176029
OS 2.5943026 2.4202065
OS 2.5951514 2.4206826
OS 2.5998425 2.4197495
OS 2.6060854 2.4209913
OS 2.6113779 2.4245276
OS 2.6149142 2.4298201
OS 2.616156 2.436063
OS 2.6149142 2.4423059
OS 2.6147519 2.4425487
OS 2.6183568 2.4461536
OS 2.6185996 2.4459913
OS 2.6248425 2.4447495
OS 2.6310854 2.4459913
OS 2.6363779 2.4495276
OS 2.6399142 2.4548201
OS 2.641156 2.461063
OS 2.6399142 2.4673059
OS 2.6363779 2.4725984
OS 2.6310854 2.4761347
OS 2.6248425 2.4773765
OE
OB 2.2720325 2.4801865 H
OS 2.2657896 2.4789447
OS 2.2604971 2.4754084
OS 2.2569608 2.4701159
OS 2.255719 2.463873
OS 2.2569608 2.4576301
OS 2.2604971 2.4523376
OS 2.2657896 2.4488013
OS 2.2720325 2.4475595
OS 2.2782754 2.4488013
OS 2.2835679 2.4523376
OS 2.2871042 2.4576301
OS 2.288346 2.463873
OS 2.2871042 2.4701159
OS 2.2835679 2.4754084
OS 2.2782754 2.4789447
OS 2.2720325 2.4801865
OE
OB 2.5258425 2.4793765 H
OS 2.5195996 2.4781347
OS 2.5143071 2.4745984
OS 2.5107708 2.4693059
OS 2.509529 2.463063
OS 2.5107708 2.4568201
OS 2.5143071 2.4515276
OS 2.5195996 2.4479913
OS 2.5258425 2.4467495
OS 2.5320854 2.4479913
OS 2.5373779 2.4515276
OS 2.5409142 2.4568201
OS 2.542156 2.463063
OS 2.5409142 2.4693059
OS 2.5373779 2.4745984
OS 2.5320854 2.4781347
OS 2.5258425 2.4793765
OE
OB 2.9488425 2.4723765 H
OS 2.9425996 2.4711347
OS 2.9373071 2.4675984
OS 2.9337708 2.4623059
OS 2.932529 2.456063
OS 2.9337708 2.4498201
OS 2.9373071 2.4445276
OS 2.9425996 2.4409913
OS 2.9488425 2.4397495
OS 2.9550854 2.4409913
OS 2.9603779 2.4445276
OS 2.9639142 2.4498201
OS 2.965156 2.456063
OS 2.9639142 2.4623059
OS 2.9603779 2.4675984
OS 2.9550854 2.4711347
OS 2.9488425 2.4723765
OE
OB 2.4758425 2.4723765 H
OS 2.4695996 2.4711347
OS 2.4643071 2.4675984
OS 2.4607708 2.4623059
OS 2.459529 2.456063
OS 2.4607708 2.4498201
OS 2.4643071 2.4445276
OS 2.4695996 2.4409913
OS 2.4758425 2.4397495
OS 2.4820854 2.4409913
OS 2.4873779 2.4445276
OS 2.4909142 2.4498201
OS 2.492156 2.456063
OS 2.4909142 2.4623059
OS 2.4873779 2.4675984
OS 2.4820854 2.4711347
OS 2.4758425 2.4723765
OE
OB 2.9905325 2.4577319 H
OS 2.9831854 2.4562705
OS 2.9769568 2.4521087
OS 2.972795 2.4458801
OS 2.9713336 2.438533
OS 2.972795 2.4311859
OS 2.9769568 2.4249573
OS 2.9831854 2.4207955
OS 2.9905325 2.4193341
OS 2.9978796 2.4207955
OS 3.0041082 2.4249573
OS 3.00827 2.4311859
OS 3.0097314 2.438533
OS 3.00827 2.4458801
OS 3.0041082 2.4521087
OS 2.9978796 2.4562705
OS 2.9905325 2.4577319
OE
OB 2.2031325 2.4577319 H
OS 2.1957854 2.4562705
OS 2.1895568 2.4521087
OS 2.185395 2.4458801
OS 2.1839336 2.438533
OS 2.185395 2.4311859
OS 2.1895568 2.4249573
OS 2.1957854 2.4207955
OS 2.2031325 2.4193341
OS 2.2104796 2.4207955
OS 2.2167082 2.4249573
OS 2.22087 2.4311859
OS 2.2223314 2.438533
OS 2.22087 2.4458801
OS 2.2167082 2.4521087
OS 2.2104796 2.4562705
OS 2.2031325 2.4577319
OE
OB 3.6179425 2.5536725 H
OS 3.6047974 2.5523778
OS 3.5921575 2.5485435
OS 3.5805085 2.542317
OS 3.570298 2.5339375
OS 3.5619185 2.523727
OS 3.555692 2.512078
OS 3.5518577 2.4994381
OS 3.550563 2.486293
OS 3.5518577 2.4731479
OS 3.555692 2.460508
OS 3.5619185 2.448859
OS 3.570298 2.4386485
OS 3.5805085 2.430269
OS 3.5921575 2.4240425
OS 3.6047974 2.4202082
OS 3.6179425 2.4189135
OS 3.6310876 2.4202082
OS 3.6437275 2.4240425
OS 3.6553765 2.430269
OS 3.665587 2.4386485
OS 3.6739665 2.448859
OS 3.680193 2.460508
OS 3.6840273 2.4731479
OS 3.685322 2.486293
OS 3.6840273 2.4994381
OS 3.680193 2.512078
OS 3.6739665 2.523727
OS 3.665587 2.5339375
OS 3.6553765 2.542317
OS 3.6437275 2.5485435
OS 3.6310876 2.5523778
OS 3.6179425 2.5536725
OE
OB 2.7838425 2.4453765 H
OS 2.7775996 2.4441347
OS 2.7723071 2.4405984
OS 2.7687708 2.4353059
OS 2.767529 2.429063
OS 2.7687708 2.4228201
OS 2.7723071 2.4175276
OS 2.7775996 2.4139913
OS 2.7838425 2.4127495
OS 2.7900854 2.4139913
OS 2.7953779 2.4175276
OS 2.7989142 2.4228201
OS 2.800156 2.429063
OS 2.7989142 2.4353059
OS 2.7953779 2.4405984
OS 2.7900854 2.4441347
OS 2.7838425 2.4453765
OE
OB 2.8948425 2.4473765 H
OS 2.8885996 2.4461347
OS 2.8833071 2.4425984
OS 2.8797708 2.4373059
OS 2.878529 2.431063
OS 2.8797708 2.4248201
OS 2.8833071 2.4195276
OS 2.8885996 2.4159913
OS 2.8948425 2.4147495
OS 2.9010854 2.4159913
OS 2.9028598 2.4171769
OS 2.9093072 2.4165275
OS 2.9145996 2.4129913
OS 2.9208425 2.4117495
OS 2.9270854 2.4129913
OS 2.9323779 2.4165276
OS 2.9359142 2.4218201
OS 2.937156 2.428063
OS 2.9359142 2.4343059
OS 2.9323779 2.4395984
OS 2.9270854 2.4431347
OS 2.9208425 2.4443765
OS 2.9145996 2.4431347
OS 2.9093072 2.4395984
OS 2.9083824 2.4395984
OS 2.9063779 2.4425984
OS 2.9010854 2.4461347
OS 2.8948425 2.4473765
OE
OB 2.4888425 2.4293765 H
OS 2.4825996 2.4281347
OS 2.4773071 2.4245984
OS 2.4737708 2.4193059
OS 2.472529 2.413063
OS 2.4737708 2.4068201
OS 2.4773071 2.4015276
OS 2.4825996 2.3979913
OS 2.4888425 2.3967495
OS 2.4950854 2.3979913
OS 2.5003779 2.4015276
OS 2.5039142 2.4068201
OS 2.505156 2.413063
OS 2.5039142 2.4193059
OS 2.5003779 2.4245984
OS 2.4950854 2.4281347
OS 2.4888425 2.4293765
OE
OB 2.4048425 2.4283765 H
OS 2.3985996 2.4271347
OS 2.3933071 2.4235984
OS 2.3897708 2.4183059
OS 2.388529 2.412063
OS 2.3897708 2.4058201
OS 2.3933071 2.4005276
OS 2.3985996 2.3969913
OS 2.4048425 2.3957495
OS 2.4110854 2.3969913
OS 2.4163779 2.4005276
OS 2.4199142 2.4058201
OS 2.421156 2.412063
OS 2.4199142 2.4183059
OS 2.4163779 2.4235984
OS 2.4110854 2.4271347
OS 2.4048425 2.4283765
OE
OB 3.4988425 2.3573765 H
OS 3.4925996 2.3561347
OS 3.4873071 2.3525984
OS 3.4837708 2.3473059
OS 3.482529 2.341063
OS 3.4837708 2.3348201
OS 3.4873071 2.3295276
OS 3.4925996 2.3259913
OS 3.4988425 2.3247495
OS 3.5050854 2.3259913
OS 3.5103779 2.3295276
OS 3.5139142 2.3348201
OS 3.515156 2.341063
OS 3.5139142 2.3473059
OS 3.5103779 2.3525984
OS 3.5050854 2.3561347
OS 3.4988425 2.3573765
OE
OB 2.4758425 2.3073765 H
OS 2.4695996 2.3061347
OS 2.4643071 2.3025984
OS 2.4607708 2.297306
OS 2.4556938 2.2974115
OS 2.4508425 2.2983765
OS 2.4445996 2.2971347
OS 2.4393071 2.2935984
OS 2.4357708 2.2883059
OS 2.434529 2.282063
OS 2.4357708 2.2758201
OS 2.4393071 2.2705276
OS 2.4445996 2.2669913
OS 2.4508425 2.2657495
OS 2.4570854 2.2669913
OS 2.4623779 2.2705276
OS 2.4659142 2.27582
OS 2.4709912 2.2757145
OS 2.4758425 2.2747495
OS 2.4820854 2.2759913
OS 2.4873779 2.2795276
OS 2.4909142 2.2848201
OS 2.492156 2.291063
OS 2.4909142 2.2973059
OS 2.4873779 2.3025984
OS 2.4820854 2.3061347
OS 2.4758425 2.3073765
OE
OB 2.8038425 2.3233765 H
OS 2.7975996 2.3221347
OS 2.7923071 2.3185984
OS 2.7887708 2.3133059
OS 2.787529 2.307063
OS 2.7887708 2.3008201
OS 2.7923071 2.2955276
OS 2.7975996 2.2919913
OS 2.8038425 2.2907495
OS 2.8100854 2.2919913
OS 2.8153779 2.2955276
OS 2.8189142 2.3008201
OS 2.820156 2.307063
OS 2.8189142 2.3133059
OS 2.8153779 2.3185984
OS 2.8100854 2.3221347
OS 2.8038425 2.3233765
OE
OB 2.6858425 2.3273765 H
OS 2.6795996 2.3261347
OS 2.6743071 2.3225984
OS 2.6707708 2.3173059
OS 2.6696588 2.3117154
OS 2.6687231 2.3100312
OS 2.6668743 2.3081824
OS 2.6651901 2.3072467
OS 2.6595996 2.3061347
OS 2.6543071 2.3025984
OS 2.6507708 2.2973059
OS 2.649529 2.2910631
OS 2.6483447 2.2898788
OS 2.6458425 2.2903765
OS 2.6395996 2.2891347
OS 2.6343071 2.2855984
OS 2.6307708 2.2803059
OS 2.629529 2.274063
OS 2.6307708 2.2678201
OS 2.6343071 2.2625276
OS 2.6395996 2.2589913
OS 2.6458425 2.2577495
OS 2.6520854 2.2589913
OS 2.6573779 2.2625276
OS 2.6609142 2.2678201
OS 2.662156 2.2740629
OS 2.6633403 2.2752472
OS 2.6658425 2.2747495
OS 2.6720854 2.2759913
OS 2.6773779 2.2795276
OS 2.6809142 2.2848201
OS 2.6817886 2.2892161
OS 2.686529 2.2890629
OS 2.6877708 2.2828201
OS 2.6913071 2.2775276
OS 2.6965996 2.2739913
OS 2.7028425 2.2727495
OS 2.7090854 2.2739913
OS 2.7143779 2.2775276
OS 2.7165125 2.2807222
OS 2.7205996 2.2779913
OS 2.7268425 2.2767495
OS 2.7330854 2.2779913
OS 2.7383779 2.2815276
OS 2.7419142 2.2868201
OS 2.743156 2.293063
OS 2.7419142 2.2993059
OS 2.7383779 2.3045984
OS 2.7330854 2.3081347
OS 2.7268425 2.3093765
OS 2.7205996 2.3081347
OS 2.7153071 2.3045984
OS 2.7131725 2.3014038
OS 2.7090854 2.3041347
OS 2.705998 2.3047488
OS 2.7019255 2.309904
OS 2.702156 2.311063
OS 2.7009142 2.3173059
OS 2.6973779 2.3225984
OS 2.6920854 2.3261347
OS 2.6858425 2.3273765
OE
OB 2.8718425 2.3133765 H
OS 2.8655996 2.3121347
OS 2.8603071 2.3085984
OS 2.8567708 2.3033059
OS 2.855529 2.297063
OS 2.8567708 2.2908201
OS 2.8603071 2.2855276
OS 2.8655996 2.2819913
OS 2.8718425 2.2807495
OS 2.8780854 2.2819913
OS 2.8833779 2.2855276
OS 2.8869142 2.2908201
OS 2.888156 2.297063
OS 2.8869142 2.3033059
OS 2.8833779 2.3085984
OS 2.8780854 2.3121347
OS 2.8718425 2.3133765
OE
OB 2.9858425 2.3033765 H
OS 2.9795996 2.3021347
OS 2.9743071 2.2985984
OS 2.9707708 2.2933059
OS 2.969529 2.287063
OS 2.9707708 2.2808201
OS 2.9743071 2.2755276
OS 2.9795996 2.2719913
OS 2.9858425 2.2707495
OS 2.9920854 2.2719913
OS 2.9973779 2.2755276
OS 3.0009142 2.2808201
OS 3.002156 2.287063
OS 3.0009142 2.2933059
OS 2.9973779 2.2985984
OS 2.9920854 2.3021347
OS 2.9858425 2.3033765
OE
OB 2.9428425 2.3023765 H
OS 2.9365996 2.3011347
OS 2.9313071 2.2975984
OS 2.9277708 2.2923059
OS 2.926529 2.286063
OS 2.9277708 2.2798201
OS 2.9313071 2.2745276
OS 2.9365996 2.2709913
OS 2.9428425 2.2697495
OS 2.9490854 2.2709913
OS 2.9543779 2.2745276
OS 2.9579142 2.2798201
OS 2.959156 2.286063
OS 2.9579142 2.2923059
OS 2.9543779 2.2975984
OS 2.9490854 2.3011347
OS 2.9428425 2.3023765
OE
OB 2.4098425 2.3303765 H
OS 2.4035996 2.3291347
OS 2.3983071 2.3255984
OS 2.3947708 2.3203059
OS 2.393529 2.314063
OS 2.3947708 2.3078201
OS 2.3983071 2.3025276
OS 2.3997406 2.3015697
OS 2.3997406 2.2955563
OS 2.3983071 2.2945984
OS 2.3947708 2.2893059
OS 2.393529 2.283063
OS 2.3947708 2.2768201
OS 2.3983071 2.2715276
OS 2.4035996 2.2679913
OS 2.4098425 2.2667495
OS 2.4160854 2.2679913
OS 2.4213779 2.2715276
OS 2.4249142 2.2768201
OS 2.426156 2.283063
OS 2.4249142 2.2893059
OS 2.4213779 2.2945984
OS 2.4199444 2.2955563
OS 2.4199444 2.3015697
OS 2.4213779 2.3025276
OS 2.4249142 2.3078201
OS 2.426156 2.314063
OS 2.4249142 2.3203059
OS 2.4213779 2.3255984
OS 2.4160854 2.3291347
OS 2.4098425 2.3303765
OE
OB 2.5818425 2.3243765 H
OS 2.5755996 2.3231347
OS 2.5703071 2.3195984
OS 2.5667708 2.3143059
OS 2.565529 2.308063
OS 2.5667708 2.3018201
OS 2.568727 2.2988924
OS 2.5683071 2.2925983
OS 2.5647708 2.2873059
OS 2.563529 2.281063
OS 2.5647708 2.2748201
OS 2.5683071 2.2695276
OS 2.5735996 2.2659913
OS 2.5798425 2.2647495
OS 2.5860854 2.2659913
OS 2.5913779 2.2695276
OS 2.5949142 2.2748201
OS 2.596156 2.281063
OS 2.5949142 2.2873059
OS 2.592958 2.2902336
OS 2.5933779 2.2965277
OS 2.5969142 2.3018201
OS 2.598156 2.308063
OS 2.5969142 2.3143059
OS 2.5933779 2.3195984
OS 2.5880854 2.3231347
OS 2.5818425 2.3243765
OE
OB 2.2538425 2.2953765 H
OS 2.2475996 2.2941347
OS 2.2423071 2.2905984
OS 2.2387708 2.2853059
OS 2.237529 2.279063
OS 2.2387708 2.2728201
OS 2.2423071 2.2675276
OS 2.2475996 2.2639913
OS 2.2538425 2.2627495
OS 2.2600854 2.2639913
OS 2.2653779 2.2675276
OS 2.2689142 2.2728201
OS 2.270156 2.279063
OS 2.2689142 2.2853059
OS 2.2653779 2.2905984
OS 2.2600854 2.2941347
OS 2.2538425 2.2953765
OE
OB 3.3428425 2.2793765 H
OS 3.3365996 2.2781347
OS 3.3313071 2.2745984
OS 3.3277708 2.2693059
OS 3.326529 2.263063
OS 3.3277708 2.2568201
OS 3.3313071 2.2515276
OS 3.3365996 2.2479913
OS 3.3428425 2.2467495
OS 3.3490854 2.2479913
OS 3.3543779 2.2515276
OS 3.3579142 2.2568201
OS 3.359156 2.263063
OS 3.3579142 2.2693059
OS 3.3543779 2.2745984
OS 3.3490854 2.2781347
OS 3.3428425 2.2793765
OE
OB 2.8418425 2.2793765 H
OS 2.8355996 2.2781347
OS 2.8303071 2.2745984
OS 2.8267708 2.2693059
OS 2.825529 2.263063
OS 2.8267708 2.2568201
OS 2.8303071 2.2515276
OS 2.8355996 2.2479913
OS 2.8418425 2.2467495
OS 2.8480854 2.2479913
OS 2.8533779 2.2515276
OS 2.8569142 2.2568201
OS 2.858156 2.263063
OS 2.8569142 2.2693059
OS 2.8533779 2.2745984
OS 2.8480854 2.2781347
OS 2.8418425 2.2793765
OE
OB 2.4998425 2.2523765 H
OS 2.4935996 2.2511347
OS 2.4883071 2.2475984
OS 2.4847708 2.2423059
OS 2.483529 2.236063
OS 2.4847708 2.2298201
OS 2.4883071 2.2245276
OS 2.4935996 2.2209913
OS 2.4998425 2.2197495
OS 2.5060854 2.2209913
OS 2.5113779 2.2245276
OS 2.5149142 2.2298201
OS 2.516156 2.236063
OS 2.5149142 2.2423059
OS 2.5113779 2.2475984
OS 2.5060854 2.2511347
OS 2.4998425 2.2523765
OE
OB 2.3308425 2.2313765 H
OS 2.3245996 2.2301347
OS 2.3193071 2.2265984
OS 2.3157708 2.2213059
OS 2.314529 2.215063
OS 2.3157708 2.2088201
OS 2.3193071 2.2035276
OS 2.3245996 2.1999913
OS 2.3308425 2.1987495
OS 2.3370854 2.1999913
OS 2.3423779 2.2035276
OS 2.3459142 2.2088201
OS 2.347156 2.215063
OS 2.3459142 2.2213059
OS 2.3423779 2.2265984
OS 2.3370854 2.2301347
OS 2.3308425 2.2313765
OE
OB 3.5717425 2.1163919 H
OS 3.5643954 2.1149305
OS 3.5581668 2.1107687
OS 3.554005 2.1045401
OS 3.5525436 2.097193
OS 3.554005 2.0898459
OS 3.5581668 2.0836173
OS 3.5643954 2.0794555
OS 3.5717425 2.0779941
OS 3.5790896 2.0794555
OS 3.5853182 2.0836173
OS 3.58948 2.0898459
OS 3.5909414 2.097193
OS 3.58948 2.1045401
OS 3.5853182 2.1107687
OS 3.5790896 2.1149305
OS 3.5717425 2.1163919
OE
OB 3.7198425 2.0123765 H
OS 3.7135996 2.0111347
OS 3.7083071 2.0075984
OS 3.7047708 2.0023059
OS 3.703529 1.996063
OS 3.7047708 1.9898201
OS 3.7083071 1.9845276
OS 3.7135996 1.9809913
OS 3.7198425 1.9797495
OS 3.7260854 1.9809913
OS 3.7313779 1.9845276
OS 3.7349142 1.9898201
OS 3.736156 1.996063
OS 3.7349142 2.0023059
OS 3.7313779 2.0075984
OS 3.7260854 2.0111347
OS 3.7198425 2.0123765
OE
OB 3.5548425 2.0073765 H
OS 3.5485996 2.0061347
OS 3.5433071 2.0025984
OS 3.5397708 1.9973059
OS 3.538529 1.991063
OS 3.5397708 1.9848201
OS 3.5433071 1.9795276
OS 3.5485996 1.9759913
OS 3.5548425 1.9747495
OS 3.5610854 1.9759913
OS 3.5663779 1.9795276
OS 3.5699142 1.9848201
OS 3.571156 1.991063
OS 3.5699142 1.9973059
OS 3.5663779 2.0025984
OS 3.5610854 2.0061347
OS 3.5548425 2.0073765
OE
OB 3.2988425 1.9873765 H
OS 3.2925996 1.9861347
OS 3.2873071 1.9825984
OS 3.2837708 1.9773059
OS 3.282529 1.971063
OS 3.2837708 1.9648201
OS 3.2873071 1.9595276
OS 3.2925996 1.9559913
OS 3.2988425 1.9547495
OS 3.3050854 1.9559913
OS 3.3103779 1.9595276
OS 3.3139142 1.9648201
OS 3.315156 1.971063
OS 3.3139142 1.9773059
OS 3.3103779 1.9825984
OS 3.3050854 1.9861347
OS 3.2988425 1.9873765
OE
OB 3.5548425 1.9573765 H
OS 3.5485996 1.9561347
OS 3.5433071 1.9525984
OS 3.5397708 1.9473059
OS 3.538529 1.941063
OS 3.5397708 1.9348201
OS 3.5433071 1.9295276
OS 3.5485996 1.9259913
OS 3.5548425 1.9247495
OS 3.5610854 1.9259913
OS 3.5663779 1.9295276
OS 3.5699142 1.9348201
OS 3.571156 1.941063
OS 3.5699142 1.9473059
OS 3.5663779 1.9525984
OS 3.5610854 1.9561347
OS 3.5548425 1.9573765
OE
OB 3.7198425 1.9373765 H
OS 3.7135996 1.9361347
OS 3.7083071 1.9325984
OS 3.7047708 1.9273059
OS 3.703529 1.921063
OS 3.7047708 1.9148201
OS 3.7083071 1.9095276
OS 3.7135996 1.9059913
OS 3.7198425 1.9047495
OS 3.7260854 1.9059913
OS 3.7313779 1.9095276
OS 3.7349142 1.9148201
OS 3.736156 1.921063
OS 3.7349142 1.9273059
OS 3.7313779 1.9325984
OS 3.7260854 1.9361347
OS 3.7198425 1.9373765
OE
OB 3.5548425 1.9073765 H
OS 3.5485996 1.9061347
OS 3.5433071 1.9025984
OS 3.5397708 1.8973059
OS 3.538529 1.891063
OS 3.5397708 1.8848201
OS 3.5433071 1.8795276
OS 3.5485996 1.8759913
OS 3.5548425 1.8747495
OS 3.5610854 1.8759913
OS 3.5663779 1.8795276
OS 3.5699142 1.8848201
OS 3.571156 1.891063
OS 3.5699142 1.8973059
OS 3.5663779 1.9025984
OS 3.5610854 1.9061347
OS 3.5548425 1.9073765
OE
OB 3.3928425 1.8873765 H
OS 3.3865996 1.8861347
OS 3.3813071 1.8825984
OS 3.3777708 1.8773059
OS 3.376529 1.871063
OS 3.3777708 1.8648201
OS 3.3813071 1.8595276
OS 3.3865996 1.8559913
OS 3.3928425 1.8547495
OS 3.3990854 1.8559913
OS 3.4043779 1.8595276
OS 3.4079142 1.8648201
OS 3.409156 1.871063
OS 3.4079142 1.8773059
OS 3.4043779 1.8825984
OS 3.3990854 1.8861347
OS 3.3928425 1.8873765
OE
OB 3.4392507 1.8872515 H
OS 3.4330078 1.8860097
OS 3.4277153 1.8824734
OS 3.424179 1.8771809
OS 3.4229372 1.870938
OS 3.424179 1.8646951
OS 3.4277153 1.8594026
OS 3.4330078 1.8558663
OS 3.4392507 1.8546245
OS 3.4454936 1.8558663
OS 3.4507861 1.8594026
OS 3.4543224 1.8646951
OS 3.4555642 1.870938
OS 3.4543224 1.8771809
OS 3.4507861 1.8824734
OS 3.4454936 1.8860097
OS 3.4392507 1.8872515
OE
OB 3.5548425 1.8573765 H
OS 3.5485996 1.8561347
OS 3.5433071 1.8525984
OS 3.5397708 1.8473059
OS 3.538529 1.841063
OS 3.5397708 1.8348201
OS 3.5433071 1.8295276
OS 3.5485996 1.8259913
OS 3.5548425 1.8247495
OS 3.5610854 1.8259913
OS 3.5663779 1.8295276
OS 3.5699142 1.8348201
OS 3.571156 1.841063
OS 3.5699142 1.8473059
OS 3.5663779 1.8525984
OS 3.5610854 1.8561347
OS 3.5548425 1.8573765
OE
OB 3.8048425 1.8563765 H
OS 3.7985996 1.8551347
OS 3.7933071 1.8515984
OS 3.7897708 1.8463059
OS 3.788529 1.840063
OS 3.7897708 1.8338201
OS 3.7933071 1.8285276
OS 3.7985996 1.8249913
OS 3.8048425 1.8237495
OS 3.8110854 1.8249913
OS 3.8163779 1.8285276
OS 3.8199142 1.8338201
OS 3.821156 1.840063
OS 3.8199142 1.8463059
OS 3.8163779 1.8515984
OS 3.8110854 1.8551347
OS 3.8048425 1.8563765
OE
OB 6.6858425 1.8443765 H
OS 6.6795996 1.8431347
OS 6.6743071 1.8395984
OS 6.6707708 1.8343059
OS 6.669529 1.828063
OS 6.6707708 1.8218201
OS 6.6743071 1.8165276
OS 6.6795996 1.8129913
OS 6.6858425 1.8117495
OS 6.6920854 1.8129913
OS 6.6973779 1.8165276
OS 6.7009142 1.8218201
OS 6.702156 1.828063
OS 6.7009142 1.8343059
OS 6.6973779 1.8395984
OS 6.6920854 1.8431347
OS 6.6858425 1.8443765
OE
OB 3.3291721 1.8423765 H
OS 3.3229292 1.8411347
OS 3.3176367 1.8375984
OS 3.3141004 1.8323059
OS 3.3128586 1.826063
OS 3.3141004 1.8198201
OS 3.3176367 1.8145276
OS 3.3229292 1.8109913
OS 3.3291721 1.8097495
OS 3.335415 1.8109913
OS 3.3407075 1.8145276
OS 3.3442438 1.8198201
OS 3.3454856 1.826063
OS 3.3442438 1.8323059
OS 3.3407075 1.8375984
OS 3.335415 1.8411347
OS 3.3291721 1.8423765
OE
OB 3.9448425 1.8323765 H
OS 3.9385996 1.8311347
OS 3.9333071 1.8275984
OS 3.9297708 1.8223059
OS 3.928529 1.816063
OS 3.9297708 1.8098201
OS 3.9333071 1.8045276
OS 3.9385996 1.8009913
OS 3.9448425 1.7997495
OS 3.9510854 1.8009913
OS 3.9563779 1.8045276
OS 3.9599142 1.8098201
OS 3.961156 1.816063
OS 3.9599142 1.8223059
OS 3.9563779 1.8275984
OS 3.9510854 1.8311347
OS 3.9448425 1.8323765
OE
OB 3.0568817 1.8281165 H
OS 3.0506388 1.8268747
OS 3.0453463 1.8233384
OS 3.04181 1.8180459
OS 3.0405682 1.811803
OS 3.04181 1.8055601
OS 3.0453463 1.8002676
OS 3.0506388 1.7967313
OS 3.0568817 1.7954895
OS 3.0631246 1.7967313
OS 3.0684171 1.8002676
OS 3.0719534 1.8055601
OS 3.0731952 1.811803
OS 3.0719534 1.8180459
OS 3.0684171 1.8233384
OS 3.0631246 1.8268747
OS 3.0568817 1.8281165
OE
OB 3.4144661 1.8213765 H
OS 3.4082232 1.8201347
OS 3.4029307 1.8165984
OS 3.3993944 1.8113059
OS 3.3981526 1.805063
OS 3.3993944 1.7988201
OS 3.4029307 1.7935276
OS 3.4082232 1.7899913
OS 3.4144661 1.7887495
OS 3.420709 1.7899913
OS 3.4260015 1.7935276
OS 3.4295378 1.7988201
OS 3.4307796 1.805063
OS 3.4295378 1.8113059
OS 3.4260015 1.8165984
OS 3.420709 1.8201347
OS 3.4144661 1.8213765
OE
OB 4.0648425 1.8123765 H
OS 4.0585996 1.8111347
OS 4.0533071 1.8075984
OS 4.0497708 1.8023059
OS 4.048529 1.796063
OS 4.0497708 1.7898201
OS 4.0533071 1.7845276
OS 4.0585996 1.7809913
OS 4.0648425 1.7797495
OS 4.0710854 1.7809913
OS 4.0763779 1.7845276
OS 4.0799142 1.7898201
OS 4.081156 1.796063
OS 4.0799142 1.8023059
OS 4.0763779 1.8075984
OS 4.0710854 1.8111347
OS 4.0648425 1.8123765
OE
OB 6.6018425 1.7933765 H
OS 6.5955996 1.7921347
OS 6.5903071 1.7885984
OS 6.5867708 1.7833059
OS 6.585529 1.777063
OS 6.5867708 1.7708201
OS 6.5903071 1.7655276
OS 6.5955996 1.7619913
OS 6.6018425 1.7607495
OS 6.6080854 1.7619913
OS 6.6133779 1.7655276
OS 6.6169142 1.7708201
OS 6.618156 1.777063
OS 6.6169142 1.7833059
OS 6.6133779 1.7885984
OS 6.6080854 1.7921347
OS 6.6018425 1.7933765
OE
OB 3.7198425 1.7823765 H
OS 3.7135996 1.7811347
OS 3.7083071 1.7775984
OS 3.7047708 1.7723059
OS 3.703529 1.766063
OS 3.7047708 1.7598201
OS 3.7083071 1.7545276
OS 3.7135996 1.7509913
OS 3.7198425 1.7497495
OS 3.7260854 1.7509913
OS 3.7313779 1.7545276
OS 3.7349142 1.7598201
OS 3.736156 1.766063
OS 3.7349142 1.7723059
OS 3.7313779 1.7775984
OS 3.7260854 1.7811347
OS 3.7198425 1.7823765
OE
OB 4.1348425 1.7673765 H
OS 4.1285996 1.7661347
OS 4.1233071 1.7625984
OS 4.1197708 1.7573059
OS 4.118529 1.751063
OS 4.1197708 1.7448201
OS 4.1233071 1.7395276
OS 4.1285996 1.7359913
OS 4.1348425 1.7347495
OS 4.1410854 1.7359913
OS 4.1463779 1.7395276
OS 4.1499142 1.7448201
OS 4.151156 1.751063
OS 4.1499142 1.7573059
OS 4.1463779 1.7625984
OS 4.1410854 1.7661347
OS 4.1348425 1.7673765
OE
OB 6.6028425 1.7383765 H
OS 6.5965996 1.7371347
OS 6.5913071 1.7335984
OS 6.5877708 1.7283059
OS 6.586529 1.722063
OS 6.5877708 1.7158201
OS 6.5913071 1.7105276
OS 6.5965996 1.7069913
OS 6.6028425 1.7057495
OS 6.6090854 1.7069913
OS 6.6143779 1.7105276
OS 6.6179142 1.7158201
OS 6.619156 1.722063
OS 6.6179142 1.7283059
OS 6.6143779 1.7335984
OS 6.6090854 1.7371347
OS 6.6028425 1.7383765
OE
OB 3.1972633 1.7303765 H
OS 3.1910204 1.7291347
OS 3.1857279 1.7255984
OS 3.1821916 1.7203059
OS 3.1809498 1.714063
OS 3.1821916 1.7078201
OS 3.1857279 1.7025276
OS 3.1910204 1.6989913
OS 3.1972633 1.6977495
OS 3.2035062 1.6989913
OS 3.2087987 1.7025276
OS 3.212335 1.7078201
OS 3.2135768 1.714063
OS 3.212335 1.7203059
OS 3.2087987 1.7255984
OS 3.2035062 1.7291347
OS 3.1972633 1.7303765
OE
OB 3.4108425 1.7299644 H
OS 3.4045996 1.7287226
OS 3.3993071 1.7251863
OS 3.3957708 1.7198938
OS 3.394529 1.7136509
OS 3.3957708 1.707408
OS 3.3993071 1.7021155
OS 3.4045996 1.6985792
OS 3.4108425 1.6973374
OS 3.4170854 1.6985792
OS 3.4223779 1.7021155
OS 3.4259142 1.707408
OS 3.427156 1.7136509
OS 3.4259142 1.7198938
OS 3.4223779 1.7251863
OS 3.4170854 1.7287226
OS 3.4108425 1.7299644
OE
OB 3.7188425 1.7293765 H
OS 3.7125996 1.7281347
OS 3.7073071 1.7245984
OS 3.7037708 1.7193059
OS 3.702529 1.713063
OS 3.7037708 1.7068201
OS 3.7073071 1.7015276
OS 3.7125996 1.6979913
OS 3.7188425 1.6967495
OS 3.7250854 1.6979913
OS 3.7303779 1.7015276
OS 3.7339142 1.7068201
OS 3.735156 1.713063
OS 3.7339142 1.7193059
OS 3.7303779 1.7245984
OS 3.7250854 1.7281347
OS 3.7188425 1.7293765
OE
OB 3.9968425 1.7273765 H
OS 3.9905996 1.7261347
OS 3.9853071 1.7225984
OS 3.9817708 1.7173059
OS 3.980529 1.711063
OS 3.9817708 1.7048201
OS 3.9853071 1.6995276
OS 3.9905996 1.6959913
OS 3.9968425 1.6947495
OS 4.0030854 1.6959913
OS 4.0083779 1.6995276
OS 4.0119142 1.7048201
OS 4.013156 1.711063
OS 4.0119142 1.7173059
OS 4.0083779 1.7225984
OS 4.0030854 1.7261347
OS 3.9968425 1.7273765
OE
OB 3.5898425 1.7273765 H
OS 3.5835996 1.7261347
OS 3.5783071 1.7225984
OS 3.5747708 1.7173059
OS 3.573529 1.711063
OS 3.5747708 1.7048201
OS 3.5783071 1.6995276
OS 3.5835996 1.6959913
OS 3.5898425 1.6947495
OS 3.5960854 1.6959913
OS 3.6013779 1.6995276
OS 3.6049142 1.7048201
OS 3.606156 1.711063
OS 3.6049142 1.7173059
OS 3.6013779 1.7225984
OS 3.5960854 1.7261347
OS 3.5898425 1.7273765
OE
OB 3.8038425 1.7073765 H
OS 3.7975996 1.7061347
OS 3.7923071 1.7025984
OS 3.7887708 1.6973059
OS 3.787529 1.691063
OS 3.7887708 1.6848201
OS 3.7923071 1.6795276
OS 3.7975996 1.6759913
OS 3.8038425 1.6747495
OS 3.8100854 1.6759913
OS 3.8153779 1.6795276
OS 3.8189142 1.6848201
OS 3.820156 1.691063
OS 3.8189142 1.6973059
OS 3.8153779 1.7025984
OS 3.8100854 1.7061347
OS 3.8038425 1.7073765
OE
OB 3.7248425 1.6913765 H
OS 3.7185996 1.6901347
OS 3.7133071 1.6865984
OS 3.7097708 1.6813059
OS 3.708529 1.675063
OS 3.7097708 1.6688201
OS 3.7133071 1.6635276
OS 3.7185996 1.6599913
OS 3.7248425 1.6587495
OS 3.7310854 1.6599913
OS 3.7363779 1.6635276
OS 3.7399142 1.6688201
OS 3.741156 1.675063
OS 3.7399142 1.6813059
OS 3.7363779 1.6865984
OS 3.7310854 1.6901347
OS 3.7248425 1.6913765
OE
OB 6.6028425 1.6883765 H
OS 6.5965996 1.6871347
OS 6.5913071 1.6835984
OS 6.5877708 1.6783059
OS 6.586529 1.672063
OS 6.5877708 1.6658201
OS 6.5913071 1.6605276
OS 6.5965996 1.6569913
OS 6.6028425 1.6557495
OS 6.6090854 1.6569913
OS 6.6143779 1.6605276
OS 6.6179142 1.6658201
OS 6.619156 1.672063
OS 6.6179142 1.6783059
OS 6.6143779 1.6835984
OS 6.6090854 1.6871347
OS 6.6028425 1.6883765
OE
OB 3.9688425 1.6873765 H
OS 3.9625996 1.6861347
OS 3.9573071 1.6825984
OS 3.9537708 1.6773059
OS 3.952529 1.671063
OS 3.9537708 1.6648201
OS 3.9573071 1.6595276
OS 3.9625996 1.6559913
OS 3.9688425 1.6547495
OS 3.9750854 1.6559913
OS 3.9803779 1.6595276
OS 3.9839142 1.6648201
OS 3.985156 1.671063
OS 3.9839142 1.6773059
OS 3.9803779 1.6825984
OS 3.9750854 1.6861347
OS 3.9688425 1.6873765
OE
OB 3.7738632 1.6824156 H
OS 3.7676203 1.6811738
OS 3.7623278 1.6776375
OS 3.7587915 1.672345
OS 3.7575497 1.6661021
OS 3.7587915 1.6598592
OS 3.7623278 1.6545667
OS 3.7676203 1.6510304
OS 3.7738632 1.6497886
OS 3.7801061 1.6510304
OS 3.7853986 1.6545667
OS 3.7889349 1.6598592
OS 3.7901767 1.6661021
OS 3.7889349 1.672345
OS 3.7853986 1.6776375
OS 3.7801061 1.6811738
OS 3.7738632 1.6824156
OE
OB 3.5908425 1.6783765 H
OS 3.5845996 1.6771347
OS 3.5793071 1.6735984
OS 3.5757708 1.6683059
OS 3.574529 1.662063
OS 3.5757708 1.6558201
OS 3.5793071 1.6505276
OS 3.5845996 1.6469913
OS 3.5908425 1.6457495
OS 3.5970854 1.6469913
OS 3.6023779 1.6505276
OS 3.6059142 1.6558201
OS 3.607156 1.662063
OS 3.6059142 1.6683059
OS 3.6023779 1.6735984
OS 3.5970854 1.6771347
OS 3.5908425 1.6783765
OE
OB 3.2248425 1.6776607 H
OS 3.2185996 1.6764189
OS 3.2133071 1.6728826
OS 3.2097708 1.6675901
OS 3.208529 1.6613472
OS 3.2097708 1.6551043
OS 3.2133071 1.6498118
OS 3.2185996 1.6462755
OS 3.2248425 1.6450337
OS 3.2310854 1.6462755
OS 3.235497 1.6492232
OS 3.2395781 1.6496996
OS 3.2419254 1.6491144
OS 3.2465996 1.6459913
OS 3.2528425 1.6447495
OS 3.2590854 1.6459913
OS 3.2643779 1.6495276
OS 3.2679142 1.6548201
OS 3.269156 1.661063
OS 3.2679142 1.6673059
OS 3.2643779 1.6725984
OS 3.2590854 1.6761347
OS 3.2528425 1.6773765
OS 3.2465996 1.6761347
OS 3.242188 1.673187
OS 3.2381069 1.6727106
OS 3.2357596 1.6732958
OS 3.2310854 1.6764189
OS 3.2248425 1.6776607
OE
OB 5.5781524 1.7357238 H
OS 5.5662745 1.73416
OS 5.5552061 1.7295754
OS 5.5457014 1.7222822
OS 5.5384082 1.7127775
OS 5.5338236 1.7017091
OS 5.5322598 1.6898312
OS 5.5338236 1.6779533
OS 5.5384082 1.6668849
OS 5.5457014 1.6573802
OS 5.5552061 1.650087
OS 5.5662745 1.6455024
OS 5.5781524 1.6439386
OS 5.5900303 1.6455024
OS 5.6010987 1.650087
OS 5.6106034 1.6573802
OS 5.6178966 1.6668849
OS 5.6224812 1.6779533
OS 5.624045 1.6898312
OS 5.6224812 1.7017091
OS 5.6178966 1.7127775
OS 5.6106034 1.7222822
OS 5.6010987 1.7295754
OS 5.5900303 1.73416
OS 5.5781524 1.7357238
OE
OB 6.6028425 1.6283765 H
OS 6.5965996 1.6271347
OS 6.5913071 1.6235984
OS 6.5877708 1.6183059
OS 6.586529 1.612063
OS 6.5877708 1.6058201
OS 6.5913071 1.6005276
OS 6.5965996 1.5969913
OS 6.6028425 1.5957495
OS 6.6090854 1.5969913
OS 6.6143779 1.6005276
OS 6.6179142 1.6058201
OS 6.619156 1.612063
OS 6.6179142 1.6183059
OS 6.6143779 1.6235984
OS 6.6090854 1.6271347
OS 6.6028425 1.6283765
OE
OB 4.1318425 1.7023765 H
OS 4.1255996 1.7011347
OS 4.1203071 1.6975984
OS 4.1167708 1.6923059
OS 4.115529 1.686063
OS 4.1167708 1.6798201
OS 4.1203071 1.6745276
OS 4.1255996 1.6709913
OS 4.1271051 1.6706918
OS 4.1275051 1.6694719
OS 4.127633 1.6654888
OS 4.1233071 1.6625984
OS 4.1197708 1.6573059
OS 4.118529 1.651063
OS 4.1197708 1.6448201
OS 4.1233071 1.6395276
OS 4.1285996 1.6359913
OS 4.1336434 1.634988
OS 4.1357664 1.6316625
OS 4.1362826 1.629938
OS 4.1362346 1.6298661
OS 4.1349928 1.6236232
OS 4.1362346 1.6173803
OS 4.1397709 1.6120878
OS 4.1450634 1.6085515
OS 4.1513063 1.6073097
OS 4.1575492 1.6085515
OS 4.1612353 1.6110144
OS 4.1648401 1.6074096
OS 4.1647708 1.6073059
OS 4.163529 1.601063
OS 4.1647708 1.5948201
OS 4.1683071 1.5895276
OS 4.1735996 1.5859913
OS 4.1798425 1.5847495
OS 4.1860854 1.5859913
OS 4.1913779 1.5895276
OS 4.1949142 1.5948201
OS 4.196156 1.601063
OS 4.1949142 1.6073059
OS 4.1913779 1.6125984
OS 4.1860854 1.6161347
OS 4.1798425 1.6173765
OS 4.1735996 1.6161347
OS 4.1699135 1.6136718
OS 4.1663087 1.6172766
OS 4.166378 1.6173803
OS 4.1676198 1.6236232
OS 4.166378 1.6298661
OS 4.1628417 1.6351586
OS 4.1575492 1.6386949
OS 4.1525054 1.6396982
OS 4.1503824 1.6430237
OS 4.1498662 1.6447482
OS 4.1499142 1.6448201
OS 4.151156 1.651063
OS 4.1499142 1.6573059
OS 4.1463779 1.6625984
OS 4.1410854 1.6661347
OS 4.1395799 1.6664342
OS 4.1391799 1.6676541
OS 4.139052 1.6716372
OS 4.1433779 1.6745276
OS 4.1469142 1.6798201
OS 4.148156 1.686063
OS 4.1469142 1.6923059
OS 4.1433779 1.6975984
OS 4.1380854 1.7011347
OS 4.1318425 1.7023765
OE
OB 3.4138425 1.5893765 H
OS 3.4075996 1.5881347
OS 3.4023071 1.5845984
OS 3.3987708 1.5793059
OS 3.397529 1.573063
OS 3.3987708 1.5668201
OS 3.4023071 1.5615276
OS 3.4075996 1.5579913
OS 3.4138425 1.5567495
OS 3.4200854 1.5579913
OS 3.4253779 1.5615276
OS 3.4289142 1.5668201
OS 3.430156 1.573063
OS 3.4289142 1.5793059
OS 3.4253779 1.5845984
OS 3.4200854 1.5881347
OS 3.4138425 1.5893765
OE
OB 3.8948425 1.5823765 H
OS 3.8885996 1.5811347
OS 3.8833071 1.5775984
OS 3.8797708 1.5723059
OS 3.878529 1.566063
OS 3.8797708 1.5598201
OS 3.8833071 1.5545276
OS 3.8885996 1.5509913
OS 3.8948425 1.5497495
OS 3.9010854 1.5509913
OS 3.9063779 1.5545276
OS 3.9099142 1.5598201
OS 3.911156 1.566063
OS 3.9099142 1.5723059
OS 3.9063779 1.5775984
OS 3.9010854 1.5811347
OS 3.8948425 1.5823765
OE
OB 3.9698425 1.5683765 H
OS 3.9635996 1.5671347
OS 3.9583071 1.5635984
OS 3.9547708 1.5583059
OS 3.953529 1.552063
OS 3.9547708 1.5458201
OS 3.9583071 1.5405276
OS 3.9635996 1.5369913
OS 3.9698425 1.5357495
OS 3.9760854 1.5369913
OS 3.9780923 1.5383323
OS 3.9831154 1.5394836
OS 3.9856688 1.5379496
OS 3.9885996 1.5359913
OS 3.9948425 1.5347495
OS 4.0010854 1.5359913
OS 4.0063779 1.5395276
OS 4.0099142 1.5448201
OS 4.011156 1.551063
OS 4.0099142 1.5573059
OS 4.0063779 1.5625984
OS 4.0010854 1.5661347
OS 3.9948425 1.5673765
OS 3.9885996 1.5661347
OS 3.9833072 1.5625984
OS 3.982046 1.5625984
OS 3.9813779 1.5635984
OS 3.9760854 1.5671347
OS 3.9698425 1.5683765
OE
OB 4.0348425 1.5623765 H
OS 4.0285996 1.5611347
OS 4.0233071 1.5575984
OS 4.0197708 1.5523059
OS 4.018529 1.546063
OS 4.0197708 1.5398201
OS 4.0233071 1.5345276
OS 4.0285996 1.5309913
OS 4.0348425 1.5297495
OS 4.0410854 1.5309913
OS 4.0463779 1.5345276
OS 4.0499142 1.5398201
OS 4.051156 1.546063
OS 4.0499142 1.5523059
OS 4.0463779 1.5575984
OS 4.0410854 1.5611347
OS 4.0348425 1.5623765
OE
OB 3.9248425 1.5523765 H
OS 3.9185996 1.5511347
OS 3.9133071 1.5475984
OS 3.9097708 1.5423059
OS 3.908529 1.536063
OS 3.9097708 1.5298201
OS 3.9133071 1.5245276
OS 3.9185996 1.5209913
OS 3.9248425 1.5197495
OS 3.9310854 1.5209913
OS 3.9363779 1.5245276
OS 3.9399142 1.5298201
OS 3.941156 1.536063
OS 3.9399142 1.5423059
OS 3.9363779 1.5475984
OS 3.9310854 1.5511347
OS 3.9248425 1.5523765
OE
OB 2.8948425 1.5773765 H
OS 2.8885996 1.5761347
OS 2.8833071 1.5725984
OS 2.8797708 1.5673059
OS 2.878529 1.561063
OS 2.8797708 1.5548201
OS 2.8833071 1.5495276
OS 2.8885996 1.5459913
OS 2.8948425 1.5447495
OS 2.9010854 1.5459913
OS 2.9013282 1.5461536
OS 2.9049331 1.5425487
OS 2.9047708 1.5423059
OS 2.903529 1.536063
OS 2.9047708 1.5298201
OS 2.9083071 1.5245276
OS 2.9135996 1.5209913
OS 2.9198425 1.5197495
OS 2.9260854 1.5209913
OS 2.9313779 1.5245276
OS 2.9349142 1.5298201
OS 2.936156 1.536063
OS 2.9349142 1.5423059
OS 2.9313779 1.5475984
OS 2.9260854 1.5511347
OS 2.9198425 1.5523765
OS 2.9135996 1.5511347
OS 2.9133568 1.5509724
OS 2.9097519 1.5545773
OS 2.9099142 1.5548201
OS 2.911156 1.561063
OS 2.9099142 1.5673059
OS 2.9063779 1.5725984
OS 2.9010854 1.5761347
OS 2.8948425 1.5773765
OE
OB 6.5488425 1.5473765 H
OS 6.5425996 1.5461347
OS 6.5373071 1.5425984
OS 6.5337708 1.5373059
OS 6.532529 1.531063
OS 6.5337708 1.5248201
OS 6.5373071 1.5195276
OS 6.5425996 1.5159913
OS 6.5488425 1.5147495
OS 6.5550854 1.5159913
OS 6.5603779 1.5195276
OS 6.5639142 1.5248201
OS 6.565156 1.531063
OS 6.5639142 1.5373059
OS 6.5603779 1.5425984
OS 6.5550854 1.5461347
OS 6.5488425 1.5473765
OE
OB 3.5948425 1.5303765 H
OS 3.5885996 1.5291347
OS 3.5833071 1.5255984
OS 3.5797708 1.5203059
OS 3.578529 1.514063
OS 3.5797708 1.5078201
OS 3.5833071 1.5025276
OS 3.5885996 1.4989913
OS 3.5948425 1.4977495
OS 3.6010854 1.4989913
OS 3.6063779 1.5025276
OS 3.6099142 1.5078201
OS 3.611156 1.514063
OS 3.6099142 1.5203059
OS 3.6063779 1.5255984
OS 3.6010854 1.5291347
OS 3.5948425 1.5303765
OE
OB 4.0648425 1.5273765 H
OS 4.0585996 1.5261347
OS 4.0533071 1.5225984
OS 4.0497708 1.5173059
OS 4.048529 1.511063
OS 4.0497708 1.5048201
OS 4.0533071 1.4995276
OS 4.0585996 1.4959913
OS 4.0648425 1.4947495
OS 4.0710854 1.4959913
OS 4.0763779 1.4995276
OS 4.0799142 1.5048201
OS 4.081156 1.511063
OS 4.0799142 1.5173059
OS 4.0763779 1.5225984
OS 4.0710854 1.5261347
OS 4.0648425 1.5273765
OE
OB 3.8648425 1.5273765 H
OS 3.8585996 1.5261347
OS 3.8533071 1.5225984
OS 3.8497708 1.5173059
OS 3.848529 1.511063
OS 3.8497708 1.5048201
OS 3.8533071 1.4995276
OS 3.8585996 1.4959913
OS 3.8648425 1.4947495
OS 3.8710854 1.4959913
OS 3.8763779 1.4995276
OS 3.8799142 1.5048201
OS 3.881156 1.511063
OS 3.8799142 1.5173059
OS 3.8763779 1.5225984
OS 3.8710854 1.5261347
OS 3.8648425 1.5273765
OE
OB 3.8348425 1.4973765 H
OS 3.8285996 1.4961347
OS 3.8233071 1.4925984
OS 3.8197708 1.4873059
OS 3.818529 1.481063
OS 3.8197708 1.4748201
OS 3.8233071 1.4695276
OS 3.8285996 1.4659913
OS 3.8348425 1.4647495
OS 3.8410854 1.4659913
OS 3.8463779 1.4695276
OS 3.8499142 1.4748201
OS 3.851156 1.481063
OS 3.8499142 1.4873059
OS 3.8463779 1.4925984
OS 3.8410854 1.4961347
OS 3.8348425 1.4973765
OE
OB 3.4068425 1.4773765 H
OS 3.4005996 1.4761347
OS 3.3953071 1.4725984
OS 3.3917708 1.4673059
OS 3.390529 1.461063
OS 3.3917708 1.4548201
OS 3.3953071 1.4495276
OS 3.4005996 1.4459913
OS 3.4068425 1.4447495
OS 3.4130854 1.4459913
OS 3.4183779 1.4495276
OS 3.4219142 1.4548201
OS 3.423156 1.461063
OS 3.4219142 1.4673059
OS 3.4183779 1.4725984
OS 3.4130854 1.4761347
OS 3.4068425 1.4773765
OE
OB 3.7328425 1.4343765 H
OS 3.7265996 1.4331347
OS 3.7213071 1.4295984
OS 3.7177708 1.4243059
OS 3.716529 1.418063
OS 3.7177708 1.4118201
OS 3.7213071 1.4065276
OS 3.7265996 1.4029913
OS 3.7328425 1.4017495
OS 3.7390854 1.4029913
OS 3.7443779 1.4065276
OS 3.7479142 1.4118201
OS 3.749156 1.418063
OS 3.7479142 1.4243059
OS 3.7443779 1.4295984
OS 3.7390854 1.4331347
OS 3.7328425 1.4343765
OE
OB 3.4072822 1.4276365 H
OS 3.4010393 1.4263947
OS 3.3957468 1.4228584
OS 3.3922105 1.4175659
OS 3.3909687 1.411323
OS 3.3922105 1.4050801
OS 3.3952066 1.4005957
OS 3.3913778 1.3975986
OS 3.3860854 1.4011347
OS 3.3798425 1.4023765
OS 3.3735996 1.4011347
OS 3.3683071 1.3975984
OS 3.3647708 1.3923059
OS 3.363529 1.386063
OS 3.3647708 1.3798201
OS 3.3683071 1.3745276
OS 3.3735996 1.3709913
OS 3.3798425 1.3697495
OS 3.3850268 1.3707807
OS 3.3880585 1.3685992
OS 3.3892832 1.3671145
OS 3.388529 1.363323
OS 3.3897708 1.3570801
OS 3.3920261 1.3537048
OS 3.3926608 1.3527545
OS 3.3890562 1.3491499
OS 3.3882815 1.3496673
OS 3.3860854 1.3511347
OS 3.3798425 1.3523765
OS 3.3735996 1.3511347
OS 3.3683071 1.3475984
OS 3.3647708 1.3423059
OS 3.363529 1.336063
OS 3.3647708 1.3298201
OS 3.3683071 1.3245276
OS 3.3735996 1.3209913
OS 3.3798425 1.3197495
OS 3.3860854 1.3209913
OS 3.3913779 1.3245276
OS 3.3949142 1.3298201
OS 3.396156 1.336063
OS 3.3949142 1.3423059
OS 3.3926589 1.3456812
OS 3.3920242 1.3466315
OS 3.3956288 1.3502361
OS 3.3964035 1.3497187
OS 3.3985996 1.3482513
OS 3.4048425 1.3470095
OS 3.4110854 1.3482513
OS 3.4163779 1.3517876
OS 3.4199142 1.3570801
OS 3.421156 1.363323
OS 3.4199142 1.3695659
OS 3.4163779 1.3748584
OS 3.4110854 1.3783947
OS 3.4048425 1.3796365
OS 3.3996582 1.3786053
OS 3.3966265 1.3807868
OS 3.3954018 1.3822715
OS 3.396156 1.386063
OS 3.3949142 1.3923059
OS 3.3919181 1.3967903
OS 3.3957469 1.3997874
OS 3.4010393 1.3962513
OS 3.4072822 1.3950095
OS 3.4135251 1.3962513
OS 3.4188176 1.3997876
OS 3.4223539 1.4050801
OS 3.4235957 1.411323
OS 3.4223539 1.4175659
OS 3.4188176 1.4228584
OS 3.4135251 1.4263947
OS 3.4072822 1.4276365
OE
OB 3.5498425 1.4573765 H
OS 3.5435996 1.4561347
OS 3.5383071 1.4525984
OS 3.5347708 1.4473059
OS 3.533529 1.441063
OS 3.5347708 1.4348201
OS 3.5383071 1.4295277
OS 3.5383071 1.4245983
OS 3.5347708 1.4193059
OS 3.533529 1.413063
OS 3.5347708 1.4068201
OS 3.5383071 1.4015276
OS 3.5435996 1.3979913
OS 3.5498425 1.3967495
OS 3.5560854 1.3979913
OS 3.5613779 1.4015276
OS 3.5649142 1.4068201
OS 3.566156 1.413063
OS 3.5649142 1.4193059
OS 3.5613779 1.4245983
OS 3.5613779 1.4295277
OS 3.5649142 1.4348201
OS 3.566156 1.441063
OS 3.5649142 1.4473059
OS 3.5613779 1.4525984
OS 3.5560854 1.4561347
OS 3.5498425 1.4573765
OE
OB 3.5717425 1.3289919 H
OS 3.5643954 1.3275305
OS 3.5581668 1.3233687
OS 3.554005 1.3171401
OS 3.5525436 1.309793
OS 3.554005 1.3024459
OS 3.5581668 1.2962173
OS 3.5643954 1.2920555
OS 3.5717425 1.2905941
OS 3.5790896 1.2920555
OS 3.5853182 1.2962173
OS 3.58948 1.3024459
OS 3.5909414 1.309793
OS 3.58948 1.3171401
OS 3.5853182 1.3233687
OS 3.5790896 1.3275305
OS 3.5717425 1.3289919
OE
OB 4.3662677 1.0459921 H
OS 4.2892441 1.0459921
OS 4.2892441 0.9689685
OS 4.3662677 0.9689685
OS 4.3662677 1.0459921
OE
OB 5.3277559 1.0463244 H
OS 5.3177023 1.0450008
OS 5.3083338 1.0411203
OS 5.300289 1.0349472
OS 5.2941159 1.0269023
OS 5.2902354 1.0175339
OS 5.2889118 1.0074803
OS 5.2902354 0.9974267
OS 5.2941159 0.9880583
OS 5.300289 0.9800134
OS 5.3083338 0.9738403
OS 5.3177023 0.9699598
OS 5.3277559 0.9686362
OS 5.3378095 0.9699598
OS 5.347178 0.9738403
OS 5.3552228 0.9800134
OS 5.3613959 0.9880583
OS 5.3652764 0.9974267
OS 5.3666 1.0074803
OS 5.3652764 1.0175339
OS 5.3613959 1.0269023
OS 5.3552228 1.0349472
OS 5.347178 1.0411203
OS 5.3378095 1.0450008
OS 5.3277559 1.0463244
OE
OB 5.1277559 1.0463244 H
OS 5.1177023 1.0450008
OS 5.1083338 1.0411203
OS 5.100289 1.0349472
OS 5.0941159 1.0269023
OS 5.0902354 1.0175339
OS 5.0889118 1.0074803
OS 5.0902354 0.9974267
OS 5.0941159 0.9880583
OS 5.100289 0.9800134
OS 5.1083338 0.9738403
OS 5.1177023 0.9699598
OS 5.1277559 0.9686362
OS 5.1378095 0.9699598
OS 5.147178 0.9738403
OS 5.1552228 0.9800134
OS 5.1613959 0.9880583
OS 5.1652764 0.9974267
OS 5.1666 1.0074803
OS 5.1652764 1.0175339
OS 5.1613959 1.0269023
OS 5.1552228 1.0349472
OS 5.147178 1.0411203
OS 5.1378095 1.0450008
OS 5.1277559 1.0463244
OE
OB 4.9277559 1.0463244 H
OS 4.9177023 1.0450008
OS 4.9083338 1.0411203
OS 4.900289 1.0349472
OS 4.8941159 1.0269023
OS 4.8902354 1.0175339
OS 4.8889118 1.0074803
OS 4.8902354 0.9974267
OS 4.8941159 0.9880583
OS 4.900289 0.9800134
OS 4.9083338 0.9738403
OS 4.9177023 0.9699598
OS 4.9277559 0.9686362
OS 4.9378095 0.9699598
OS 4.947178 0.9738403
OS 4.9552228 0.9800134
OS 4.9613959 0.9880583
OS 4.9652764 0.9974267
OS 4.9666 1.0074803
OS 4.9652764 1.0175339
OS 4.9613959 1.0269023
OS 4.9552228 1.0349472
OS 4.947178 1.0411203
OS 4.9378095 1.0450008
OS 4.9277559 1.0463244
OE
OB 3.6179425 0.9836725 H
OS 3.6047974 0.9823778
OS 3.5921575 0.9785435
OS 3.5805085 0.972317
OS 3.570298 0.9639375
OS 3.5619185 0.953727
OS 3.555692 0.942078
OS 3.5518577 0.9294381
OS 3.550563 0.916293
OS 3.5518577 0.9031479
OS 3.555692 0.890508
OS 3.5619185 0.878859
OS 3.570298 0.8686485
OS 3.5805085 0.860269
OS 3.5921575 0.8540425
OS 3.6047974 0.8502082
OS 3.6179425 0.8489135
OS 3.6310876 0.8502082
OS 3.6437275 0.8540425
OS 3.6553765 0.860269
OS 3.665587 0.8686485
OS 3.6739665 0.878859
OS 3.680193 0.890508
OS 3.6840273 0.9031479
OS 3.685322 0.916293
OS 3.6840273 0.9294381
OS 3.680193 0.942078
OS 3.6739665 0.953727
OS 3.665587 0.9639375
OS 3.6553765 0.972317
OS 3.6437275 0.9785435
OS 3.6310876 0.9823778
OS 3.6179425 0.9836725
OE
OB 5.5781524 0.9365112 H
OS 5.5662745 0.9349474
OS 5.5552061 0.9303628
OS 5.5457014 0.9230696
OS 5.5384082 0.9135649
OS 5.5338236 0.9024965
OS 5.5322598 0.8906186
OS 5.5338236 0.8787407
OS 5.5384082 0.8676723
OS 5.5457014 0.8581676
OS 5.5552061 0.8508744
OS 5.5662745 0.8462898
OS 5.5781524 0.844726
OS 5.5900303 0.8462898
OS 5.6010987 0.8508744
OS 5.6106034 0.8581676
OS 5.6178966 0.8676723
OS 5.6224812 0.8787407
OS 5.624045 0.8906186
OS 5.6224812 0.9024965
OS 5.6178966 0.9135649
OS 5.6106034 0.9230696
OS 5.6010987 0.9303628
OS 5.5900303 0.9349474
OS 5.5781524 0.9365112
OE
SE
S P 0
OB 6.2758024 3.7096816 I
OS 6.2792454 3.7046648
OS 6.278529 3.701063
OS 6.2797708 3.6948201
OS 6.2833071 3.6895276
OS 6.2885996 3.6859913
OS 6.2948425 3.6847495
OS 6.3010854 3.6859913
OS 6.3063779 3.6895276
OS 6.3099142 3.6948201
OS 6.311156 3.701063
OS 6.3104696 3.704514
OS 6.3140059 3.709497
OS 7.0248425 3.706063
OS 7.0875984 3.6433071
OS 7.0875984 1.4888189
OS 6.7798425 1.181063
OS 6.6498425 1.181063
OS 6.5898425 1.241063
OS 6.5898425 1.326063
OS 6.6215033 1.3577238
OS 6.6225996 1.3569913
OS 6.6288425 1.3557495
OS 6.6350854 1.3569913
OS 6.6403779 1.3605276
OS 6.6439142 1.3658201
OS 6.645156 1.372063
OS 6.6439142 1.3783059
OS 6.6431817 1.3794022
OS 6.9098425 1.646063
OS 6.9098425 1.991063
OS 6.8198425 2.081063
OS 6.4098425 2.081063
OS 6.3998541 2.0910514
OS 6.4013055 2.0958362
OS 6.4020854 2.0959913
OS 6.4073779 2.0995276
OS 6.4109142 2.1048201
OS 6.412156 2.111063
OS 6.4109142 2.1173059
OS 6.4073779 2.1225984
OS 6.4020854 2.1261347
OS 6.3958425 2.1273765
OS 6.3895996 2.1261347
OS 6.3843071 2.1225984
OS 6.3807708 2.1173059
OS 6.3806157 2.116526
OS 6.3758309 2.1150746
OS 6.3348425 2.156063
OS 6.3348425 2.996063
OS 5.8798425 3.451063
OS 5.8798425 3.601063
OS 5.9898425 3.711063
OS 6.2758024 3.7096816
OE
OB 6.9001969 3.6472339 H
OS 6.8852614 3.6452676
OS 6.8713437 3.6395027
OS 6.8593924 3.6303321
OS 6.8502218 3.6183808
OS 6.8444569 3.6044631
OS 6.8424906 3.5895276
OS 6.8444569 3.5745921
OS 6.8502218 3.5606744
OS 6.8593924 3.5487231
OS 6.8713437 3.5395525
OS 6.8852614 3.5337876
OS 6.9001969 3.5318213
OS 6.9151324 3.5337876
OS 6.9290501 3.5395525
OS 6.9410014 3.5487231
OS 6.950172 3.5606744
OS 6.9559369 3.5745921
OS 6.9579032 3.5895276
OS 6.9559369 3.6044631
OS 6.950172 3.6183808
OS 6.9410014 3.6303321
OS 6.9290501 3.6395027
OS 6.9151324 3.6452676
OS 6.9001969 3.6472339
OE
OB 6.7348425 3.6472339 H
OS 6.719907 3.6452676
OS 6.7059893 3.6395027
OS 6.694038 3.6303321
OS 6.6848674 3.6183808
OS 6.6791025 3.6044631
OS 6.6771362 3.5895276
OS 6.6791025 3.5745921
OS 6.6848674 3.5606744
OS 6.694038 3.5487231
OS 6.7059893 3.5395525
OS 6.719907 3.5337876
OS 6.7348425 3.5318213
OS 6.749778 3.5337876
OS 6.7636957 3.5395525
OS 6.775647 3.5487231
OS 6.7848176 3.5606744
OS 6.7905825 3.5745921
OS 6.7925488 3.5895276
OS 6.7905825 3.6044631
OS 6.7848176 3.6183808
OS 6.775647 3.6303321
OS 6.7636957 3.6395027
OS 6.749778 3.6452676
OS 6.7348425 3.6472339
OE
OB 6.5694882 3.6472339 H
OS 6.5545527 3.6452676
OS 6.540635 3.6395027
OS 6.5286837 3.6303321
OS 6.5195131 3.6183807
OS 6.5137482 3.6044631
OS 6.5117819 3.5895276
OS 6.5137482 3.5745921
OS 6.5195131 3.5606745
OS 6.5286837 3.5487231
OS 6.540635 3.5395525
OS 6.5545527 3.5337876
OS 6.5694882 3.5318213
OS 6.5844237 3.5337876
OS 6.5983414 3.5395525
OS 6.6102927 3.5487231
OS 6.6194633 3.5606745
OS 6.6252282 3.5745921
OS 6.6271945 3.5895276
OS 6.6252282 3.6044631
OS 6.6194633 3.6183807
OS 6.6102927 3.6303321
OS 6.5983414 3.6395027
OS 6.5844237 3.6452676
OS 6.5694882 3.6472339
OE
OB 6.5098425 3.4723765 H
OS 6.5035996 3.4711347
OS 6.4983071 3.4675984
OS 6.4947708 3.4623059
OS 6.493529 3.456063
OS 6.4947708 3.4498201
OS 6.4983071 3.4445276
OS 6.5035996 3.4409913
OS 6.5098425 3.4397495
OS 6.5160854 3.4409913
OS 6.5213779 3.4445276
OS 6.5249142 3.4498201
OS 6.526156 3.456063
OS 6.5249142 3.4623059
OS 6.5213779 3.4675984
OS 6.5160854 3.4711347
OS 6.5098425 3.4723765
OE
OB 6.4798425 3.4423765 H
OS 6.4735996 3.4411347
OS 6.4683071 3.4375984
OS 6.4647708 3.4323059
OS 6.463529 3.426063
OS 6.4647708 3.4198201
OS 6.4683071 3.4145276
OS 6.4735996 3.4109913
OS 6.4798425 3.4097495
OS 6.4860854 3.4109913
OS 6.4913779 3.4145276
OS 6.4949142 3.4198201
OS 6.496156 3.426063
OS 6.4949142 3.4323059
OS 6.4913779 3.4375984
OS 6.4860854 3.4411347
OS 6.4798425 3.4423765
OE
OB 6.4475772 3.4123765 H
OS 6.4413343 3.4111347
OS 6.4360418 3.4075984
OS 6.4325055 3.4023059
OS 6.4312637 3.396063
OS 6.4325055 3.3898201
OS 6.4360418 3.3845276
OS 6.4413343 3.3809913
OS 6.4475772 3.3797495
OS 6.4538201 3.3809913
OS 6.4591126 3.3845276
OS 6.4626489 3.3898201
OS 6.4638907 3.396063
OS 6.4626489 3.4023059
OS 6.4591126 3.4075984
OS 6.4538201 3.4111347
OS 6.4475772 3.4123765
OE
OB 6.4098425 3.3873765 H
OS 6.4035996 3.3861347
OS 6.3983071 3.3825984
OS 6.3947708 3.3773059
OS 6.393529 3.371063
OS 6.3947708 3.3648201
OS 6.3983071 3.3595276
OS 6.4035996 3.3559913
OS 6.4098425 3.3547495
OS 6.4160854 3.3559913
OS 6.4213779 3.3595276
OS 6.4249142 3.3648201
OS 6.426156 3.371063
OS 6.4249142 3.3773059
OS 6.4213779 3.3825984
OS 6.4160854 3.3861347
OS 6.4098425 3.3873765
OE
OB 6.6488425 3.3573765 H
OS 6.6425996 3.3561347
OS 6.6373071 3.3525984
OS 6.6337708 3.3473059
OS 6.632529 3.341063
OS 6.6337708 3.3348201
OS 6.6373071 3.3295276
OS 6.6425996 3.3259913
OS 6.6488425 3.3247495
OS 6.6550854 3.3259913
OS 6.6603779 3.3295276
OS 6.6639142 3.3348201
OS 6.665156 3.341063
OS 6.6639142 3.3473059
OS 6.6603779 3.3525984
OS 6.6550854 3.3561347
OS 6.6488425 3.3573765
OE
OB 6.3547483 3.3474519 H
OS 6.3485054 3.3462101
OS 6.3432129 3.3426738
OS 6.3396766 3.3373813
OS 6.3384348 3.3311384
OS 6.3396766 3.3248955
OS 6.3432129 3.319603
OS 6.3485054 3.3160667
OS 6.3547483 3.3148249
OS 6.3609912 3.3160667
OS 6.3662837 3.319603
OS 6.36982 3.3248955
OS 6.3710618 3.3311384
OS 6.36982 3.3373813
OS 6.3662837 3.3426738
OS 6.3609912 3.3462101
OS 6.3547483 3.3474519
OE
OB 6.4448425 3.3073765 H
OS 6.4385996 3.3061347
OS 6.4333071 3.3025984
OS 6.4297708 3.2973059
OS 6.428529 3.291063
OS 6.4297708 3.2848201
OS 6.4333071 3.2795276
OS 6.4385996 3.2759913
OS 6.4448425 3.2747495
OS 6.4510854 3.2759913
OS 6.4563779 3.2795276
OS 6.4599142 3.2848201
OS 6.461156 3.291063
OS 6.4599142 3.2973059
OS 6.4563779 3.3025984
OS 6.4510854 3.3061347
OS 6.4448425 3.3073765
OE
OB 6.3348425 3.2823765 H
OS 6.3285996 3.2811347
OS 6.3233071 3.2775984
OS 6.3197708 3.2723059
OS 6.318529 3.266063
OS 6.3197708 3.2598201
OS 6.3233071 3.2545276
OS 6.3285996 3.2509913
OS 6.3348425 3.2497495
OS 6.3410854 3.2509913
OS 6.3463779 3.2545276
OS 6.3499142 3.2598201
OS 6.351156 3.266063
OS 6.3499142 3.2723059
OS 6.3463779 3.2775984
OS 6.3410854 3.2811347
OS 6.3348425 3.2823765
OE
OB 6.4768425 3.2473765 H
OS 6.4705996 3.2461347
OS 6.4653071 3.2425984
OS 6.4617708 3.2373059
OS 6.460529 3.231063
OS 6.4617708 3.2248201
OS 6.4653071 3.2195276
OS 6.4705996 3.2159913
OS 6.4768425 3.2147495
OS 6.4830854 3.2159913
OS 6.4883779 3.2195276
OS 6.4919142 3.2248201
OS 6.493156 3.231063
OS 6.4919142 3.2373059
OS 6.4883779 3.2425984
OS 6.4830854 3.2461347
OS 6.4768425 3.2473765
OE
OB 6.2824161 3.2423765 H
OS 6.2761732 3.2411347
OS 6.2708807 3.2375984
OS 6.2673444 3.2323059
OS 6.2661026 3.226063
OS 6.2673444 3.2198201
OS 6.2708807 3.2145276
OS 6.2761732 3.2109913
OS 6.2824161 3.2097495
OS 6.288659 3.2109913
OS 6.2939515 3.2145276
OS 6.2974878 3.2198201
OS 6.2987296 3.226063
OS 6.2974878 3.2323059
OS 6.2939515 3.2375984
OS 6.288659 3.2411347
OS 6.2824161 3.2423765
OE
OB 6.3094161 3.2153765 H
OS 6.3031732 3.2141347
OS 6.2978807 3.2105984
OS 6.2943444 3.2053059
OS 6.2931026 3.199063
OS 6.2943444 3.1928201
OS 6.2978807 3.1875276
OS 6.3031732 3.1839913
OS 6.3094161 3.1827495
OS 6.315659 3.1839913
OS 6.3209515 3.1875276
OS 6.3244878 3.1928201
OS 6.3257296 3.199063
OS 6.3244878 3.2053059
OS 6.3209515 3.2105984
OS 6.315659 3.2141347
OS 6.3094161 3.2153765
OE
OB 6.4398425 3.2073765 H
OS 6.4335996 3.2061347
OS 6.4283071 3.2025984
OS 6.4247708 3.1973059
OS 6.423529 3.191063
OS 6.4247708 3.1848201
OS 6.4283071 3.1795276
OS 6.4335996 3.1759913
OS 6.4398425 3.1747495
OS 6.4460854 3.1759913
OS 6.4513779 3.1795276
OS 6.4549142 3.1848201
OS 6.456156 3.191063
OS 6.4549142 3.1973059
OS 6.4513779 3.2025984
OS 6.4460854 3.2061347
OS 6.4398425 3.2073765
OE
OB 6.3398425 3.1673765 H
OS 6.3335996 3.1661347
OS 6.3283071 3.1625984
OS 6.3247708 3.1573059
OS 6.323529 3.151063
OS 6.3247708 3.1448201
OS 6.3283071 3.1395276
OS 6.3335996 3.1359913
OS 6.3398425 3.1347495
OS 6.3460854 3.1359913
OS 6.3513779 3.1395276
OS 6.3549142 3.1448201
OS 6.356156 3.151063
OS 6.3549142 3.1573059
OS 6.3513779 3.1625984
OS 6.3460854 3.1661347
OS 6.3398425 3.1673765
OE
OB 6.6476378 3.1462348 H
OS 6.6413949 3.144993
OS 6.6361024 3.1414567
OS 6.6325661 3.1361642
OS 6.6313243 3.1299213
OS 6.6325661 3.1236784
OS 6.6361024 3.1183859
OS 6.6413949 3.1148496
OS 6.6476378 3.1136078
OS 6.6538807 3.1148496
OS 6.6591732 3.1183859
OS 6.6627095 3.1236784
OS 6.6639513 3.1299213
OS 6.6627095 3.1361642
OS 6.6591732 3.1414567
OS 6.6538807 3.144993
OS 6.6476378 3.1462348
OE
OB 6.3048425 3.1373765 H
OS 6.2985996 3.1361347
OS 6.2933071 3.1325984
OS 6.2897708 3.1273059
OS 6.288529 3.121063
OS 6.2897708 3.1148201
OS 6.2933071 3.1095276
OS 6.2985996 3.1059913
OS 6.3048425 3.1047495
OS 6.3110854 3.1059913
OS 6.3163779 3.1095276
OS 6.3199142 3.1148201
OS 6.321156 3.121063
OS 6.3199142 3.1273059
OS 6.3163779 3.1325984
OS 6.3110854 3.1361347
OS 6.3048425 3.1373765
OE
OB 6.6268425 3.0483765 H
OS 6.6205996 3.0471347
OS 6.6153071 3.0435984
OS 6.6117708 3.0383059
OS 6.610529 3.032063
OS 6.6117708 3.0258201
OS 6.6153071 3.0205276
OS 6.6205996 3.0169913
OS 6.6268425 3.0157495
OS 6.6330854 3.0169913
OS 6.6383779 3.0205276
OS 6.6419142 3.0258201
OS 6.643156 3.032063
OS 6.6419142 3.0383059
OS 6.6383779 3.0435984
OS 6.6330854 3.0471347
OS 6.6268425 3.0483765
OE
OB 6.4568425 3.0253765 H
OS 6.4505996 3.0241347
OS 6.4453071 3.0205984
OS 6.4417708 3.0153059
OS 6.440529 3.009063
OS 6.4417708 3.0028201
OS 6.4453071 2.9975276
OS 6.4505996 2.9939913
OS 6.4568425 2.9927495
OS 6.4630854 2.9939913
OS 6.4683779 2.9975276
OS 6.4719142 3.0028201
OS 6.473156 3.009063
OS 6.4719142 3.0153059
OS 6.4683779 3.0205984
OS 6.4630854 3.0241347
OS 6.4568425 3.0253765
OE
OB 6.3720472 2.9257623 H
OS 6.3658043 2.9245205
OS 6.3605118 2.9209842
OS 6.3569755 2.9156917
OS 6.3557337 2.9094488
OS 6.3569755 2.9032059
OS 6.3605118 2.8979134
OS 6.3658043 2.8943771
OS 6.3720472 2.8931353
OS 6.3782901 2.8943771
OS 6.3835826 2.8979134
OS 6.3871189 2.9032059
OS 6.3883607 2.9094488
OS 6.3871189 2.9156917
OS 6.3835826 2.9209842
OS 6.3782901 2.9245205
OS 6.3720472 2.9257623
OE
OB 6.3988425 2.6733765 H
OS 6.3925996 2.6721347
OS 6.3873071 2.6685984
OS 6.3837708 2.6633059
OS 6.382529 2.657063
OS 6.3837708 2.6508201
OS 6.3873071 2.6455276
OS 6.3925996 2.6419913
OS 6.3988425 2.6407495
OS 6.4050854 2.6419913
OS 6.4103779 2.6455276
OS 6.4139142 2.6508201
OS 6.415156 2.657063
OS 6.4139142 2.6633059
OS 6.4103779 2.6685984
OS 6.4050854 2.6721347
OS 6.3988425 2.6733765
OE
OB 6.3978425 2.6263765 H
OS 6.3915996 2.6251347
OS 6.3863071 2.6215984
OS 6.3827708 2.6163059
OS 6.381529 2.610063
OS 6.3827708 2.6038201
OS 6.3863071 2.5985276
OS 6.3915996 2.5949913
OS 6.3978425 2.5937495
OS 6.4040854 2.5949913
OS 6.4093779 2.5985276
OS 6.4129142 2.6038201
OS 6.414156 2.610063
OS 6.4129142 2.6163059
OS 6.4093779 2.6215984
OS 6.4040854 2.6251347
OS 6.3978425 2.6263765
OE
OB 6.3968425 2.5723765 H
OS 6.3905996 2.5711347
OS 6.3853071 2.5675984
OS 6.3817708 2.5623059
OS 6.380529 2.556063
OS 6.3817708 2.5498201
OS 6.3853071 2.5445276
OS 6.3905996 2.5409913
OS 6.3968425 2.5397495
OS 6.4030854 2.5409913
OS 6.4083779 2.5445276
OS 6.4119142 2.5498201
OS 6.413156 2.556063
OS 6.4119142 2.5623059
OS 6.4083779 2.5675984
OS 6.4030854 2.5711347
OS 6.3968425 2.5723765
OE
OB 6.3978425 2.5173765 H
OS 6.3915996 2.5161347
OS 6.3863071 2.5125984
OS 6.3827708 2.5073059
OS 6.381529 2.501063
OS 6.3827708 2.4948201
OS 6.3863071 2.4895276
OS 6.3915996 2.4859913
OS 6.3978425 2.4847495
OS 6.4040854 2.4859913
OS 6.4093779 2.4895276
OS 6.4129142 2.4948201
OS 6.414156 2.501063
OS 6.4129142 2.5073059
OS 6.4093779 2.5125984
OS 6.4040854 2.5161347
OS 6.3978425 2.5173765
OE
OB 6.3988425 2.4693765 H
OS 6.3925996 2.4681347
OS 6.3873071 2.4645984
OS 6.3837708 2.4593059
OS 6.382529 2.453063
OS 6.3837708 2.4468201
OS 6.3873071 2.4415276
OS 6.3925996 2.4379913
OS 6.3988425 2.4367495
OS 6.4050854 2.4379913
OS 6.4103779 2.4415276
OS 6.4139142 2.4468201
OS 6.415156 2.453063
OS 6.4139142 2.4593059
OS 6.4103779 2.4645984
OS 6.4050854 2.4681347
OS 6.3988425 2.4693765
OE
OB 6.6078425 2.1923765 H
OS 6.6015996 2.1911347
OS 6.5963071 2.1875984
OS 6.5927708 2.1823059
OS 6.591529 2.176063
OS 6.5927708 2.1698201
OS 6.5963071 2.1645276
OS 6.6015996 2.1609913
OS 6.6078425 2.1597495
OS 6.6140854 2.1609913
OS 6.6193779 2.1645276
OS 6.6229142 2.1698201
OS 6.624156 2.176063
OS 6.6229142 2.1823059
OS 6.6193779 2.1875984
OS 6.6140854 2.1911347
OS 6.6078425 2.1923765
OE
OB 6.9498425 2.1113765 H
OS 6.9435996 2.1101347
OS 6.9383071 2.1065984
OS 6.9347708 2.1013059
OS 6.933529 2.095063
OS 6.9347708 2.0888201
OS 6.9383071 2.0835276
OS 6.9435996 2.0799913
OS 6.9498425 2.0787495
OS 6.9560854 2.0799913
OS 6.9613779 2.0835276
OS 6.9649142 2.0888201
OS 6.966156 2.095063
OS 6.9649142 2.1013059
OS 6.9613779 2.1065984
OS 6.9560854 2.1101347
OS 6.9498425 2.1113765
OE
OB 6.9744094 1.9562741 H
OS 6.9681665 1.9550323
OS 6.962874 1.951496
OS 6.9593377 1.9462035
OS 6.9580959 1.9399606
OS 6.9593377 1.9337177
OS 6.962874 1.9284252
OS 6.9681665 1.9248889
OS 6.9744094 1.9236471
OS 6.9806523 1.9248889
OS 6.9859448 1.9284252
OS 6.9894811 1.9337177
OS 6.9907229 1.9399606
OS 6.9894811 1.9462035
OS 6.9859448 1.951496
OS 6.9806523 1.9550323
OS 6.9744094 1.9562741
OE
SE
S P 0
OB 6.5048425 4.151063 I
OS 6.5048425 4.1113541
OS 6.5034033 4.1066097
OS 6.5021086 4.0934646
OS 6.5034033 4.0803195
OS 6.5048425 4.0755751
OS 6.5048425 3.720276
OS 6.5012984 3.7167489
OS 6.3140453 3.7176536
OS 6.3133492 3.7175186
OS 6.3126403 3.7175386
OS 6.3118019 3.7172186
OS 6.3109209 3.7170478
OS 6.3103292 3.7166565
OS 6.3096669 3.7164038
OS 6.3090152 3.7157878
OS 6.3082661 3.7152925
OS 6.3078691 3.7147045
OS 6.307354 3.7142176
OS 6.3062605 3.7126768
OS 6.3010854 3.7161347
OS 6.2948425 3.7173765
OS 6.2885996 3.7161347
OS 6.2866976 3.7148638
OS 6.2815978 3.7154215
OS 6.2808743 3.7159099
OS 6.2802495 3.7165194
OS 6.2795679 3.7167919
OS 6.2789601 3.7172022
OS 6.2781054 3.7173765
OS 6.2772942 3.7177008
OS 6.2765603 3.7176917
OS 6.2758418 3.7178382
OS 5.9898819 3.7192196
OS 5.9898625 3.7192158
OS 5.9898425 3.7192198
OS 5.988292 3.7189113
OS 5.9867575 3.7186138
OS 5.9867407 3.7186027
OS 5.9867211 3.7185988
OS 5.9854185 3.7177285
OS 5.9841027 3.7168585
OS 5.9840914 3.7168418
OS 5.9840748 3.7168307
OS 5.8740748 3.6068307
OS 5.8723067 3.6041845
OS 5.8716857 3.601063
OS 5.8716858 3.6010625
OS 5.8716858 3.4510635
OS 5.8716857 3.451063
OS 5.8723067 3.4479416
OS 5.8740748 3.4452953
OS 5.8740751 3.4452951
OS 6.3266858 2.9926843
OS 6.3266858 2.3979063
OS 6.3048425 2.376063
OS 6.2895075 2.376063
OS 6.2874038 2.381063
OS 6.2899142 2.3848201
OS 6.291156 2.391063
OS 6.2899142 2.3973059
OS 6.2863779 2.4025984
OS 6.2810854 2.4061347
OS 6.2748425 2.4073765
OS 6.2685996 2.4061347
OS 6.2633071 2.4025984
OS 6.2597708 2.3973059
OS 6.258529 2.391063
OS 6.2597708 2.3848201
OS 6.2622812 2.381063
OS 6.2601775 2.376063
OS 4.6398425 2.376063
OS 4.3498425 2.666063
OS 4.3498425 2.7125017
OS 4.3513779 2.7135276
OS 4.3549142 2.7188201
OS 4.356156 2.725063
OS 4.3549142 2.7313059
OS 4.3513779 2.7365984
OS 4.3498425 2.7376243
OS 4.3498425 3.1334869
OS 4.350156 3.135063
OS 4.3498425 3.1366391
OS 4.3498425 3.781063
OS 4.1848425 3.946063
OS 4.0648425 3.946063
OS 3.9370776 3.8182981
OS 3.8403307 3.8182981
OS 3.8360854 3.8211347
OS 3.8298425 3.8223765
OS 3.8235996 3.8211347
OS 3.8183071 3.8175984
OS 3.8147708 3.8123059
OS 3.813529 3.806063
OS 3.8147708 3.7998201
OS 3.8183071 3.7945276
OS 3.8235996 3.7909913
OS 3.8298425 3.7897495
OS 3.8360854 3.7909913
OS 3.8403307 3.7938279
OS 3.9060745 3.7938279
OS 3.907988 3.7892085
OS 3.8048425 3.686063
OS 2.7098425 3.686063
OS 2.6959296 3.6721501
OS 2.6913778 3.6725985
OS 2.6860854 3.6761347
OS 2.6798425 3.6773765
OS 2.6735996 3.6761347
OS 2.6683071 3.6725984
OS 2.6647708 3.6673059
OS 2.663529 3.661063
OS 2.6647708 3.6548201
OS 2.668307 3.6495277
OS 2.6687554 3.6449759
OS 2.3498425 3.326063
OS 2.3498425 3.3091102
OS 2.2854055 3.3091102
OS 2.2854055 3.2490158
OS 2.3498425 3.2490158
OS 2.3498425 3.2303701
OS 2.2854055 3.2303701
OS 2.2854055 3.1702757
OS 2.3498425 3.1702757
OS 2.3498425 3.1516299
OS 2.2854055 3.1516299
OS 2.2854055 3.0915355
OS 2.3498425 3.0915355
OS 2.3498425 2.718063
OS 2.0148425 2.718063
OS 2.0148425 3.8035017
OS 2.0163779 3.8045276
OS 2.0199142 3.8098201
OS 2.021156 3.816063
OS 2.0210101 3.8167964
OS 2.0215918 3.8177387
OS 2.0253427 3.8206446
OS 2.0298425 3.8197495
OS 2.0360854 3.8209913
OS 2.0413779 3.8245276
OS 2.0449142 3.8298201
OS 2.046156 3.836063
OS 2.0449142 3.8423059
OS 2.0413779 3.8475984
OS 2.0360854 3.8511347
OS 2.0298425 3.8523765
OS 2.0235996 3.8511347
OS 2.0198425 3.8486243
OS 2.0148425 3.850728
OS 2.0148425 4.0287647
OS 2.0198425 4.0311322
OS 2.0254039 4.0268648
OS 2.0340397 4.0232878
OS 2.0433071 4.0220677
OS 2.0525745 4.0232878
OS 2.0612103 4.0268648
OS 2.068626 4.0325551
OS 2.0743163 4.0399708
OS 2.0778933 4.0486066
OS 2.0791134 4.057874
OS 2.0778933 4.0671414
OS 2.0743163 4.0757772
OS 2.068626 4.0831929
OS 2.0612103 4.0888832
OS 2.0525745 4.0924602
OS 2.0433071 4.0936803
OS 2.0340397 4.0924602
OS 2.0254039 4.0888832
OS 2.0198425 4.0846158
OS 2.0148425 4.0869833
OS 2.0148425 4.1287647
OS 2.0198425 4.1311322
OS 2.0254039 4.1268648
OS 2.0340397 4.1232878
OS 2.0433071 4.1220677
OS 2.0525745 4.1232878
OS 2.0612103 4.1268648
OS 2.068626 4.1325551
OS 2.0743163 4.1399708
OS 2.0778933 4.1486066
OS 2.0791134 4.157874
OS 2.0778933 4.1671414
OS 2.0743163 4.1757772
OS 2.068626 4.1831929
OS 2.0612103 4.1888832
OS 2.0525745 4.1924602
OS 2.0433071 4.1936803
OS 2.0340397 4.1924602
OS 2.0254039 4.1888832
OS 2.0198425 4.1846158
OS 2.0148425 4.1869833
OS 2.0148425 4.222374
OS 2.0788071 4.222374
OS 2.0788071 4.293374
OS 2.0148425 4.293374
OS 2.0148425 4.326063
OS 6.3298425 4.326063
OS 6.5048425 4.151063
OE
OB 3.3958425 4.2383765 H
OS 3.3895996 4.2371347
OS 3.3843071 4.2335984
OS 3.3807708 4.2283059
OS 3.379529 4.222063
OS 3.3807708 4.2158201
OS 3.3843071 4.2105276
OS 3.3895996 4.2069913
OS 3.3958425 4.2057495
OS 3.4020854 4.2069913
OS 3.4073779 4.2105276
OS 3.4109142 4.2158201
OS 3.412156 4.222063
OS 3.4109142 4.2283059
OS 3.4073779 4.2335984
OS 3.4020854 4.2371347
OS 3.3958425 4.2383765
OE
OB 2.8888425 4.2373765 H
OS 2.8825996 4.2361347
OS 2.8773071 4.2325984
OS 2.8737708 4.2273059
OS 2.872529 4.221063
OS 2.8737708 4.2148201
OS 2.8773071 4.2095276
OS 2.8825996 4.2059913
OS 2.8888425 4.2047495
OS 2.8950854 4.2059913
OS 2.9003779 4.2095276
OS 2.9039142 4.2148201
OS 2.905156 4.221063
OS 2.9039142 4.2273059
OS 2.9003779 4.2325984
OS 2.8950854 4.2361347
OS 2.8888425 4.2373765
OE
OB 2.2908425 4.2333765 H
OS 2.2845996 4.2321347
OS 2.2793071 4.2285984
OS 2.2757708 4.2233059
OS 2.274529 4.217063
OS 2.2757708 4.2108201
OS 2.2793071 4.2055276
OS 2.2845996 4.2019913
OS 2.2908425 4.2007495
OS 2.2970854 4.2019913
OS 2.3023779 4.2055276
OS 2.3059142 4.2108201
OS 2.307156 4.217063
OS 2.3059142 4.2233059
OS 2.3023779 4.2285984
OS 2.2970854 4.2321347
OS 2.2908425 4.2333765
OE
OB 4.3878425 4.2223765 H
OS 4.3815996 4.2211347
OS 4.3763071 4.2175984
OS 4.3727708 4.2123059
OS 4.371529 4.206063
OS 4.3727708 4.1998201
OS 4.3763071 4.1945276
OS 4.3815996 4.1909913
OS 4.3878425 4.1897495
OS 4.3940854 4.1909913
OS 4.3993779 4.1945276
OS 4.4029142 4.1998201
OS 4.404156 4.206063
OS 4.4029142 4.2123059
OS 4.3993779 4.2175984
OS 4.3940854 4.2211347
OS 4.3878425 4.2223765
OE
OB 4.9108425 4.2193765 H
OS 4.9045996 4.2181347
OS 4.8993071 4.2145984
OS 4.8957708 4.2093059
OS 4.894529 4.203063
OS 4.8957708 4.1968201
OS 4.8993071 4.1915276
OS 4.9045996 4.1879913
OS 4.9108425 4.1867495
OS 4.9170854 4.1879913
OS 4.9223779 4.1915276
OS 4.9259142 4.1968201
OS 4.927156 4.203063
OS 4.9259142 4.2093059
OS 4.9223779 4.2145984
OS 4.9170854 4.2181347
OS 4.9108425 4.2193765
OE
OB 3.9580709 4.1520014 H
OS 3.9513575 4.1511176
OS 3.9451017 4.1485263
OS 3.9397297 4.1444042
OS 3.9356076 4.1390322
OS 3.9330163 4.1327764
OS 3.9321325 4.126063
OS 3.9330163 4.1193496
OS 3.9356076 4.1130938
OS 3.9397297 4.1077218
OS 3.9451017 4.1035997
OS 3.9513575 4.1010084
OS 3.9580709 4.1001246
OS 3.9647843 4.1010084
OS 3.9710401 4.1035997
OS 3.9764121 4.1077218
OS 3.9805342 4.1130938
OS 3.9831255 4.1193496
OS 3.9840093 4.126063
OS 3.9831255 4.1327764
OS 3.9805342 4.1390322
OS 3.9764121 4.1444042
OS 3.9710401 4.1485263
OS 3.9647843 4.1511176
OS 3.9580709 4.1520014
OE
OB 3.7848425 4.1520014 H
OS 3.7781291 4.1511176
OS 3.7718733 4.1485263
OS 3.7665013 4.1444042
OS 3.7623792 4.1390322
OS 3.7597879 4.1327764
OS 3.7589041 4.126063
OS 3.7597879 4.1193496
OS 3.7623792 4.1130938
OS 3.7665013 4.1077218
OS 3.7718733 4.1035997
OS 3.7781291 4.1010084
OS 3.7848425 4.1001246
OS 3.7915559 4.1010084
OS 3.7978117 4.1035997
OS 3.8031837 4.1077218
OS 3.8073058 4.1130938
OS 3.8098971 4.1193496
OS 3.8107809 4.126063
OS 3.8098971 4.1327764
OS 3.8073058 4.1390322
OS 3.8031837 4.1444042
OS 3.7978117 4.1485263
OS 3.7915559 4.1511176
OS 3.7848425 4.1520014
OE
OB 4.7547119 4.1322459 H
OS 4.748469 4.1310041
OS 4.7431765 4.1274678
OS 4.7396402 4.1221753
OS 4.7383984 4.1159324
OS 4.7396402 4.1096895
OS 4.7431765 4.104397
OS 4.748469 4.1008607
OS 4.7547119 4.0996189
OS 4.7609548 4.1008607
OS 4.7662473 4.104397
OS 4.7697836 4.1096895
OS 4.7710254 4.1159324
OS 4.7697836 4.1221753
OS 4.7662473 4.1274678
OS 4.7609548 4.1310041
OS 4.7547119 4.1322459
OE
OB 2.1460663 4.1201044 H
OS 2.1398234 4.1188626
OS 2.1345309 4.1153263
OS 2.1309946 4.1100338
OS 2.1297528 4.1037909
OS 2.1309946 4.097548
OS 2.1345309 4.0922555
OS 2.1398234 4.0887192
OS 2.1460663 4.0874774
OS 2.1523092 4.0887192
OS 2.1576017 4.0922555
OS 2.161138 4.097548
OS 2.1623798 4.1037909
OS 2.161138 4.1100338
OS 2.1576017 4.1153263
OS 2.1523092 4.1188626
OS 2.1460663 4.1201044
OE
OB 5.2670079 4.1052111 H
OS 5.260765 4.1039693
OS 5.2554725 4.100433
OS 5.2519362 4.0951405
OS 5.2506944 4.0888976
OS 5.2519362 4.0826547
OS 5.2554725 4.0773622
OS 5.260765 4.0738259
OS 5.2670079 4.0725841
OS 5.2732508 4.0738259
OS 5.2785433 4.0773622
OS 5.2820796 4.0826547
OS 5.2833214 4.0888976
OS 5.2820796 4.0951405
OS 5.2785433 4.100433
OS 5.2732508 4.1039693
OS 5.2670079 4.1052111
OE
OB 2.253937 4.1029277 H
OS 2.2476941 4.1016859
OS 2.2424016 4.0981496
OS 2.2388653 4.0928571
OS 2.2376235 4.0866142
OS 2.2388653 4.0803713
OS 2.2424016 4.0750788
OS 2.2476941 4.0715425
OS 2.253937 4.0703007
OS 2.2601799 4.0715425
OS 2.2654724 4.0750788
OS 2.2690087 4.0803713
OS 2.2702505 4.0866142
OS 2.2690087 4.0928571
OS 2.2654724 4.0981496
OS 2.2601799 4.1016859
OS 2.253937 4.1029277
OE
OB 3.5048425 4.1023765 H
OS 3.4985996 4.1011347
OS 3.4933071 4.0975984
OS 3.4897708 4.0923059
OS 3.488529 4.086063
OS 3.4897708 4.0798201
OS 3.4933071 4.0745276
OS 3.4985996 4.0709913
OS 3.5048425 4.0697495
OS 3.5110854 4.0709913
OS 3.5163779 4.0745276
OS 3.5199142 4.0798201
OS 3.521156 4.086063
OS 3.5199142 4.0923059
OS 3.5163779 4.0975984
OS 3.5110854 4.1011347
OS 3.5048425 4.1023765
OE
OB 3.2948425 4.1274482 H
OS 3.2841414 4.1260394
OS 3.2741696 4.1219089
OS 3.2656066 4.1153383
OS 3.259036 4.1067753
OS 3.2549055 4.0968035
OS 3.2534967 4.0861024
OS 3.2549055 4.0754013
OS 3.259036 4.0654295
OS 3.2656066 4.0568665
OS 3.2741696 4.0502959
OS 3.2841414 4.0461654
OS 3.2948425 4.0447566
OS 3.3055436 4.0461654
OS 3.3155154 4.0502959
OS 3.3240784 4.0568665
OS 3.330649 4.0654295
OS 3.3347795 4.0754013
OS 3.3361883 4.0861024
OS 3.3347795 4.0968035
OS 3.330649 4.1067753
OS 3.3240784 4.1153383
OS 3.3155154 4.1219089
OS 3.3055436 4.1260394
OS 3.2948425 4.1274482
OE
OB 2.9948425 4.1274482 H
OS 2.9841414 4.1260394
OS 2.9741696 4.1219089
OS 2.9656066 4.1153383
OS 2.959036 4.1067753
OS 2.9549055 4.0968035
OS 2.9534967 4.0861024
OS 2.9549055 4.0754013
OS 2.959036 4.0654295
OS 2.9656066 4.0568665
OS 2.9741696 4.0502959
OS 2.9841414 4.0461654
OS 2.9948425 4.0447566
OS 3.0055436 4.0461654
OS 3.0155154 4.0502959
OS 3.0240784 4.0568665
OS 3.030649 4.0654295
OS 3.0347795 4.0754013
OS 3.0361883 4.0861024
OS 3.0347795 4.0968035
OS 3.030649 4.1067753
OS 3.0240784 4.1153383
OS 3.0155154 4.1219089
OS 3.0055436 4.1260394
OS 2.9948425 4.1274482
OE
OB 3.7778425 4.0393765 H
OS 3.7715996 4.0381347
OS 3.7663071 4.0345984
OS 3.7627708 4.0293059
OS 3.761529 4.023063
OS 3.7627708 4.0168201
OS 3.7663071 4.0115276
OS 3.7715996 4.0079913
OS 3.7778425 4.0067495
OS 3.7840854 4.0079913
OS 3.7893779 4.0115276
OS 3.7929142 4.0168201
OS 3.794156 4.023063
OS 3.7929142 4.0293059
OS 3.7893779 4.0345984
OS 3.7840854 4.0381347
OS 3.7778425 4.0393765
OE
OB 6.1641339 4.1088055 H
OS 6.0755511 4.1088055
OS 6.0619003 4.1070083
OS 6.0491799 4.1017393
OS 6.0382565 4.0933576
OS 6.0298748 4.0824342
OS 6.0246058 4.0697138
OS 6.0228086 4.056063
OS 6.0246058 4.0424122
OS 6.0298748 4.0296918
OS 6.0382565 4.0187684
OS 6.0491799 4.0103867
OS 6.0619003 4.0051177
OS 6.0755511 4.0033205
OS 6.1641339 4.0033205
OS 6.1777847 4.0051177
OS 6.1905051 4.0103867
OS 6.2014285 4.0187684
OS 6.2098102 4.0296918
OS 6.2150792 4.0424122
OS 6.2168764 4.056063
OS 6.2150792 4.0697138
OS 6.2098102 4.0824342
OS 6.2014285 4.0933576
OS 6.1905051 4.1017393
OS 6.1777847 4.1070083
OS 6.1641339 4.1088055
OE
OB 2.3533464 4.03403 H
OS 2.3471035 4.0327882
OS 2.341811 4.0292519
OS 2.3382747 4.0239594
OS 2.3370329 4.0177165
OS 2.3382747 4.0114736
OS 2.341811 4.0061811
OS 2.3471035 4.0026448
OS 2.3533464 4.001403
OS 2.3595893 4.0026448
OS 2.3648818 4.0061811
OS 2.3684181 4.0114736
OS 2.3696599 4.0177165
OS 2.3684181 4.0239594
OS 2.3648818 4.0292519
OS 2.3595893 4.0327882
OS 2.3533464 4.03403
OE
OB 5.7234252 4.0832969 H
OS 5.7084897 4.0813306
OS 5.6945721 4.0755657
OS 5.6826207 4.0663951
OS 5.6734501 4.0544438
OS 5.6676852 4.0405261
OS 5.6657189 4.0255906
OS 5.6676852 4.0106551
OS 5.6734501 3.9967374
OS 5.6826207 3.9847861
OS 5.6945721 3.9756155
OS 5.7084897 3.9698506
OS 5.7234252 3.9678843
OS 5.7383607 3.9698506
OS 5.7522783 3.9756155
OS 5.7642297 3.9847861
OS 5.7734003 3.9967374
OS 5.7791652 4.0106551
OS 5.7811315 4.0255906
OS 5.7791652 4.0405261
OS 5.7734003 4.0544438
OS 5.7642297 4.0663951
OS 5.7522783 4.0755657
OS 5.7383607 4.0813306
OS 5.7234252 4.0832969
OE
OB 2.0848425 3.9123765 H
OS 2.0785996 3.9111347
OS 2.0733071 3.9075984
OS 2.0697708 3.9023059
OS 2.068529 3.896063
OS 2.0697708 3.8898201
OS 2.0699331 3.8895773
OS 2.0663282 3.8859724
OS 2.0660854 3.8861347
OS 2.0598425 3.8873765
OS 2.0535996 3.8861347
OS 2.0483071 3.8825984
OS 2.0447708 3.8773059
OS 2.043529 3.871063
OS 2.0447708 3.8648201
OS 2.0483071 3.8595276
OS 2.0535996 3.8559913
OS 2.0598425 3.8547495
OS 2.0660854 3.8559913
OS 2.0713779 3.8595276
OS 2.0749142 3.8648201
OS 2.076156 3.871063
OS 2.0749142 3.8773059
OS 2.0747519 3.8775487
OS 2.0783568 3.8811536
OS 2.0785996 3.8809913
OS 2.0848425 3.8797495
OS 2.0910854 3.8809913
OS 2.0963779 3.8845276
OS 2.0999142 3.8898201
OS 2.101156 3.896063
OS 2.0999142 3.9023059
OS 2.0963779 3.9075984
OS 2.0910854 3.9111347
OS 2.0848425 3.9123765
OE
OB 5.9348031 4.0349866 H
OS 5.9211523 4.0331894
OS 5.9084318 4.0279204
OS 5.8975085 4.0195387
OS 5.8891268 4.0086153
OS 5.8838578 3.9958949
OS 5.8820606 3.9822441
OS 5.8820606 3.8936613
OS 5.8838578 3.8800105
OS 5.8891268 3.8672901
OS 5.8975085 3.8563667
OS 5.9084318 3.847985
OS 5.9211523 3.842716
OS 5.9348031 3.8409188
OS 5.9484539 3.842716
OS 5.9611744 3.847985
OS 5.9720977 3.8563667
OS 5.9804794 3.8672901
OS 5.9857484 3.8800105
OS 5.9875456 3.8936613
OS 5.9875456 3.9822441
OS 5.9857484 3.9958949
OS 5.9804794 4.0086153
OS 5.9720977 4.0195387
OS 5.9611744 4.0279204
OS 5.9484539 4.0331894
OS 5.9348031 4.0349866
OE
OB 3.6998425 3.8523765 H
OS 3.6935996 3.8511347
OS 3.6883071 3.8475984
OS 3.6847708 3.8423059
OS 3.683529 3.836063
OS 3.6847708 3.8298201
OS 3.6883071 3.8245276
OS 3.6935996 3.8209913
OS 3.6998425 3.8197495
OS 3.7060854 3.8209913
OS 3.7113779 3.8245276
OS 3.7149142 3.8298201
OS 3.716156 3.836063
OS 3.7149142 3.8423059
OS 3.7113779 3.8475984
OS 3.7060854 3.8511347
OS 3.6998425 3.8523765
OE
OB 3.0148425 3.8473765 H
OS 3.0085996 3.8461347
OS 3.0033071 3.8425984
OS 2.9997708 3.8373059
OS 2.998529 3.831063
OS 2.9997708 3.8248201
OS 3.0033071 3.8195276
OS 3.0085996 3.8159913
OS 3.0148425 3.8147495
OS 3.0210854 3.8159913
OS 3.0263779 3.8195276
OS 3.0299142 3.8248201
OS 3.031156 3.831063
OS 3.0299142 3.8373059
OS 3.0263779 3.8425984
OS 3.0210854 3.8461347
OS 3.0148425 3.8473765
OE
OB 5.7234252 3.9021945 H
OS 5.7084897 3.9002282
OS 5.6945721 3.8944633
OS 5.6826207 3.8852927
OS 5.6734501 3.8733414
OS 5.6676852 3.8594237
OS 5.6657189 3.8444882
OS 5.6676852 3.8295527
OS 5.6734501 3.815635
OS 5.6826207 3.8036837
OS 5.6945721 3.7945131
OS 5.7084897 3.7887482
OS 5.7234252 3.7867819
OS 5.7383607 3.7887482
OS 5.7522783 3.7945131
OS 5.7642297 3.8036837
OS 5.7734003 3.815635
OS 5.7791652 3.8295527
OS 5.7811315 3.8444882
OS 5.7791652 3.8594237
OS 5.7734003 3.8733414
OS 5.7642297 3.8852927
OS 5.7522783 3.8944633
OS 5.7383607 3.9002282
OS 5.7234252 3.9021945
OE
OB 3.2698425 3.8043765 H
OS 3.2635996 3.8031347
OS 3.2583071 3.7995984
OS 3.2547708 3.7943059
OS 3.253529 3.788063
OS 3.2547708 3.7818201
OS 3.2583071 3.7765276
OS 3.2635996 3.7729913
OS 3.2698425 3.7717495
OS 3.2760854 3.7729913
OS 3.2813779 3.7765276
OS 3.2849142 3.7818201
OS 3.286156 3.788063
OS 3.2849142 3.7943059
OS 3.2813779 3.7995984
OS 3.2760854 3.8031347
OS 3.2698425 3.8043765
OE
OB 2.8608425 3.8033765 H
OS 2.8545996 3.8021347
OS 2.8493071 3.7985984
OS 2.8457708 3.7933059
OS 2.844529 3.787063
OS 2.8457708 3.7808201
OS 2.8493071 3.7755276
OS 2.8545996 3.7719913
OS 2.8608425 3.7707495
OS 2.8670854 3.7719913
OS 2.8723779 3.7755276
OS 2.8759142 3.7808201
OS 2.877156 3.787063
OS 2.8759142 3.7933059
OS 2.8723779 3.7985984
OS 2.8670854 3.8021347
OS 2.8608425 3.8033765
OE
OB 6.1690551 3.8775488 H
OS 6.0706299 3.8775488
OS 6.0556944 3.8755825
OS 6.0417767 3.8698176
OS 6.0298254 3.860647
OS 6.0206548 3.8486956
OS 6.0148899 3.834778
OS 6.0129236 3.8198425
OS 6.0148899 3.804907
OS 6.0206548 3.7909894
OS 6.0298254 3.779038
OS 6.0417767 3.7698674
OS 6.0556944 3.7641025
OS 6.0706299 3.7621362
OS 6.1690551 3.7621362
OS 6.1839906 3.7641025
OS 6.1979083 3.7698674
OS 6.2098596 3.779038
OS 6.2190302 3.7909894
OS 6.2247951 3.804907
OS 6.2267614 3.8198425
OS 6.2247951 3.834778
OS 6.2190302 3.8486956
OS 6.2098596 3.860647
OS 6.1979083 3.8698176
OS 6.1839906 3.8755825
OS 6.1690551 3.8775488
OE
OB 3.8308425 3.7783765 H
OS 3.8245996 3.7771347
OS 3.8193071 3.7735984
OS 3.8157708 3.7683059
OS 3.814529 3.762063
OS 3.8157708 3.7558201
OS 3.8193071 3.7505276
OS 3.8245996 3.7469913
OS 3.8308425 3.7457495
OS 3.8370854 3.7469913
OS 3.8423779 3.7505276
OS 3.8459142 3.7558201
OS 3.847156 3.762063
OS 3.8459142 3.7683059
OS 3.8423779 3.7735984
OS 3.8370854 3.7771347
OS 3.8308425 3.7783765
OE
OB 2.531398 3.962003 H
OS 2.5144508 3.9606692
OS 2.497921 3.9567008
OS 2.4822154 3.9501953
OS 2.4677209 3.941313
OS 2.4547943 3.9302727
OS 2.443754 3.9173461
OS 2.4348717 3.9028516
OS 2.4283662 3.887146
OS 2.4243978 3.8706162
OS 2.423064 3.853669
OS 2.4243978 3.8367218
OS 2.4283662 3.820192
OS 2.4348717 3.8044864
OS 2.443754 3.7899919
OS 2.4547943 3.7770653
OS 2.4677209 3.766025
OS 2.4822154 3.7571427
OS 2.497921 3.7506372
OS 2.5144508 3.7466688
OS 2.531398 3.745335
OS 2.5483452 3.7466688
OS 2.564875 3.7506372
OS 2.5805806 3.7571427
OS 2.5950751 3.766025
OS 2.6080017 3.7770653
OS 2.619042 3.7899919
OS 2.6279243 3.8044864
OS 2.6344298 3.820192
OS 2.6383982 3.8367218
OS 2.639732 3.853669
OS 2.6383982 3.8706162
OS 2.6344298 3.887146
OS 2.6279243 3.9028516
OS 2.619042 3.9173461
OS 2.6080017 3.9302727
OS 2.5950751 3.941313
OS 2.5805806 3.9501953
OS 2.564875 3.9567008
OS 2.5483452 3.9606692
OS 2.531398 3.962003
OE
OB 3.6998425 3.7673765 H
OS 3.6935996 3.7661347
OS 3.6883071 3.7625984
OS 3.6847708 3.7573059
OS 3.683529 3.751063
OS 3.6847708 3.7448201
OS 3.6883071 3.7395276
OS 3.6935996 3.7359913
OS 3.6998425 3.7347495
OS 3.7060854 3.7359913
OS 3.7113779 3.7395276
OS 3.7149142 3.7448201
OS 3.716156 3.751063
OS 3.7149142 3.7573059
OS 3.7113779 3.7625984
OS 3.7060854 3.7661347
OS 3.6998425 3.7673765
OE
OB 2.9933858 3.7673765 H
OS 2.9871429 3.7661347
OS 2.9818504 3.7625984
OS 2.9783141 3.7573059
OS 2.9770723 3.751063
OS 2.9783141 3.7448201
OS 2.9818504 3.7395276
OS 2.9871429 3.7359913
OS 2.9933858 3.7347495
OS 2.9996287 3.7359913
OS 3.0049212 3.7395276
OS 3.0084575 3.7448201
OS 3.0096993 3.751063
OS 3.0084575 3.7573059
OS 3.0049212 3.7625984
OS 2.9996287 3.7661347
OS 2.9933858 3.7673765
OE
OB 2.2588425 3.7573765 H
OS 2.2525996 3.7561347
OS 2.2473071 3.7525984
OS 2.2437708 3.7473059
OS 2.242529 3.741063
OS 2.2437708 3.7348201
OS 2.2473071 3.7295276
OS 2.2525996 3.7259913
OS 2.2588425 3.7247495
OS 2.2650854 3.7259913
OS 2.2703779 3.7295276
OS 2.2739142 3.7348201
OS 2.275156 3.741063
OS 2.2739142 3.7473059
OS 2.2703779 3.7525984
OS 2.2650854 3.7561347
OS 2.2588425 3.7573765
OE
OB 2.1398425 3.7543765 H
OS 2.1335996 3.7531347
OS 2.1283071 3.7495984
OS 2.1247708 3.7443059
OS 2.123529 3.738063
OS 2.1247708 3.7318201
OS 2.1283071 3.7265276
OS 2.1335996 3.7229913
OS 2.1398425 3.7217495
OS 2.1460854 3.7229913
OS 2.1513779 3.7265276
OS 2.1549142 3.7318201
OS 2.156156 3.738063
OS 2.1549142 3.7443059
OS 2.1513779 3.7495984
OS 2.1460854 3.7531347
OS 2.1398425 3.7543765
OE
OB 2.7248425 3.7453765 H
OS 2.7185996 3.7441347
OS 2.7133071 3.7405984
OS 2.7097708 3.7353059
OS 2.708529 3.729063
OS 2.7097708 3.7228201
OS 2.7133071 3.7175276
OS 2.7185996 3.7139913
OS 2.7248425 3.7127495
OS 2.7310854 3.7139913
OS 2.7363779 3.7175276
OS 2.7399142 3.7228201
OS 2.741156 3.729063
OS 2.7399142 3.7353059
OS 2.7363779 3.7405984
OS 2.7310854 3.7441347
OS 2.7248425 3.7453765
OE
OB 2.4223425 3.6247884 H
OS 2.4133837 3.6230064
OS 2.4057888 3.6179317
OS 2.4007141 3.6103368
OS 2.3989321 3.601378
OS 2.4007141 3.5924192
OS 2.4057888 3.5848243
OS 2.4133837 3.5797496
OS 2.4223425 3.5779676
OS 2.4313013 3.5797496
OS 2.4388962 3.5848243
OS 2.4439709 3.5924192
OS 2.4457529 3.601378
OS 2.4439709 3.6103368
OS 2.4388962 3.6179317
OS 2.4313013 3.6230064
OS 2.4223425 3.6247884
OE
OB 5.7338425 3.5723765 H
OS 5.7275996 3.5711347
OS 5.7223071 3.5675984
OS 5.7187708 3.5623059
OS 5.717529 3.556063
OS 5.7187708 3.5498201
OS 5.7223071 3.5445276
OS 5.7275996 3.5409913
OS 5.7338425 3.5397495
OS 5.7400854 3.5409913
OS 5.7453779 3.5445276
OS 5.7489142 3.5498201
OS 5.750156 3.556063
OS 5.7489142 3.5623059
OS 5.7453779 3.5675984
OS 5.7400854 3.5711347
OS 5.7338425 3.5723765
OE
OB 5.6768425 3.5623765 H
OS 5.6705996 3.5611347
OS 5.6653071 3.5575984
OS 5.6617708 3.5523059
OS 5.660529 3.546063
OS 5.6617708 3.5398201
OS 5.6653071 3.5345276
OS 5.6705996 3.5309913
OS 5.6768425 3.5297495
OS 5.6830854 3.5309913
OS 5.6883779 3.5345276
OS 5.6919142 3.5398201
OS 5.693156 3.546063
OS 5.6919142 3.5523059
OS 5.6883779 3.5575984
OS 5.6830854 3.5611347
OS 5.6768425 3.5623765
OE
OB 2.4348425 3.5623765 H
OS 2.4285996 3.5611347
OS 2.4233071 3.5575984
OS 2.4197708 3.5523059
OS 2.418529 3.546063
OS 2.4197708 3.5398201
OS 2.4233071 3.5345276
OS 2.4285996 3.5309913
OS 2.4348425 3.5297495
OS 2.4410854 3.5309913
OS 2.4463779 3.5345276
OS 2.4499142 3.5398201
OS 2.451156 3.546063
OS 2.4499142 3.5523059
OS 2.4463779 3.5575984
OS 2.4410854 3.5611347
OS 2.4348425 3.5623765
OE
OB 2.2548425 3.5523765 H
OS 2.2485996 3.5511347
OS 2.2433071 3.5475984
OS 2.2397708 3.5423059
OS 2.238529 3.536063
OS 2.2397708 3.5298201
OS 2.2424883 3.5257531
OS 2.2396399 3.5214222
OS 2.2348425 3.5223765
OS 2.2285996 3.5211347
OS 2.2233071 3.5175984
OS 2.2197708 3.5123059
OS 2.218529 3.506063
OS 2.2197708 3.4998201
OS 2.2233071 3.4945276
OS 2.2285996 3.4909913
OS 2.2348425 3.4897495
OS 2.2410854 3.4909913
OS 2.2463779 3.4945276
OS 2.2499142 3.4998201
OS 2.251156 3.506063
OS 2.2499142 3.5123059
OS 2.2471967 3.5163729
OS 2.2500451 3.5207038
OS 2.2548425 3.5197495
OS 2.2610854 3.5209913
OS 2.2663779 3.5245276
OS 2.2699142 3.5298201
OS 2.271156 3.536063
OS 2.2699142 3.5423059
OS 2.2663779 3.5475984
OS 2.2610854 3.5511347
OS 2.2548425 3.5523765
OE
OB 2.3898425 3.4973765 H
OS 2.3835996 3.4961347
OS 2.3783071 3.4925984
OS 2.3747708 3.4873059
OS 2.373529 3.481063
OS 2.3747708 3.4748201
OS 2.3783071 3.4695276
OS 2.3835996 3.4659913
OS 2.3898425 3.4647495
OS 2.3960854 3.4659913
OS 2.4013779 3.4695276
OS 2.4049142 3.4748201
OS 2.406156 3.481063
OS 2.4049142 3.4873059
OS 2.4013779 3.4925984
OS 2.3960854 3.4961347
OS 2.3898425 3.4973765
OE
OB 2.4223425 3.4673081 H
OS 2.4133837 3.4655261
OS 2.4057888 3.4604514
OS 2.4007141 3.4528565
OS 2.3989321 3.4438977
OS 2.4007141 3.4349389
OS 2.4057888 3.427344
OS 2.4133837 3.4222693
OS 2.4223425 3.4204873
OS 2.4313013 3.4222693
OS 2.4388962 3.427344
OS 2.4439709 3.4349389
OS 2.4457529 3.4438977
OS 2.4439709 3.4528565
OS 2.4388962 3.4604514
OS 2.4313013 3.4655261
OS 2.4223425 3.4673081
OE
OB 2.3215354 3.3773765 H
OS 2.3152925 3.3761347
OS 2.31 3.3725984
OS 2.3064637 3.3673059
OS 2.3052219 3.361063
OS 2.3064637 3.3548201
OS 2.31 3.3495276
OS 2.3152925 3.3459913
OS 2.3215354 3.3447495
OS 2.3277783 3.3459913
OS 2.3330708 3.3495276
OS 2.3366071 3.3548201
OS 2.3378489 3.361063
OS 2.3366071 3.3673059
OS 2.3330708 3.3725984
OS 2.3277783 3.3761347
OS 2.3215354 3.3773765
OE
OB 2.2598425 3.2773765 H
OS 2.2535996 3.2761347
OS 2.2483071 3.2725984
OS 2.2447708 3.2673059
OS 2.243529 3.261063
OS 2.2447708 3.2548201
OS 2.2483071 3.2495276
OS 2.2535996 3.2459913
OS 2.2598425 3.2447495
OS 2.2660854 3.2459913
OS 2.2713779 3.2495276
OS 2.2749142 3.2548201
OS 2.276156 3.261063
OS 2.2749142 3.2673059
OS 2.2713779 3.2725984
OS 2.2660854 3.2761347
OS 2.2598425 3.2773765
OE
OB 2.2058425 3.2163765 H
OS 2.1995996 3.2151347
OS 2.1943071 3.2115984
OS 2.1907708 3.2063059
OS 2.189529 3.200063
OS 2.1907708 3.1938201
OS 2.1943071 3.1885276
OS 2.1995996 3.1849913
OS 2.2058425 3.1837495
OS 2.2120854 3.1849913
OS 2.2173779 3.1885276
OS 2.2209142 3.1938201
OS 2.222156 3.200063
OS 2.2209142 3.2063059
OS 2.2173779 3.2115984
OS 2.2120854 3.2151347
OS 2.2058425 3.2163765
OE
OB 4.4778425 3.1513765 H
OS 4.4715996 3.1501347
OS 4.4663071 3.1465984
OS 4.4627708 3.1413059
OS 4.461529 3.135063
OS 4.4627708 3.1288201
OS 4.4663071 3.1235276
OS 4.4715996 3.1199913
OS 4.4778425 3.1187495
OS 4.4840854 3.1199913
OS 4.4893779 3.1235276
OS 4.4929142 3.1288201
OS 4.494156 3.135063
OS 4.4929142 3.1413059
OS 4.4893779 3.1465984
OS 4.4840854 3.1501347
OS 4.4778425 3.1513765
OE
OB 4.4318425 3.1513765 H
OS 4.4255996 3.1501347
OS 4.4203071 3.1465984
OS 4.4167708 3.1413059
OS 4.415529 3.135063
OS 4.4167708 3.1288201
OS 4.4203071 3.1235276
OS 4.4255996 3.1199913
OS 4.4318425 3.1187495
OS 4.4380854 3.1199913
OS 4.4433779 3.1235276
OS 4.4469142 3.1288201
OS 4.448156 3.135063
OS 4.4469142 3.1413059
OS 4.4433779 3.1465984
OS 4.4380854 3.1501347
OS 4.4318425 3.1513765
OE
OB 6.253937 2.9257623 H
OS 6.2476941 2.9245205
OS 6.2424016 2.9209842
OS 6.2388653 2.9156917
OS 6.2376235 2.9094488
OS 6.2388653 2.9032059
OS 6.2424016 2.8979134
OS 6.2476941 2.8943771
OS 6.253937 2.8931353
OS 6.2601799 2.8943771
OS 6.2654724 2.8979134
OS 6.2690087 2.9032059
OS 6.2702505 2.9094488
OS 6.2690087 2.9156917
OS 6.2654724 2.9209842
OS 6.2601799 2.9245205
OS 6.253937 2.9257623
OE
OB 4.7942913 2.8243844 H
OS 4.7880484 2.8231426
OS 4.7827559 2.8196063
OS 4.7792196 2.8143138
OS 4.7779778 2.8080709
OS 4.7792196 2.801828
OS 4.7827559 2.7965355
OS 4.7880484 2.7929992
OS 4.7942913 2.7917574
OS 4.8005342 2.7929992
OS 4.8058267 2.7965355
OS 4.809363 2.801828
OS 4.8106048 2.8080709
OS 4.809363 2.8143138
OS 4.8058267 2.8196063
OS 4.8005342 2.8231426
OS 4.7942913 2.8243844
OE
OB 5.5781524 2.5349364 H
OS 5.5662745 2.5333726
OS 5.5552061 2.528788
OS 5.5457014 2.5214948
OS 5.5384082 2.5119901
OS 5.5338236 2.5009217
OS 5.5322598 2.4890438
OS 5.5338236 2.4771659
OS 5.5384082 2.4660975
OS 5.5457014 2.4565928
OS 5.5552061 2.4492996
OS 5.5662745 2.444715
OS 5.5781524 2.4431512
OS 5.5900303 2.444715
OS 5.6010987 2.4492996
OS 5.6106034 2.4565928
OS 5.6178966 2.4660975
OS 5.6224812 2.4771659
OS 5.624045 2.4890438
OS 5.6224812 2.5009217
OS 5.6178966 2.5119901
OS 5.6106034 2.5214948
OS 5.6010987 2.528788
OS 5.5900303 2.5333726
OS 5.5781524 2.5349364
OE
OB 6.0048425 2.4503765 H
OS 5.9985996 2.4491347
OS 5.9933071 2.4455984
OS 5.9897708 2.4403059
OS 5.988529 2.434063
OS 5.9897708 2.4278201
OS 5.9933071 2.4225276
OS 5.9985996 2.4189913
OS 6.0048425 2.4177495
OS 6.0110854 2.4189913
OS 6.0163779 2.4225276
OS 6.0199142 2.4278201
OS 6.021156 2.434063
OS 6.0199142 2.4403059
OS 6.0163779 2.4455984
OS 6.0110854 2.4491347
OS 6.0048425 2.4503765
OE
SE
P 0.149508 2.830047 31 P 0 0 ;0=24,1=1
P 0.149508 3.853669 31 P 0 0 ;0=24,1=1
P 0.6538425 1.551063 30 P 0 0 ;0=23,1=1
P 0.6539669 2.5938902 30 P 0 0 ;0=23,1=1
P 0.6548425 0.790063 30 P 0 0 ;0=23,1=1
P 0.6548425 1.314063 30 P 0 0 ;0=23,1=1
P 0.6548425 1.839063 30 P 0 0 ;0=23,1=1
P 0.6548425 2.073063 30 P 0 0 ;0=23,1=1
P 0.6548425 2.365063 30 P 0 0 ;0=23,1=1
P 0.6558425 1.028063 30 P 0 0 ;0=23,1=1
P 0.9370078 2.3179133 30 P 0 0 ;0=23,1=1
P 0.988189 1.7175197 30 P 0 0 ;0=23,1=1
P 0.9901575 0.6870079 30 P 0 0 ;0=23,1=1
P 0.996063 1.1870079 30 P 0 0 ;0=23,1=1
P 0.9968357 2.256036 30 P 0 0 ;0=23,1=1
P 1.0048425 0.906063 30 P 0 0 ;0=23,1=1
P 1.0088425 1.430063 30 P 0 0 ;0=23,1=1
P 1.0098425 1.956063 30 P 0 0 ;0=23,1=1
P 1.0208425 2.481063 30 P 0 0 ;0=23,1=1
P 1.2428425 1.472063 30 P 0 0 ;0=23,1=1
P 1.2488425 2.000063 30 P 0 0 ;0=23,1=1
P 1.2568425 0.942063 30 P 0 0 ;0=23,1=1
P 1.2618425 2.482063 30 P 0 0 ;0=23,1=1
P 1.2948425 4.256063 30 P 0 0 ;0=23,1=1
P 1.3454724 4.1751969 30 P 0 0 ;0=23,1=1
P 1.3937008 1.8169291 30 P 0 0 ;0=23,1=1
P 1.4084645 3.980315 30 P 0 0 ;0=23,1=1
P 1.4408425 3.557063 30 P 0 0 ;0=23,1=1
P 1.4598425 3.147063 30 P 0 0 ;0=23,1=1
P 1.5498425 3.621063 30 P 0 0 ;0=23,1=1
P 1.5578425 4.229063 30 P 0 0 ;0=23,1=1
P 1.5679134 1.2854331 30 P 0 0 ;0=23,1=1
P 1.5682025 2.067703 30 P 0 0 ;0=23,1=1
P 1.5698819 4.1712599 30 P 0 0 ;0=23,1=1
P 1.5748425 3.596063 30 P 0 0 ;0=23,1=1
P 1.6198425 2.121063 30 P 0 0 ;0=23,1=1
P 1.6708425 1.595063 30 P 0 0 ;0=23,1=1
P 1.6708425 1.694063 30 P 0 0 ;0=23,1=1
P 1.6718425 1.399063 30 P 0 0 ;0=23,1=1
P 1.6718425 1.497063 30 P 0 0 ;0=23,1=1
P 1.6718425 1.792063 30 P 0 0 ;0=23,1=1
P 1.6748425 1.989063 30 P 0 0 ;0=23,1=1
P 1.6758425 1.891063 30 P 0 0 ;0=23,1=1
P 1.6918425 4.079063 30 P 0 0 ;0=23,1=1
P 1.7148425 1.595063 30 P 0 0 ;0=23,1=1
P 1.7168425 1.399063 30 P 0 0 ;0=23,1=1
P 1.7188425 1.497063 30 P 0 0 ;0=23,1=1
P 1.7188425 1.792063 30 P 0 0 ;0=23,1=1
P 1.7198425 1.536063 30 P 0 0 ;0=23,1=1
P 1.7218425 1.694063 30 P 0 0 ;0=23,1=1
P 1.7218425 1.890063 30 P 0 0 ;0=23,1=1
P 1.7218425 1.989063 30 P 0 0 ;0=23,1=1
P 1.7268425 4.329374 30 P 0 0 ;0=23,1=1
P 1.7498425 4.110063 30 P 0 0 ;0=23,1=1
P 1.7548425 2.126063 30 P 0 0 ;0=23,1=1
P 1.7548425 3.661063 30 P 0 0 ;0=23,1=1
P 1.7798425 4.156063 30 P 0 0 ;0=23,1=1
P 1.7888425 4.329374 30 P 0 0 ;0=23,1=1
P 1.7978425 0.355063 30 P 0 0 ;0=23,1=1
P 1.7982283 1.3041339 30 P 0 0 ;0=23,1=1
P 1.8227825 1.674003 30 P 0 0 ;0=23,1=1
P 1.8326771 0.2559055 30 P 0 0 ;0=23,1=1
P 1.8326771 0.2874016 30 P 0 0 ;0=23,1=1
P 1.8498425 3.701063 30 P 0 0 ;0=23,1=1
P 1.8523622 0.2559055 30 P 0 0 ;0=23,1=1
P 1.8523622 0.2874016 30 P 0 0 ;0=23,1=1
P 1.8720472 0.2559055 30 P 0 0 ;0=23,1=1
P 1.8720472 0.2874016 30 P 0 0 ;0=23,1=1
P 1.8799377 1.811803 30 P 0 0 ;0=23,1=1
P 1.8848425 2.071063 30 P 0 0 ;0=23,1=1
P 1.8848425 3.601063 30 P 0 0 ;0=23,1=1
P 1.8938425 1.693063 30 P 0 0 ;0=23,1=1
P 1.8973025 1.516523 30 P 0 0 ;0=23,1=1
P 1.9038425 4.018063 30 P 0 0 ;0=23,1=1
P 1.9161425 0.244763 30 P 0 0 ;0=23,1=1
P 2.0048425 1.336063 30 P 0 0 ;0=23,1=1
P 2.0048425 3.816063 30 P 0 0 ;0=23,1=1
P 2.0288425 1.361663 30 P 0 0 ;0=23,1=1
P 2.0298425 3.836063 30 P 0 0 ;0=23,1=1
P 2.0348425 0.246063 30 P 0 0 ;0=23,1=1
P 2.0598425 1.386063 30 P 0 0 ;0=23,1=1
P 2.0598425 3.871063 30 P 0 0 ;0=23,1=1
P 2.0767716 0.2559055 30 P 0 0 ;0=23,1=1
P 2.0767716 0.2874016 30 P 0 0 ;0=23,1=1
P 2.0838425 1.411663 30 P 0 0 ;0=23,1=1
P 2.0848425 3.896063 30 P 0 0 ;0=23,1=1
P 2.1122047 0.2559055 30 P 0 0 ;0=23,1=1
P 2.1122047 0.2874016 30 P 0 0 ;0=23,1=1
P 2.1398425 3.611063 30 P 0 0 ;0=23,1=1
P 2.1398425 3.738063 30 P 0 0 ;0=23,1=1
P 2.1460663 4.1037909 30 P 0 0 ;0=23,1=1
P 2.1468425 2.753063 30 P 0 0 ;0=23,1=1
P 2.1515748 0.2559055 30 P 0 0 ;0=23,1=1
P 2.1515748 0.2874016 30 P 0 0 ;0=23,1=1
P 2.2058425 3.200063 30 P 0 0 ;0=23,1=1
P 2.2068425 1.298063 30 P 0 0 ;0=23,1=1
P 2.2317425 2.584163 30 P 0 0 ;0=23,1=1
P 2.2348425 3.506063 30 P 0 0 ;0=23,1=1
P 2.2523425 2.613563 30 P 0 0 ;0=23,1=1
P 2.2538425 2.279063 30 P 0 0 ;0=23,1=1
P 2.253937 4.0866142 30 P 0 0 ;0=23,1=1
P 2.2548425 3.536063 30 P 0 0 ;0=23,1=1
P 2.2588425 3.741063 30 P 0 0 ;0=23,1=1
P 2.2598425 3.261063 30 P 0 0 ;0=23,1=1
P 2.2720325 2.463873 30 P 0 0 ;0=23,1=1
P 2.2748425 1.506063 30 P 0 0 ;0=23,1=1
P 2.2908425 4.217063 30 P 0 0 ;0=23,1=1
P 2.2998425 1.916063 30 P 0 0 ;0=23,1=1
P 2.3098425 0.246063 30 P 0 0 ;0=23,1=1
P 2.3114125 1.0900094 30 P 0 0 ;0=23,1=1
P 2.3118425 0.934063 30 P 0 0 ;0=23,1=1
P 2.3215354 2.586063 30 P 0 0 ;0=23,1=1
P 2.3215354 3.361063 30 P 0 0 ;0=23,1=1
P 2.3308425 2.215063 30 P 0 0 ;0=23,1=1
P 2.3503937 0.4055118 30 P 0 0 ;0=23,1=1
P 2.3533464 4.0177165 30 P 0 0 ;0=23,1=1
P 2.3848425 1.941063 30 P 0 0 ;0=23,1=1
P 2.3897638 0.4055118 30 P 0 0 ;0=23,1=1
P 2.3898425 3.481063 30 P 0 0 ;0=23,1=1
P 2.394685 2.7204724 30 P 0 0 ;0=23,1=1
P 2.4048425 2.412063 30 P 0 0 ;0=23,1=1
P 2.4098325 0.932053 30 P 0 0 ;0=23,1=1
P 2.4098325 1.088053 30 P 0 0 ;0=23,1=1
P 2.4098425 1.967063 30 P 0 0 ;0=23,1=1
P 2.4098425 2.283063 30 P 0 0 ;0=23,1=1
P 2.4098425 2.314063 30 P 0 0 ;0=23,1=1
P 2.4098425 2.579063 30 P 0 0 ;0=23,1=1
P 2.4133858 0.2795276 30 P 0 0 ;0=23,1=1
P 2.4138425 3.295063 30 P 0 0 ;0=23,1=1
P 2.4140551 3.1998504 30 P 0 0 ;0=23,1=1
P 2.4187174 3.1185066 30 P 0 0 ;0=23,1=1
P 2.4192759 2.7886295 30 P 0 0 ;0=23,1=1
P 2.4291925 2.621063 30 P 0 0 ;0=23,1=1
P 2.4348425 3.546063 30 P 0 0 ;0=23,1=1
P 2.4448819 0.2795276 30 P 0 0 ;0=23,1=1
P 2.4468425 1.437063 30 P 0 0 ;0=23,1=1
P 2.4470546 0.2425914 30 P 0 0 ;0=23,1=1
P 2.4508425 2.282063 30 P 0 0 ;0=23,1=1
P 2.462374 3.1722441 30 P 0 0 ;0=23,1=1
P 2.4698827 0.4109883 30 P 0 0 ;0=23,1=1
P 2.4738425 2.980063 30 P 0 0 ;0=23,1=1
P 2.4758425 2.291063 30 P 0 0 ;0=23,1=1
P 2.4758425 2.456063 30 P 0 0 ;0=23,1=1
P 2.4788425 0.937063 30 P 0 0 ;0=23,1=1
P 2.4888425 2.413063 30 P 0 0 ;0=23,1=1
P 2.4948425 2.661063 30 P 0 0 ;0=23,1=1
P 2.4948425 2.696063 30 P 0 0 ;0=23,1=1
P 2.4998425 2.236063 30 P 0 0 ;0=23,1=1
P 2.5028425 1.316063 30 P 0 0 ;0=23,1=1
P 2.5082625 0.931483 30 P 0 0 ;0=23,1=1
P 2.5088425 1.090063 30 P 0 0 ;0=23,1=1
P 2.511811 0.4055118 30 P 0 0 ;0=23,1=1
P 2.5258425 2.463063 30 P 0 0 ;0=23,1=1
P 2.531398 2.830047 31 P 0 0 ;0=24,1=1
P 2.531398 3.853669 31 P 0 0 ;0=24,1=1
P 2.5460625 0.244843 30 P 0 0 ;0=23,1=1
P 2.5498425 1.755063 30 P 0 0 ;0=23,1=1
P 2.5708425 4.283063 30 P 0 0 ;0=23,1=1
P 2.5758425 2.412063 30 P 0 0 ;0=23,1=1
P 2.5787402 0.2795276 30 P 0 0 ;0=23,1=1
P 2.5798425 1.790063 30 P 0 0 ;0=23,1=1
P 2.5798425 2.281063 30 P 0 0 ;0=23,1=1
P 2.5798425 3.486063 30 P 0 0 ;0=23,1=1
P 2.5818425 2.308063 30 P 0 0 ;0=23,1=1
P 2.5868425 2.569063 30 P 0 0 ;0=23,1=1
P 2.5908425 3.288063 30 P 0 0 ;0=23,1=1
P 2.5918425 3.1862205 30 P 0 0 ;0=23,1=1
P 2.5984252 0.7952756 30 P 0 0 ;0=23,1=1
P 2.5998425 2.436063 30 P 0 0 ;0=23,1=1
P 2.6048425 1.734063 30 P 0 0 ;0=23,1=1
P 2.6066825 0.931903 30 P 0 0 ;0=23,1=1
P 2.6068425 1.091063 30 P 0 0 ;0=23,1=1
P 2.6102362 0.2795276 30 P 0 0 ;0=23,1=1
P 2.6220472 0.976378 30 P 0 0 ;0=23,1=1
P 2.6248425 2.461063 30 P 0 0 ;0=23,1=1
P 2.6259843 0.7952756 30 P 0 0 ;0=23,1=1
P 2.6268425 1.770063 30 P 0 0 ;0=23,1=1
P 2.6318425 2.876063 30 P 0 0 ;0=23,1=1
P 2.6348425 3.406063 30 P 0 0 ;0=23,1=1
P 2.636874 0.2479055 30 P 0 0 ;0=23,1=1
P 2.6438425 1.616063 30 P 0 0 ;0=23,1=1
P 2.6458425 2.274063 30 P 0 0 ;0=23,1=1
P 2.6496063 0.976378 30 P 0 0 ;0=23,1=1
P 2.6653543 0.4055118 30 P 0 0 ;0=23,1=1
P 2.6653543 0.7952756 30 P 0 0 ;0=23,1=1
P 2.6658425 1.092063 30 P 0 0 ;0=23,1=1
P 2.6658425 2.291063 30 P 0 0 ;0=23,1=1
P 2.6668425 1.640063 30 P 0 0 ;0=23,1=1
P 2.6748425 3.501063 30 P 0 0 ;0=23,1=1
P 2.6798425 3.661063 30 P 0 0 ;0=23,1=1
P 2.6811024 0.976378 30 P 0 0 ;0=23,1=1
P 2.6858425 2.311063 30 P 0 0 ;0=23,1=1
P 2.6858425 2.568063 30 P 0 0 ;0=23,1=1
P 2.6929134 0.7952756 30 P 0 0 ;0=23,1=1
P 2.6929134 2.7214567 30 P 0 0 ;0=23,1=1
P 2.6948425 1.481063 30 P 0 0 ;0=23,1=1
P 2.7028425 2.289063 30 P 0 0 ;0=23,1=1
P 2.7047244 0.4055118 30 P 0 0 ;0=23,1=1
P 2.7086614 0.976378 30 P 0 0 ;0=23,1=1
P 2.7198425 1.591063 30 P 0 0 ;0=23,1=1
P 2.7224094 3.7860709 30 P 0 0 ;0=23,1=1
P 2.7244825 1.093063 30 P 0 0 ;0=23,1=1
P 2.7248425 3.521063 30 P 0 0 ;0=23,1=1
P 2.7248425 3.729063 30 P 0 0 ;0=23,1=1
P 2.7268425 2.293063 30 P 0 0 ;0=23,1=1
P 2.7322835 0.7952756 30 P 0 0 ;0=23,1=1
P 2.7401575 0.976378 30 P 0 0 ;0=23,1=1
P 2.74882 0.282312 30 P 0 0 ;0=23,1=1
P 2.7598425 0.7952756 30 P 0 0 ;0=23,1=1
P 2.7677165 0.976378 30 P 0 0 ;0=23,1=1
P 2.7748425 3.566063 30 P 0 0 ;0=23,1=1
P 2.7795276 0.2795276 30 P 0 0 ;0=23,1=1
P 2.7838425 2.429063 30 P 0 0 ;0=23,1=1
P 2.7838425 2.568063 30 P 0 0 ;0=23,1=1
P 2.7841625 1.094063 30 P 0 0 ;0=23,1=1
P 2.7992126 0.7952756 30 P 0 0 ;0=23,1=1
P 2.7992126 0.976378 30 P 0 0 ;0=23,1=1
P 2.7998425 3.616063 30 P 0 0 ;0=23,1=1
P 2.7999951 0.2519685 30 P 0 0 ;0=23,1=1
P 2.8038425 2.307063 30 P 0 0 ;0=23,1=1
P 2.8218425 2.601063 30 P 0 0 ;0=23,1=1
P 2.8219832 0.4078519 30 P 0 0 ;0=23,1=1
P 2.8267717 0.7952756 30 P 0 0 ;0=23,1=1
P 2.8267717 0.976378 30 P 0 0 ;0=23,1=1
P 2.8418425 2.263063 30 P 0 0 ;0=23,1=1
P 2.8428425 1.095063 30 P 0 0 ;0=23,1=1
P 2.8543307 0.4055118 30 P 0 0 ;0=23,1=1
P 2.8608425 3.787063 30 P 0 0 ;0=23,1=1
P 2.8622047 0.7952756 30 P 0 0 ;0=23,1=1
P 2.8718425 2.297063 30 P 0 0 ;0=23,1=1
P 2.8782843 0.2495967 30 P 0 0 ;0=23,1=1
P 2.8818425 2.566063 30 P 0 0 ;0=23,1=1
P 2.8888425 4.221063 30 P 0 0 ;0=23,1=1
P 2.8937008 0.7952756 30 P 0 0 ;0=23,1=1
P 2.8948425 1.561063 30 P 0 0 ;0=23,1=1
P 2.8948425 2.431063 30 P 0 0 ;0=23,1=1
P 2.9018425 1.095063 30 P 0 0 ;0=23,1=1
P 2.9054946 0.2795104 30 P 0 0 ;0=23,1=1
P 2.9198425 1.536063 30 P 0 0 ;0=23,1=1
P 2.9208425 2.428063 30 P 0 0 ;0=23,1=1
P 2.9338425 0.953063 30 P 0 0 ;0=23,1=1
P 2.9370079 0.2795276 30 P 0 0 ;0=23,1=1
P 2.9428425 2.286063 30 P 0 0 ;0=23,1=1
P 2.9488425 2.456063 30 P 0 0 ;0=23,1=1
P 2.9574751 0.2519685 30 P 0 0 ;0=23,1=1
P 2.9588425 2.621063 30 P 0 0 ;0=23,1=1
P 2.980457 0.4091539 30 P 0 0 ;0=23,1=1
P 2.9858425 2.287063 30 P 0 0 ;0=23,1=1
P 2.9933858 3.751063 30 P 0 0 ;0=23,1=1
P 3.0148425 3.831063 30 P 0 0 ;0=23,1=1
P 3.019685 0.4055118 30 P 0 0 ;0=23,1=1
P 3.0568817 1.811803 30 P 0 0 ;0=23,1=1
P 3.0688976 3.3956693 30 P 0 0 ;0=23,1=1
P 3.0974409 0.2519685 30 P 0 0 ;0=23,1=1
P 3.1830708 3.1358268 30 P 0 0 ;0=23,1=1
P 3.1889764 3.1870079 30 P 0 0 ;0=23,1=1
P 3.1972633 1.714063 30 P 0 0 ;0=23,1=1
P 3.1978425 2.970063 30 P 0 0 ;0=23,1=1
P 3.2198425 3.806063 30 P 0 0 ;0=23,1=1
P 3.2248425 1.6613472 30 P 0 0 ;0=23,1=1
P 3.2308425 3.235063 30 P 0 0 ;0=23,1=1
P 3.2398425 3.596063 30 P 0 0 ;0=23,1=1
P 3.2528425 1.661063 30 P 0 0 ;0=23,1=1
P 3.2636972 3.3039177 30 P 0 0 ;0=23,1=1
P 3.2698425 3.788063 30 P 0 0 ;0=23,1=1
P 3.2755905 3.1417323 30 P 0 0 ;0=23,1=1
P 3.277559 2.9635827 30 P 0 0 ;0=23,1=1
P 3.2988425 1.971063 30 P 0 0 ;0=23,1=1
P 3.3028425 3.344063 30 P 0 0 ;0=23,1=1
P 3.3291721 1.826063 30 P 0 0 ;0=23,1=1
P 3.3308425 3.301063 30 P 0 0 ;0=23,1=1
P 3.3428425 2.263063 30 P 0 0 ;0=23,1=1
P 3.3448425 2.996063 30 P 0 0 ;0=23,1=1
P 3.3588425 3.448063 30 P 0 0 ;0=23,1=1
P 3.3688425 3.050063 30 P 0 0 ;0=23,1=1
P 3.3708425 2.888063 30 P 0 0 ;0=23,1=1
P 3.3748425 3.273063 30 P 0 0 ;0=23,1=1
P 3.3798425 1.336063 30 P 0 0 ;0=23,1=1
P 3.3798425 1.386063 30 P 0 0 ;0=23,1=1
P 3.3928425 1.871063 30 P 0 0 ;0=23,1=1
P 3.3948425 3.447063 30 P 0 0 ;0=23,1=1
P 3.3958425 4.222063 30 P 0 0 ;0=23,1=1
P 3.4048425 1.363323 30 P 0 0 ;0=23,1=1
P 3.4068425 1.461063 30 P 0 0 ;0=23,1=1
P 3.4072822 1.411323 30 P 0 0 ;0=23,1=1
P 3.4108425 1.7136509 30 P 0 0 ;0=23,1=1
P 3.4138425 1.573063 30 P 0 0 ;0=23,1=1
P 3.4144661 1.805063 30 P 0 0 ;0=23,1=1
P 3.4248425 3.636063 30 P 0 0 ;0=23,1=1
P 3.4368425 3.457063 30 P 0 0 ;0=23,1=1
P 3.4392507 1.870938 30 P 0 0 ;0=23,1=1
P 3.4698425 3.456063 30 P 0 0 ;0=23,1=1
P 3.4918425 3.103063 30 P 0 0 ;0=23,1=1
P 3.4918425 3.297063 30 P 0 0 ;0=23,1=1
P 3.4988425 2.341063 30 P 0 0 ;0=23,1=1
P 3.5048425 4.086063 30 P 0 0 ;0=23,1=1
P 3.5298425 3.481063 30 P 0 0 ;0=23,1=1
P 3.5318425 3.660063 30 P 0 0 ;0=23,1=1
P 3.5398425 3.806063 30 P 0 0 ;0=23,1=1
P 3.542865 3.3190405 30 P 0 0 ;0=23,1=1
P 3.5498425 1.413063 30 P 0 0 ;0=23,1=1
P 3.5498425 1.441063 30 P 0 0 ;0=23,1=1
P 3.5548425 1.841063 30 P 0 0 ;0=23,1=1
P 3.5548425 1.891063 30 P 0 0 ;0=23,1=1
P 3.5548425 1.941063 30 P 0 0 ;0=23,1=1
P 3.5548425 1.991063 30 P 0 0 ;0=23,1=1
P 3.5718425 2.033063 30 P 0 0 ;0=23,1=1
P 3.5718425 2.058063 30 P 0 0 ;0=23,1=1
P 3.5898425 1.711063 30 P 0 0 ;0=23,1=1
P 3.5908425 1.662063 30 P 0 0 ;0=23,1=1
P 3.5948425 1.514063 30 P 0 0 ;0=23,1=1
P 3.6038425 0.682063 30 P 0 0 ;0=23,1=1
P 3.6228425 3.486063 30 P 0 0 ;0=23,1=1
P 3.6238425 2.587063 30 P 0 0 ;0=23,1=1
P 3.6428425 0.636063 30 P 0 0 ;0=23,1=1
P 3.6538425 3.293063 30 P 0 0 ;0=23,1=1
P 3.6998425 3.751063 30 P 0 0 ;0=23,1=1
P 3.6998425 3.836063 30 P 0 0 ;0=23,1=1
P 3.7178425 3.072063 30 P 0 0 ;0=23,1=1
P 3.7188425 1.713063 30 P 0 0 ;0=23,1=1
P 3.7198425 1.766063 30 P 0 0 ;0=23,1=1
P 3.7198425 1.921063 30 P 0 0 ;0=23,1=1
P 3.7198425 1.996063 30 P 0 0 ;0=23,1=1
P 3.7248425 1.675063 30 P 0 0 ;0=23,1=1
P 3.7328425 1.418063 30 P 0 0 ;0=23,1=1
P 3.7448425 3.261063 30 P 0 0 ;0=23,1=1
P 3.7448425 3.342063 30 P 0 0 ;0=23,1=1
P 3.7738632 1.6661021 30 P 0 0 ;0=23,1=1
P 3.7778425 4.023063 30 P 0 0 ;0=23,1=1
P 3.7998425 3.201063 30 P 0 0 ;0=23,1=1
P 3.8038425 1.691063 30 P 0 0 ;0=23,1=1
P 3.8048425 1.840063 30 P 0 0 ;0=23,1=1
P 3.8068425 3.235063 30 P 0 0 ;0=23,1=1
P 3.8298425 3.176063 30 P 0 0 ;0=23,1=1
P 3.8298425 3.806063 30 P 0 0 ;0=23,1=1
P 3.8308425 3.762063 30 P 0 0 ;0=23,1=1
P 3.8348425 1.481063 30 P 0 0 ;0=23,1=1
P 3.8548425 3.151063 30 P 0 0 ;0=23,1=1
P 3.8648425 1.511063 30 P 0 0 ;0=23,1=1
P 3.8808425 3.109063 30 P 0 0 ;0=23,1=1
P 3.8948425 1.566063 30 P 0 0 ;0=23,1=1
P 3.9248425 1.536063 30 P 0 0 ;0=23,1=1
P 3.9398425 3.121063 30 P 0 0 ;0=23,1=1
P 3.9448425 1.816063 30 P 0 0 ;0=23,1=1
P 3.9608425 2.724063 30 P 0 0 ;0=23,1=1
P 3.9688425 1.671063 30 P 0 0 ;0=23,1=1
P 3.9698425 1.552063 30 P 0 0 ;0=23,1=1
P 3.9948425 1.551063 30 P 0 0 ;0=23,1=1
P 3.9968425 1.711063 30 P 0 0 ;0=23,1=1
P 4.0348425 1.546063 30 P 0 0 ;0=23,1=1
P 4.0398425 2.406063 30 P 0 0 ;0=23,1=1
P 4.0398425 3.784063 30 P 0 0 ;0=23,1=1
P 4.0498425 3.665063 30 P 0 0 ;0=23,1=1
P 4.0648425 1.511063 30 P 0 0 ;0=23,1=1
P 4.0648425 1.796063 30 P 0 0 ;0=23,1=1
P 4.0648425 2.722063 30 P 0 0 ;0=23,1=1
P 4.0688425 3.135063 30 P 0 0 ;0=23,1=1
P 4.0858425 3.892063 30 P 0 0 ;0=23,1=1
P 4.1148425 3.135063 30 P 0 0 ;0=23,1=1
P 4.1203866 3.5941508 30 P 0 0 ;0=23,1=1
P 4.1318425 1.686063 30 P 0 0 ;0=23,1=1
P 4.1348425 1.651063 30 P 0 0 ;0=23,1=1
P 4.1348425 1.751063 30 P 0 0 ;0=23,1=1
P 4.1513063 1.6236232 30 P 0 0 ;0=23,1=1
P 4.1528425 3.135063 30 P 0 0 ;0=23,1=1
P 4.1798425 1.601063 30 P 0 0 ;0=23,1=1
P 4.1948425 3.884063 30 P 0 0 ;0=23,1=1
P 4.2088425 3.135063 30 P 0 0 ;0=23,1=1
P 4.2348425 2.725063 30 P 0 0 ;0=23,1=1
P 4.2548425 3.776063 30 P 0 0 ;0=23,1=1
P 4.2728425 3.135063 30 P 0 0 ;0=23,1=1
P 4.3338425 3.135063 30 P 0 0 ;0=23,1=1
P 4.3398425 2.725063 30 P 0 0 ;0=23,1=1
P 4.3878425 4.206063 30 P 0 0 ;0=23,1=1
P 4.4318425 3.135063 30 P 0 0 ;0=23,1=1
P 4.4778425 3.135063 30 P 0 0 ;0=23,1=1
P 4.5036614 2.7898819 30 P 0 0 ;0=23,1=1
P 4.7547119 4.1159324 30 P 0 0 ;0=23,1=1
P 4.7942913 2.8080709 30 P 0 0 ;0=23,1=1
P 4.9108425 4.203063 30 P 0 0 ;0=23,1=1
P 5.2670079 4.0888976 30 P 0 0 ;0=23,1=1
P 5.2748425 3.511063 30 P 0 0 ;0=23,1=1
P 5.5778425 2.214063 30 P 0 0 ;0=23,1=1
P 5.6348425 2.236063 30 P 0 0 ;0=23,1=1
P 5.6768425 3.546063 30 P 0 0 ;0=23,1=1
P 5.7338425 3.556063 30 P 0 0 ;0=23,1=1
P 5.9948425 3.552063 30 P 0 0 ;0=23,1=1
P 6.0048425 2.434063 30 P 0 0 ;0=23,1=1
P 6.0488425 2.171063 30 P 0 0 ;0=23,1=1
P 6.253937 2.9094488 30 P 0 0 ;0=23,1=1
P 6.2748425 2.391063 30 P 0 0 ;0=23,1=1
P 6.2824161 3.226063 30 P 0 0 ;0=23,1=1
P 6.2848425 2.501063 30 P 0 0 ;0=23,1=1
P 6.2948425 3.701063 30 P 0 0 ;0=23,1=1
P 6.3048425 3.121063 30 P 0 0 ;0=23,1=1
P 6.3094161 3.199063 30 P 0 0 ;0=23,1=1
P 6.3348425 3.266063 30 P 0 0 ;0=23,1=1
P 6.3398425 3.151063 30 P 0 0 ;0=23,1=1
P 6.3547483 3.3311384 30 P 0 0 ;0=23,1=1
P 6.3720472 2.9094488 30 P 0 0 ;0=23,1=1
P 6.3958425 2.111063 30 P 0 0 ;0=23,1=1
P 6.3968425 2.556063 30 P 0 0 ;0=23,1=1
P 6.3978425 2.501063 30 P 0 0 ;0=23,1=1
P 6.3978425 2.610063 30 P 0 0 ;0=23,1=1
P 6.3988425 2.453063 30 P 0 0 ;0=23,1=1
P 6.3988425 2.657063 30 P 0 0 ;0=23,1=1
P 6.4098425 3.371063 30 P 0 0 ;0=23,1=1
P 6.4248425 2.181063 30 P 0 0 ;0=23,1=1
P 6.4398425 3.191063 30 P 0 0 ;0=23,1=1
P 6.4448425 3.291063 30 P 0 0 ;0=23,1=1
P 6.4475772 3.396063 30 P 0 0 ;0=23,1=1
P 6.4568425 3.009063 30 P 0 0 ;0=23,1=1
P 6.4768425 3.231063 30 P 0 0 ;0=23,1=1
P 6.4798425 3.426063 30 P 0 0 ;0=23,1=1
P 6.5098425 3.456063 30 P 0 0 ;0=23,1=1
P 6.5488425 1.531063 30 P 0 0 ;0=23,1=1
P 6.6018425 1.777063 30 P 0 0 ;0=23,1=1
P 6.6028425 1.612063 30 P 0 0 ;0=23,1=1
P 6.6028425 1.672063 30 P 0 0 ;0=23,1=1
P 6.6028425 1.722063 30 P 0 0 ;0=23,1=1
P 6.6078425 2.176063 30 P 0 0 ;0=23,1=1
P 6.6268425 3.032063 30 P 0 0 ;0=23,1=1
P 6.6288425 1.372063 30 P 0 0 ;0=23,1=1
P 6.6476378 3.1299213 30 P 0 0 ;0=23,1=1
P 6.6488425 3.341063 30 P 0 0 ;0=23,1=1
P 6.6858425 1.828063 30 P 0 0 ;0=23,1=1
P 6.6998425 1.881063 30 P 0 0 ;0=23,1=1
P 6.8448425 1.661063 30 P 0 0 ;0=23,1=1
P 6.9498425 2.095063 30 P 0 0 ;0=23,1=1
P 6.9744094 1.9399606 30 P 0 0 ;0=23,1=1

### steps/pcb/layers/bottom_overlay/features
#Layer_Color=32896
#
#Feature symbol names
#
$0 r3.937
$1 r1
$2 r10
$3 r6

#
#Feature attribute names
#
@0 .nomenclature
@1 .string
@2 .string_angle

#
#Feature attribute text strings
#
&0 U14
&1 C47
&2 C46
&3 C45
&4 C44
&5 C87
&6 C88
&7 C89
&8 C90
&9 C53
&10 C52
&11 C51
&12 C50
&13 C49
&14 C48

#
#Layer features
#
A 0.2105315 2.8300473 0.2105315 2.8300473 0.1495079 2.8300473 2 P 0 N
A 1.7712204 0.4310709 1.6275196 0.4310709 1.69937 0.4310709 0 P 0 N
A 2.5924212 2.8300473 2.5924212 2.8300473 2.5313976 2.8300473 2 P 0 N
A 2.5924212 3.8536693 2.5924212 3.8536693 2.5313976 3.8536693 2 P 0 N
L -0.0001175 0.177913 0.5908825 0.177913 1 P 0
L -0.0004331 0.1781182 0.5901181 0.1781182 0 P 0
L 0.0180118 2.7168583 0.0180118 3.9668583 2 P 0
L 0.0180118 2.7168583 2.6628937 2.7168583 2 P 0
L 0.0180118 3.9668583 2.6628937 3.9668583 2 P 0
L 0.5901181 0.1781182 0.5901181 0.5029213 0 P 0
L 0.5901181 0.5029213 1.312559 0.5029213 0 P 0
L 0.5908825 0.177913 0.5908825 0.502913 1 P 0
L 1.312559 0.313945 1.312559 0.5029213 0 P 0
L 1.312559 0.313945 1.6275197 0.313945 0 P 0
L 1.6275197 0.313945 1.6275197 0.4310709 0 P 0
L 2.1985692 2.9482203 2.2185627 2.9282268 2 P 0 ;0,1=5,2=0.000000
L 2.1985692 2.9532187 2.1985692 2.9482203 2 P 0 ;0,1=5,2=0.000000
L 2.2185627 2.9282268 2.2185627 2.9232284 2 P 0 ;0,1=5,2=0.000000
L 2.2185627 2.9532187 2.1985692 2.9532187 2 P 0 ;0,1=5,2=0.000000
L 2.2285595 2.9282268 2.2335578 2.9232284 2 P 0 ;0,1=5,2=0.000000
L 2.2285595 2.9332252 2.2285595 2.9282268 2 P 0 ;0,1=5,2=0.000000
L 2.2285595 2.9432219 2.2335578 2.9382236 2 P 0 ;0,1=5,2=0.000000
L 2.2285595 2.9482203 2.2285595 2.9432219 2 P 0 ;0,1=5,2=0.000000
L 2.2335578 2.9232284 2.2435546 2.9232284 2 P 0 ;0,1=5,2=0.000000
L 2.2335578 2.9382236 2.2285595 2.9332252 2 P 0 ;0,1=5,2=0.000000
L 2.2335578 2.9532187 2.2285595 2.9482203 2 P 0 ;0,1=5,2=0.000000
L 2.2399078 2.8288173 2.2449061 2.8238189 2 P 0 ;0,1=6,2=0.000000
L 2.2399078 2.8338157 2.2399078 2.8288173 2 P 0 ;0,1=6,2=0.000000
L 2.2399078 2.8438124 2.2449061 2.8388141 2 P 0 ;0,1=6,2=0.000000
L 2.2399078 2.8488108 2.2399078 2.8438124 2 P 0 ;0,1=6,2=0.000000
L 2.2435546 2.9232284 2.248553 2.9282268 2 P 0 ;0,1=5,2=0.000000
L 2.2435546 2.9382236 2.2335578 2.9382236 2 P 0 ;0,1=5,2=0.000000
L 2.2435546 2.9382236 2.248553 2.9432219 2 P 0 ;0,1=5,2=0.000000
L 2.2435546 2.9532187 2.2335578 2.9532187 2 P 0 ;0,1=5,2=0.000000
L 2.2449061 2.8238189 2.2549029 2.8238189 2 P 0 ;0,1=6,2=0.000000
L 2.2449061 2.8388141 2.2399078 2.8338157 2 P 0 ;0,1=6,2=0.000000
L 2.2449061 2.8538092 2.2399078 2.8488108 2 P 0 ;0,1=6,2=0.000000
L 2.248553 2.9282268 2.248553 2.9332252 2 P 0 ;0,1=5,2=0.000000
L 2.248553 2.9332252 2.2435546 2.9382236 2 P 0 ;0,1=5,2=0.000000
L 2.248553 2.9432219 2.248553 2.9482203 2 P 0 ;0,1=5,2=0.000000
L 2.248553 2.9482203 2.2435546 2.9532187 2 P 0 ;0,1=5,2=0.000000
L 2.2549029 2.8238189 2.2599013 2.8288173 2 P 0 ;0,1=6,2=0.000000
L 2.2549029 2.8388141 2.2449061 2.8388141 2 P 0 ;0,1=6,2=0.000000
L 2.2549029 2.8388141 2.2599013 2.8438124 2 P 0 ;0,1=6,2=0.000000
L 2.2549029 2.8538092 2.2449061 2.8538092 2 P 0 ;0,1=6,2=0.000000
L 2.2585498 2.9482203 2.2635481 2.9532187 2 P 0 ;0,1=5,2=0.000000
L 2.2599013 2.8288173 2.2599013 2.8338157 2 P 0 ;0,1=6,2=0.000000
L 2.2599013 2.8338157 2.2549029 2.8388141 2 P 0 ;0,1=6,2=0.000000
L 2.2599013 2.8438124 2.2599013 2.8488108 2 P 0 ;0,1=6,2=0.000000
L 2.2599013 2.8488108 2.2549029 2.8538092 2 P 0 ;0,1=6,2=0.000000
L 2.2635481 2.9232284 2.2585498 2.9282268 2 P 0 ;0,1=5,2=0.000000
L 2.2635481 2.9532187 2.2735449 2.9532187 2 P 0 ;0,1=5,2=0.000000
L 2.2698981 2.8288173 2.2748964 2.8238189 2 P 0 ;0,1=6,2=0.000000
L 2.2698981 2.8338157 2.2698981 2.8288173 2 P 0 ;0,1=6,2=0.000000
L 2.2698981 2.8438124 2.2748964 2.8388141 2 P 0 ;0,1=6,2=0.000000
L 2.2698981 2.8488108 2.2698981 2.8438124 2 P 0 ;0,1=6,2=0.000000
L 2.2735449 2.9232284 2.2635481 2.9232284 2 P 0 ;0,1=5,2=0.000000
L 2.2735449 2.9532187 2.2785433 2.9482203 2 P 0 ;0,1=5,2=0.000000
L 2.2748964 2.8238189 2.2848932 2.8238189 2 P 0 ;0,1=6,2=0.000000
L 2.2748964 2.8388141 2.2698981 2.8338157 2 P 0 ;0,1=6,2=0.000000
L 2.2748964 2.8538092 2.2698981 2.8488108 2 P 0 ;0,1=6,2=0.000000
L 2.2785433 2.9282268 2.2735449 2.9232284 2 P 0 ;0,1=5,2=0.000000
L 2.2785433 2.9482203 2.2785433 2.9282268 2 P 0 ;0,1=5,2=0.000000
L 2.2848932 2.8238189 2.2898916 2.8288173 2 P 0 ;0,1=6,2=0.000000
L 2.2848932 2.8388141 2.2748964 2.8388141 2 P 0 ;0,1=6,2=0.000000
L 2.2848932 2.8388141 2.2898916 2.8438124 2 P 0 ;0,1=6,2=0.000000
L 2.2848932 2.8538092 2.2748964 2.8538092 2 P 0 ;0,1=6,2=0.000000
L 2.2898916 2.8288173 2.2898916 2.8338157 2 P 0 ;0,1=6,2=0.000000
L 2.2898916 2.8338157 2.2848932 2.8388141 2 P 0 ;0,1=6,2=0.000000
L 2.2898916 2.8438124 2.2898916 2.8488108 2 P 0 ;0,1=6,2=0.000000
L 2.2898916 2.8488108 2.2848932 2.8538092 2 P 0 ;0,1=6,2=0.000000
L 2.2998884 2.8488108 2.3048867 2.8538092 2 P 0 ;0,1=6,2=0.000000
L 2.3048867 2.8238189 2.2998884 2.8288173 2 P 0 ;0,1=6,2=0.000000
L 2.3048867 2.8538092 2.3148835 2.8538092 2 P 0 ;0,1=6,2=0.000000
L 2.3061023 0.4646441 2.3061023 0.4746409 2 P 0 ;0,1=4,2=270.000000
L 2.3061023 0.4746409 2.3111007 0.4796392 2 P 0 ;0,1=4,2=270.000000
L 2.3061023 0.5046312 2.3360926 0.5046312 2 P 0 ;0,1=4,2=270.000000
L 2.3061023 0.5346215 2.3360926 0.5346215 2 P 0 ;0,1=4,2=270.000000
L 2.3111007 0.4596457 2.3061023 0.4646441 2 P 0 ;0,1=4,2=270.000000
L 2.3148835 2.8238189 2.3048867 2.8238189 2 P 0 ;0,1=6,2=0.000000
L 2.3148835 2.8538092 2.3198819 2.8488108 2 P 0 ;0,1=6,2=0.000000
L 2.3198819 2.8288173 2.3148835 2.8238189 2 P 0 ;0,1=6,2=0.000000
L 2.3198819 2.8488108 2.3198819 2.8288173 2 P 0 ;0,1=6,2=0.000000
L 2.3210975 0.489636 2.3210975 0.5096295 2 P 0 ;0,1=4,2=270.000000
L 2.3210975 0.5196263 2.3210975 0.5396198 2 P 0 ;0,1=4,2=270.000000
L 2.3310942 0.4596457 2.3111007 0.4596457 2 P 0 ;0,1=4,2=270.000000
L 2.3310942 0.4796392 2.3360926 0.4746409 2 P 0 ;0,1=4,2=270.000000
L 2.3328425 2.906063 2.3928425 2.906063 3 P 0
L 2.3328425 2.982063 2.3928425 2.982063 3 P 0
L 2.3360926 0.4646441 2.3310942 0.4596457 2 P 0 ;0,1=4,2=270.000000
L 2.3360926 0.4746409 2.3360926 0.4646441 2 P 0 ;0,1=4,2=270.000000
L 2.3360926 0.5046312 2.3210975 0.489636 2 P 0 ;0,1=4,2=270.000000
L 2.3360926 0.5346215 2.3210975 0.5196263 2 P 0 ;0,1=4,2=270.000000
L 2.3759842 0.4626756 2.3759842 0.4726724 2 P 0 ;0,1=3,2=270.000000
L 2.3759842 0.4726724 2.3809826 0.4776707 2 P 0 ;0,1=3,2=270.000000
L 2.3759842 0.5026627 2.4059745 0.5026627 2 P 0 ;0,1=3,2=270.000000
L 2.3759842 0.5226562 2.3809826 0.5176578 2 P 0 ;0,1=3,2=270.000000
L 2.3759842 0.532653 2.3759842 0.5226562 2 P 0 ;0,1=3,2=270.000000
L 2.3809826 0.4576772 2.3759842 0.4626756 2 P 0 ;0,1=3,2=270.000000
L 2.3809826 0.5376513 2.3759842 0.532653 2 P 0 ;0,1=3,2=270.000000
L 2.3909794 0.4876675 2.3909794 0.507661 2 P 0 ;0,1=3,2=270.000000
L 2.3909794 0.5176578 2.3959777 0.5276546 2 P 0 ;0,1=3,2=270.000000
L 2.3909794 0.5376513 2.3809826 0.5376513 2 P 0 ;0,1=3,2=270.000000
L 2.3959777 0.5276546 2.3959777 0.532653 2 P 0 ;0,1=3,2=270.000000
L 2.3959777 0.532653 2.3909794 0.5376513 2 P 0 ;0,1=3,2=270.000000
L 2.4009761 0.4576772 2.3809826 0.4576772 2 P 0 ;0,1=3,2=270.000000
L 2.4009761 0.4776707 2.4059745 0.4726724 2 P 0 ;0,1=3,2=270.000000
L 2.4059745 0.4626756 2.4009761 0.4576772 2 P 0 ;0,1=3,2=270.000000
L 2.4059745 0.4726724 2.4059745 0.4626756 2 P 0 ;0,1=3,2=270.000000
L 2.4059745 0.5026627 2.3909794 0.4876675 2 P 0 ;0,1=3,2=270.000000
L 2.4059745 0.5176578 2.3909794 0.5176578 2 P 0 ;0,1=3,2=270.000000
L 2.4059745 0.5376513 2.4059745 0.5176578 2 P 0 ;0,1=3,2=270.000000
L 2.4503498 0.4460808 2.4503498 0.4560776 2 P 0 ;0,1=2,2=270.000000
L 2.4503498 0.4560776 2.4553482 0.4610759 2 P 0 ;0,1=2,2=270.000000
L 2.4503498 0.4860679 2.4803401 0.4860679 2 P 0 ;0,1=2,2=270.000000
L 2.4503498 0.5060614 2.4503498 0.5160582 2 P 0 ;0,1=2,2=270.000000
L 2.4503498 0.5160582 2.4553482 0.5210565 2 P 0 ;0,1=2,2=270.000000
L 2.4553482 0.4410824 2.4503498 0.4460808 2 P 0 ;0,1=2,2=270.000000
L 2.4553482 0.501063 2.4503498 0.5060614 2 P 0 ;0,1=2,2=270.000000
L 2.4553482 0.5210565 2.4603466 0.5210565 2 P 0 ;0,1=2,2=270.000000
L 2.4603466 0.5210565 2.465345 0.5160582 2 P 0 ;0,1=2,2=270.000000
L 2.465345 0.4710727 2.465345 0.4910662 2 P 0 ;0,1=2,2=270.000000
L 2.465345 0.501063 2.4553482 0.501063 2 P 0 ;0,1=2,2=270.000000
L 2.465345 0.5160582 2.465345 0.501063 2 P 0 ;0,1=2,2=270.000000
L 2.4753417 0.4410824 2.4553482 0.4410824 2 P 0 ;0,1=2,2=270.000000
L 2.4753417 0.4610759 2.4803401 0.4560776 2 P 0 ;0,1=2,2=270.000000
L 2.4753417 0.5110598 2.465345 0.501063 2 P 0 ;0,1=2,2=270.000000
L 2.4803401 0.4460808 2.4753417 0.4410824 2 P 0 ;0,1=2,2=270.000000
L 2.4803401 0.4560776 2.4803401 0.4460808 2 P 0 ;0,1=2,2=270.000000
L 2.4803401 0.4860679 2.465345 0.4710727 2 P 0 ;0,1=2,2=270.000000
L 2.4803401 0.5210565 2.4753417 0.5110598 2 P 0 ;0,1=2,2=270.000000
L 2.5193498 0.4460808 2.5193498 0.4560776 2 P 0 ;0,1=1,2=270.000000
L 2.5193498 0.4560776 2.5243482 0.4610759 2 P 0 ;0,1=1,2=270.000000
L 2.5193498 0.4860679 2.5493401 0.4860679 2 P 0 ;0,1=1,2=270.000000
L 2.5243482 0.4410824 2.5193498 0.4460808 2 P 0 ;0,1=1,2=270.000000
L 2.5243482 0.501063 2.5193498 0.501063 2 P 0 ;0,1=1,2=270.000000
L 2.534345 0.4710727 2.534345 0.4910662 2 P 0 ;0,1=1,2=270.000000
L 2.5443417 0.4410824 2.5243482 0.4410824 2 P 0 ;0,1=1,2=270.000000
L 2.5443417 0.4610759 2.5493401 0.4560776 2 P 0 ;0,1=1,2=270.000000
L 2.5443417 0.5210565 2.5243482 0.501063 2 P 0 ;0,1=1,2=270.000000
L 2.5493401 0.4460808 2.5443417 0.4410824 2 P 0 ;0,1=1,2=270.000000
L 2.5493401 0.4560776 2.5493401 0.4460808 2 P 0 ;0,1=1,2=270.000000
L 2.5493401 0.4860679 2.534345 0.4710727 2 P 0 ;0,1=1,2=270.000000
L 2.5493401 0.501063 2.5493401 0.5210565 2 P 0 ;0,1=1,2=270.000000
L 2.5493401 0.5210565 2.5443417 0.5210565 2 P 0 ;0,1=1,2=270.000000
L 2.5878651 4.002063 2.5878651 4.0320533 2 P 0 ;0,1=0,2=0.000000
L 2.5878651 4.0320533 2.6028603 4.0170582 2 P 0 ;0,1=0,2=0.000000
L 2.5948425 2.977063 2.5948425 3.037063 3 P 0
L 2.6028603 4.0170582 2.5828668 4.0170582 2 P 0 ;0,1=0,2=0.000000
L 2.6043307 3.0857071 2.6043307 3.0957039 2 P 0 ;0,1=7,2=270.000000
L 2.6043307 3.0957039 2.6093291 3.1007022 2 P 0 ;0,1=7,2=270.000000
L 2.6043307 3.1156974 2.6093291 3.110699 2 P 0 ;0,1=7,2=270.000000
L 2.6043307 3.1256942 2.6043307 3.1156974 2 P 0 ;0,1=7,2=270.000000
L 2.6043307 3.1456877 2.6043307 3.1556845 2 P 0 ;0,1=7,2=270.000000
L 2.6043307 3.1556845 2.6093291 3.1606828 2 P 0 ;0,1=7,2=270.000000
L 2.6093291 3.0807087 2.6043307 3.0857071 2 P 0 ;0,1=7,2=270.000000
L 2.6093291 3.110699 2.6143275 3.110699 2 P 0 ;0,1=7,2=270.000000
L 2.6093291 3.1306925 2.6043307 3.1256942 2 P 0 ;0,1=7,2=270.000000
L 2.6093291 3.1406893 2.6043307 3.1456877 2 P 0 ;0,1=7,2=270.000000
L 2.6093291 3.1606828 2.6293226 3.1606828 2 P 0 ;0,1=7,2=270.000000
L 2.6143275 3.110699 2.6193259 3.1156974 2 P 0 ;0,1=7,2=270.000000
L 2.6143275 3.1306925 2.6093291 3.1306925 2 P 0 ;0,1=7,2=270.000000
L 2.6178554 4.002063 2.6228538 4.002063 2 P 0 ;0,1=0,2=0.000000
L 2.6193259 3.1156974 2.6193259 3.1256942 2 P 0 ;0,1=7,2=270.000000
L 2.6193259 3.1156974 2.6243242 3.110699 2 P 0 ;0,1=7,2=270.000000
L 2.6193259 3.1256942 2.6143275 3.1306925 2 P 0 ;0,1=7,2=270.000000
L 2.6193259 3.1456877 2.6193259 3.1606828 2 P 0 ;0,1=7,2=270.000000
L 2.6228538 4.002063 2.6228538 4.0320533 2 P 0 ;0,1=0,2=0.000000
L 2.6228538 4.0320533 2.6278522 4.0270549 2 P 0 ;0,1=0,2=0.000000
L 2.6243242 3.110699 2.6293226 3.110699 2 P 0 ;0,1=7,2=270.000000
L 2.6243242 3.1306925 2.6193259 3.1256942 2 P 0 ;0,1=7,2=270.000000
L 2.6243242 3.1406893 2.6193259 3.1456877 2 P 0 ;0,1=7,2=270.000000
L 2.6278522 4.002063 2.6178554 4.002063 2 P 0 ;0,1=0,2=0.000000
L 2.6293226 3.0807087 2.6093291 3.0807087 2 P 0 ;0,1=7,2=270.000000
L 2.6293226 3.1007022 2.634321 3.0957039 2 P 0 ;0,1=7,2=270.000000
L 2.6293226 3.110699 2.634321 3.1156974 2 P 0 ;0,1=7,2=270.000000
L 2.6293226 3.1306925 2.6243242 3.1306925 2 P 0 ;0,1=7,2=270.000000
L 2.6293226 3.1406893 2.6243242 3.1406893 2 P 0 ;0,1=7,2=270.000000
L 2.6293226 3.1606828 2.634321 3.1556845 2 P 0 ;0,1=7,2=270.000000
L 2.634321 3.0857071 2.6293226 3.0807087 2 P 0 ;0,1=7,2=270.000000
L 2.634321 3.0957039 2.634321 3.0857071 2 P 0 ;0,1=7,2=270.000000
L 2.634321 3.1156974 2.634321 3.1256942 2 P 0 ;0,1=7,2=270.000000
L 2.634321 3.1256942 2.6293226 3.1306925 2 P 0 ;0,1=7,2=270.000000
L 2.634321 3.1456877 2.6293226 3.1406893 2 P 0 ;0,1=7,2=270.000000
L 2.634321 3.1556845 2.634321 3.1456877 2 P 0 ;0,1=7,2=270.000000
L 2.6343498 0.4460808 2.6343498 0.4560776 2 P 0 ;0,1=14,2=270.000000
L 2.6343498 0.4560776 2.6393482 0.4610759 2 P 0 ;0,1=14,2=270.000000
L 2.6343498 0.4860679 2.6643401 0.4860679 2 P 0 ;0,1=14,2=270.000000
L 2.6343498 0.5060614 2.6393482 0.501063 2 P 0 ;0,1=14,2=270.000000
L 2.6343498 0.5160582 2.6343498 0.5060614 2 P 0 ;0,1=14,2=270.000000
L 2.637849 4.0070614 2.637849 4.0320533 2 P 0 ;0,1=0,2=0.000000
L 2.6393482 0.4410824 2.6343498 0.4460808 2 P 0 ;0,1=14,2=270.000000
L 2.6393482 0.501063 2.6443466 0.501063 2 P 0 ;0,1=14,2=270.000000
L 2.6393482 0.5210565 2.6343498 0.5160582 2 P 0 ;0,1=14,2=270.000000
L 2.6428473 4.002063 2.637849 4.0070614 2 P 0 ;0,1=0,2=0.000000
L 2.6443466 0.501063 2.649345 0.5060614 2 P 0 ;0,1=14,2=270.000000
L 2.6443466 0.5210565 2.6393482 0.5210565 2 P 0 ;0,1=14,2=270.000000
L 2.649345 0.4710727 2.649345 0.4910662 2 P 0 ;0,1=14,2=270.000000
L 2.649345 0.5060614 2.649345 0.5160582 2 P 0 ;0,1=14,2=270.000000
L 2.649345 0.5060614 2.6543433 0.501063 2 P 0 ;0,1=14,2=270.000000
L 2.649345 0.5160582 2.6443466 0.5210565 2 P 0 ;0,1=14,2=270.000000
L 2.6528441 4.002063 2.6428473 4.002063 2 P 0 ;0,1=0,2=0.000000
L 2.6543433 0.501063 2.6593417 0.501063 2 P 0 ;0,1=14,2=270.000000
L 2.6543433 0.5210565 2.649345 0.5160582 2 P 0 ;0,1=14,2=270.000000
L 2.6578425 4.0070614 2.6528441 4.002063 2 P 0 ;0,1=0,2=0.000000
L 2.6578425 4.0320533 2.6578425 4.0070614 2 P 0 ;0,1=0,2=0.000000
L 2.6593417 0.4410824 2.6393482 0.4410824 2 P 0 ;0,1=14,2=270.000000
L 2.6593417 0.4610759 2.6643401 0.4560776 2 P 0 ;0,1=14,2=270.000000
L 2.6593417 0.501063 2.6643401 0.5060614 2 P 0 ;0,1=14,2=270.000000
L 2.6593417 0.5210565 2.6543433 0.5210565 2 P 0 ;0,1=14,2=270.000000
L 2.6628937 2.7168583 2.6628937 3.9668583 2 P 0
L 2.6643401 0.4460808 2.6593417 0.4410824 2 P 0 ;0,1=14,2=270.000000
L 2.6643401 0.4560776 2.6643401 0.4460808 2 P 0 ;0,1=14,2=270.000000
L 2.6643401 0.4860679 2.649345 0.4710727 2 P 0 ;0,1=14,2=270.000000
L 2.6643401 0.5060614 2.6643401 0.5160582 2 P 0 ;0,1=14,2=270.000000
L 2.6643401 0.5160582 2.6593417 0.5210565 2 P 0 ;0,1=14,2=270.000000
L 2.6708425 2.977063 2.6708425 3.037063 3 P 0
L 2.7023498 0.4460808 2.7023498 0.4560776 2 P 0 ;0,1=13,2=270.000000
L 2.7023498 0.4560776 2.7073482 0.4610759 2 P 0 ;0,1=13,2=270.000000
L 2.7023498 0.4860679 2.7323401 0.4860679 2 P 0 ;0,1=13,2=270.000000
L 2.7023498 0.5060614 2.7023498 0.5160582 2 P 0 ;0,1=13,2=270.000000
L 2.7023498 0.5160582 2.7073482 0.5210565 2 P 0 ;0,1=13,2=270.000000
L 2.7073482 0.4410824 2.7023498 0.4460808 2 P 0 ;0,1=13,2=270.000000
L 2.7073482 0.501063 2.7023498 0.5060614 2 P 0 ;0,1=13,2=270.000000
L 2.7073482 0.5210565 2.7273417 0.5210565 2 P 0 ;0,1=13,2=270.000000
L 2.717345 0.4710727 2.717345 0.4910662 2 P 0 ;0,1=13,2=270.000000
L 2.717345 0.5060614 2.717345 0.5210565 2 P 0 ;0,1=13,2=270.000000
L 2.7223433 0.501063 2.717345 0.5060614 2 P 0 ;0,1=13,2=270.000000
L 2.7273417 0.4410824 2.7073482 0.4410824 2 P 0 ;0,1=13,2=270.000000
L 2.7273417 0.4610759 2.7323401 0.4560776 2 P 0 ;0,1=13,2=270.000000
L 2.7273417 0.501063 2.7223433 0.501063 2 P 0 ;0,1=13,2=270.000000
L 2.7273417 0.5210565 2.7323401 0.5160582 2 P 0 ;0,1=13,2=270.000000
L 2.7323401 0.4460808 2.7273417 0.4410824 2 P 0 ;0,1=13,2=270.000000
L 2.7323401 0.4560776 2.7323401 0.4460808 2 P 0 ;0,1=13,2=270.000000
L 2.7323401 0.4860679 2.717345 0.4710727 2 P 0 ;0,1=13,2=270.000000
L 2.7323401 0.5060614 2.7273417 0.501063 2 P 0 ;0,1=13,2=270.000000
L 2.7323401 0.5160582 2.7323401 0.5060614 2 P 0 ;0,1=13,2=270.000000
L 2.789849 3.0025687 2.7948473 2.9975703 2 P 0 ;0,1=8,2=0.000000
L 2.789849 3.0225622 2.789849 3.0025687 2 P 0 ;0,1=8,2=0.000000
L 2.7933498 0.4460808 2.7933498 0.4560776 2 P 0 ;0,1=12,2=270.000000
L 2.7933498 0.4560776 2.7983482 0.4610759 2 P 0 ;0,1=12,2=270.000000
L 2.7933498 0.4760711 2.7983482 0.4710727 2 P 0 ;0,1=12,2=270.000000
L 2.7933498 0.4860679 2.7933498 0.4760711 2 P 0 ;0,1=12,2=270.000000
L 2.7933498 0.5060614 2.7983482 0.501063 2 P 0 ;0,1=12,2=270.000000
L 2.7933498 0.5160582 2.7933498 0.5060614 2 P 0 ;0,1=12,2=270.000000
L 2.7948473 2.9975703 2.8048441 2.9975703 2 P 0 ;0,1=8,2=0.000000
L 2.7948473 3.0275606 2.789849 3.0225622 2 P 0 ;0,1=8,2=0.000000
L 2.7983482 0.4410824 2.7933498 0.4460808 2 P 0 ;0,1=12,2=270.000000
L 2.7983482 0.4910662 2.7933498 0.4860679 2 P 0 ;0,1=12,2=270.000000
L 2.7983482 0.501063 2.8183417 0.501063 2 P 0 ;0,1=12,2=270.000000
L 2.7983482 0.5210565 2.7933498 0.5160582 2 P 0 ;0,1=12,2=270.000000
L 2.8048441 2.9975703 2.8098425 3.0025687 2 P 0 ;0,1=8,2=0.000000
L 2.8048441 3.0275606 2.7948473 3.0275606 2 P 0 ;0,1=8,2=0.000000
L 2.808345 0.4710727 2.8133433 0.4810695 2 P 0 ;0,1=12,2=270.000000
L 2.808345 0.4910662 2.7983482 0.4910662 2 P 0 ;0,1=12,2=270.000000
L 2.8098425 3.0025687 2.8098425 3.0225622 2 P 0 ;0,1=8,2=0.000000
L 2.8098425 3.0225622 2.8048441 3.0275606 2 P 0 ;0,1=8,2=0.000000
L 2.8133433 0.4810695 2.8133433 0.4860679 2 P 0 ;0,1=12,2=270.000000
L 2.8133433 0.4860679 2.808345 0.4910662 2 P 0 ;0,1=12,2=270.000000
L 2.8183417 0.4410824 2.7983482 0.4410824 2 P 0 ;0,1=12,2=270.000000
L 2.8183417 0.4610759 2.8233401 0.4560776 2 P 0 ;0,1=12,2=270.000000
L 2.8183417 0.501063 2.8233401 0.5060614 2 P 0 ;0,1=12,2=270.000000
L 2.8183417 0.5210565 2.7983482 0.5210565 2 P 0 ;0,1=12,2=270.000000
L 2.8198393 3.0025687 2.8198393 3.0225622 2 P 0 ;0,1=8,2=0.000000
L 2.8198393 3.0225622 2.8248376 3.0275606 2 P 0 ;0,1=8,2=0.000000
L 2.8233401 0.4460808 2.8183417 0.4410824 2 P 0 ;0,1=12,2=270.000000
L 2.8233401 0.4560776 2.8233401 0.4460808 2 P 0 ;0,1=12,2=270.000000
L 2.8233401 0.4710727 2.808345 0.4710727 2 P 0 ;0,1=12,2=270.000000
L 2.8233401 0.4910662 2.8233401 0.4710727 2 P 0 ;0,1=12,2=270.000000
L 2.8233401 0.5060614 2.8233401 0.5160582 2 P 0 ;0,1=12,2=270.000000
L 2.8233401 0.5160582 2.8183417 0.5210565 2 P 0 ;0,1=12,2=270.000000
L 2.8248376 2.9975703 2.8198393 3.0025687 2 P 0 ;0,1=8,2=0.000000
L 2.8248376 3.0275606 2.8348344 3.0275606 2 P 0 ;0,1=8,2=0.000000
L 2.8348344 2.9975703 2.8248376 2.9975703 2 P 0 ;0,1=8,2=0.000000
L 2.8348344 3.0125655 2.8198393 3.0125655 2 P 0 ;0,1=8,2=0.000000
L 2.8348344 3.0275606 2.8398328 3.0225622 2 P 0 ;0,1=8,2=0.000000
L 2.8398328 3.0025687 2.8348344 2.9975703 2 P 0 ;0,1=8,2=0.000000
L 2.8398328 3.0175638 2.8348344 3.0125655 2 P 0 ;0,1=8,2=0.000000
L 2.8398328 3.0225622 2.8398328 3.0175638 2 P 0 ;0,1=8,2=0.000000
L 2.8498296 3.0225622 2.8548279 3.0275606 2 P 0 ;0,1=8,2=0.000000
L 2.8548279 2.9975703 2.8498296 3.0025687 2 P 0 ;0,1=8,2=0.000000
L 2.8548279 3.0275606 2.8648247 3.0275606 2 P 0 ;0,1=8,2=0.000000
L 2.8643498 0.4460808 2.8643498 0.4560776 2 P 0 ;0,1=11,2=270.000000
L 2.8643498 0.4560776 2.8693482 0.4610759 2 P 0 ;0,1=11,2=270.000000
L 2.8643498 0.4760711 2.8693482 0.4710727 2 P 0 ;0,1=11,2=270.000000
L 2.8643498 0.4860679 2.8643498 0.4760711 2 P 0 ;0,1=11,2=270.000000
L 2.8643498 0.501063 2.8643498 0.5110598 2 P 0 ;0,1=11,2=270.000000
L 2.8643498 0.5060614 2.8943401 0.5060614 2 P 0 ;0,1=11,2=270.000000
L 2.8643498 0.5110598 2.8643498 0.5060614 2 P 0 ;0,1=11,2=270.000000
L 2.8648247 2.9975703 2.8548279 2.9975703 2 P 0 ;0,1=8,2=0.000000
L 2.8648247 3.0275606 2.8698231 3.0225622 2 P 0 ;0,1=8,2=0.000000
L 2.8693482 0.4410824 2.8643498 0.4460808 2 P 0 ;0,1=11,2=270.000000
L 2.8693482 0.4910662 2.8643498 0.4860679 2 P 0 ;0,1=11,2=270.000000
L 2.8698231 3.0025687 2.8648247 2.9975703 2 P 0 ;0,1=8,2=0.000000
L 2.8698231 3.0225622 2.8698231 3.0025687 2 P 0 ;0,1=8,2=0.000000
L 2.879345 0.4710727 2.8843433 0.4810695 2 P 0 ;0,1=11,2=270.000000
L 2.879345 0.4910662 2.8693482 0.4910662 2 P 0 ;0,1=11,2=270.000000
L 2.8843433 0.4810695 2.8843433 0.4860679 2 P 0 ;0,1=11,2=270.000000
L 2.8843433 0.4860679 2.879345 0.4910662 2 P 0 ;0,1=11,2=270.000000
L 2.8893417 0.4410824 2.8693482 0.4410824 2 P 0 ;0,1=11,2=270.000000
L 2.8893417 0.4610759 2.8943401 0.4560776 2 P 0 ;0,1=11,2=270.000000
L 2.8943401 0.4460808 2.8893417 0.4410824 2 P 0 ;0,1=11,2=270.000000
L 2.8943401 0.4560776 2.8943401 0.4460808 2 P 0 ;0,1=11,2=270.000000
L 2.8943401 0.4710727 2.879345 0.4710727 2 P 0 ;0,1=11,2=270.000000
L 2.8943401 0.4910662 2.8943401 0.4710727 2 P 0 ;0,1=11,2=270.000000
L 2.8943401 0.5060614 2.8893417 0.501063 2 P 0 ;0,1=11,2=270.000000
L 2.9593498 0.4460808 2.9593498 0.4560776 2 P 0 ;0,1=10,2=270.000000
L 2.9593498 0.4560776 2.9643482 0.4610759 2 P 0 ;0,1=10,2=270.000000
L 2.9593498 0.4760711 2.9643482 0.4710727 2 P 0 ;0,1=10,2=270.000000
L 2.9593498 0.4860679 2.9593498 0.4760711 2 P 0 ;0,1=10,2=270.000000
L 2.9593498 0.501063 2.9793433 0.5210565 2 P 0 ;0,1=10,2=270.000000
L 2.9593498 0.5210565 2.9593498 0.501063 2 P 0 ;0,1=10,2=270.000000
L 2.9643482 0.4410824 2.9593498 0.4460808 2 P 0 ;0,1=10,2=270.000000
L 2.9643482 0.4910662 2.9593498 0.4860679 2 P 0 ;0,1=10,2=270.000000
L 2.974345 0.4710727 2.9793433 0.4810695 2 P 0 ;0,1=10,2=270.000000
L 2.974345 0.4910662 2.9643482 0.4910662 2 P 0 ;0,1=10,2=270.000000
L 2.9793433 0.4810695 2.9793433 0.4860679 2 P 0 ;0,1=10,2=270.000000
L 2.9793433 0.4860679 2.974345 0.4910662 2 P 0 ;0,1=10,2=270.000000
L 2.9793433 0.5210565 2.9843417 0.5210565 2 P 0 ;0,1=10,2=270.000000
L 2.9843417 0.4410824 2.9643482 0.4410824 2 P 0 ;0,1=10,2=270.000000
L 2.9843417 0.4610759 2.9893401 0.4560776 2 P 0 ;0,1=10,2=270.000000
L 2.9843417 0.5210565 2.9893401 0.5160582 2 P 0 ;0,1=10,2=270.000000
L 2.9893401 0.4460808 2.9843417 0.4410824 2 P 0 ;0,1=10,2=270.000000
L 2.9893401 0.4560776 2.9893401 0.4460808 2 P 0 ;0,1=10,2=270.000000
L 2.9893401 0.4710727 2.974345 0.4710727 2 P 0 ;0,1=10,2=270.000000
L 2.9893401 0.4910662 2.9893401 0.4710727 2 P 0 ;0,1=10,2=270.000000
L 2.9893401 0.5060614 2.9843417 0.501063 2 P 0 ;0,1=10,2=270.000000
L 2.9893401 0.5160582 2.9893401 0.5060614 2 P 0 ;0,1=10,2=270.000000
L 3.0253498 0.4460808 3.0253498 0.4560776 2 P 0 ;0,1=9,2=270.000000
L 3.0253498 0.4560776 3.0303482 0.4610759 2 P 0 ;0,1=9,2=270.000000
L 3.0253498 0.4760711 3.0303482 0.4710727 2 P 0 ;0,1=9,2=270.000000
L 3.0253498 0.4860679 3.0253498 0.4760711 2 P 0 ;0,1=9,2=270.000000
L 3.0253498 0.5060614 3.0303482 0.501063 2 P 0 ;0,1=9,2=270.000000
L 3.0253498 0.5160582 3.0253498 0.5060614 2 P 0 ;0,1=9,2=270.000000
L 3.0303482 0.4410824 3.0253498 0.4460808 2 P 0 ;0,1=9,2=270.000000
L 3.0303482 0.4910662 3.0253498 0.4860679 2 P 0 ;0,1=9,2=270.000000
L 3.0303482 0.5210565 3.0253498 0.5160582 2 P 0 ;0,1=9,2=270.000000
L 3.0353466 0.5210565 3.0303482 0.5210565 2 P 0 ;0,1=9,2=270.000000
L 3.040345 0.4710727 3.0453433 0.4810695 2 P 0 ;0,1=9,2=270.000000
L 3.040345 0.4910662 3.0303482 0.4910662 2 P 0 ;0,1=9,2=270.000000
L 3.040345 0.5110598 3.040345 0.5160582 2 P 0 ;0,1=9,2=270.000000
L 3.040345 0.5160582 3.0353466 0.5210565 2 P 0 ;0,1=9,2=270.000000
L 3.040345 0.5160582 3.040345 0.5110598 2 P 0 ;0,1=9,2=270.000000
L 3.0453433 0.4810695 3.0453433 0.4860679 2 P 0 ;0,1=9,2=270.000000
L 3.0453433 0.4860679 3.040345 0.4910662 2 P 0 ;0,1=9,2=270.000000
L 3.0453433 0.5210565 3.040345 0.5160582 2 P 0 ;0,1=9,2=270.000000
L 3.0503417 0.4410824 3.0303482 0.4410824 2 P 0 ;0,1=9,2=270.000000
L 3.0503417 0.4610759 3.0553401 0.4560776 2 P 0 ;0,1=9,2=270.000000
L 3.0503417 0.501063 3.0553401 0.5060614 2 P 0 ;0,1=9,2=270.000000
L 3.0503417 0.5210565 3.0453433 0.5210565 2 P 0 ;0,1=9,2=270.000000
L 3.0553401 0.4460808 3.0503417 0.4410824 2 P 0 ;0,1=9,2=270.000000
L 3.0553401 0.4560776 3.0553401 0.4460808 2 P 0 ;0,1=9,2=270.000000
L 3.0553401 0.4710727 3.040345 0.4710727 2 P 0 ;0,1=9,2=270.000000
L 3.0553401 0.4910662 3.0553401 0.4710727 2 P 0 ;0,1=9,2=270.000000
L 3.0553401 0.5060614 3.0553401 0.5160582 2 P 0 ;0,1=9,2=270.000000
L 3.0553401 0.5160582 3.0503417 0.5210565 2 P 0 ;0,1=9,2=270.000000

### steps/pcb/layers/bottom_paste/features
#Layer_Color=128
#
#Feature symbol names
#
$0 r3.937
$1 r1
$2 rect82.874x44.0945
$3 rect28x165
$4 rect28x126
$5 rect45.2756x57.0866
$6 rect25.1969x26.7717
$7 rect57.0866x45.2756
$8 rect26.7717x25.1969

#
#Feature attribute names
#
@0 .geometry
@1 .pad_usage

#
#Feature attribute text strings
#
&0 SMD_RoundX82.8740Y44.0945
&1 SMD_RoundX28.0000Y165.0000
&2 SMD_RoundX28.0000Y126.0000
&3 SMD_RoundX45.2756Y57.0866
&4 SMD_RoundX25.1969Y26.7717
&5 SMD_RoundX57.0866Y45.2756
&6 SMD_RoundX26.7717Y25.1969

#
#Layer features
#
A 1.7712204 0.4310709 1.6275196 0.4310709 1.69937 0.4310709 0 P 0 N
L -0.0001175 0.177913 0.5908825 0.177913 1 P 0
L -0.0004331 0.1781182 0.5901181 0.1781182 0 P 0
L 0.5901181 0.1781182 0.5901181 0.5029213 0 P 0
L 0.5901181 0.5029213 1.312559 0.5029213 0 P 0
L 0.5908825 0.177913 0.5908825 0.502913 1 P 0
L 1.312559 0.313945 1.312559 0.5029213 0 P 0
L 1.312559 0.313945 1.6275197 0.313945 0 P 0
L 1.6275197 0.313945 1.6275197 0.4310709 0 P 0
P 1.7972451 0.1572953 4 P 0 0 ;0=2,1=0
P 1.8366151 0.1377953 3 P 0 0 ;0=1,1=0
P 1.8759851 0.1377953 3 P 0 0 ;0=1,1=0
P 1.9153551 0.1377953 3 P 0 0 ;0=1,1=0
P 1.9547251 0.1377953 3 P 0 0 ;0=1,1=0
P 1.9940951 0.1377953 3 P 0 0 ;0=1,1=0
P 2.0334651 0.1377953 3 P 0 0 ;0=1,1=0
P 2.0728351 0.1377953 3 P 0 0 ;0=1,1=0
P 2.1122051 0.1377953 3 P 0 0 ;0=1,1=0
P 2.1515751 0.1377953 3 P 0 0 ;0=1,1=0
P 2.1909451 0.1377953 3 P 0 0 ;0=1,1=0
P 2.3090551 0.1377953 3 P 0 0 ;0=1,1=0
P 2.3274094 2.944063 5 P 0 0 ;0=3,1=0
P 2.3348425 3.0428426 2 P 0 0 ;0=0,1=0
P 2.3348425 3.1215827 2 P 0 0 ;0=0,1=0
P 2.3348425 3.2003229 2 P 0 0 ;0=0,1=0
P 2.3348425 3.279063 2 P 0 0 ;0=0,1=0
P 2.3484251 0.1377953 3 P 0 0 ;0=1,1=0
P 2.3498425 0.3291339 6 P 0 0 ;0=4,1=0
P 2.3498425 0.3629922 6 P 0 0 ;0=4,1=0
P 2.3519134 2.854063 8 P 0 0 ;0=6,1=0
P 2.3857717 2.854063 8 P 0 0 ;0=6,1=0
P 2.3877951 0.1377953 3 P 0 0 ;0=1,1=0
P 2.3898425 0.3291339 6 P 0 0 ;0=4,1=0
P 2.3898425 0.3629922 6 P 0 0 ;0=4,1=0
P 2.3982756 2.944063 5 P 0 0 ;0=3,1=0
P 2.4271651 0.1377953 3 P 0 0 ;0=1,1=0
P 2.4665351 0.1377953 3 P 0 0 ;0=1,1=0
P 2.4688425 0.3291339 6 P 0 0 ;0=4,1=0
P 2.4688425 0.3629922 6 P 0 0 ;0=4,1=0
P 2.5059051 0.1377953 3 P 0 0 ;0=1,1=0
P 2.5098425 3.0428426 2 P 0 0 ;0=0,1=0
P 2.5098425 3.1215827 2 P 0 0 ;0=0,1=0
P 2.5098425 3.2003229 2 P 0 0 ;0=0,1=0
P 2.5098425 3.279063 2 P 0 0 ;0=0,1=0
P 2.5118425 0.3291339 6 P 0 0 ;0=4,1=0
P 2.5118425 0.3629922 6 P 0 0 ;0=4,1=0
P 2.5452751 0.1377953 3 P 0 0 ;0=1,1=0
P 2.5846451 0.1377953 3 P 0 0 ;0=1,1=0
P 2.6240151 0.1377953 3 P 0 0 ;0=1,1=0
P 2.6328425 2.9716299 7 P 0 0 ;0=5,1=0
P 2.6328425 3.0424961 7 P 0 0 ;0=5,1=0
P 2.6633851 0.1377953 3 P 0 0 ;0=1,1=0
P 2.6648425 0.3291339 6 P 0 0 ;0=4,1=0
P 2.6648425 0.3629922 6 P 0 0 ;0=4,1=0
P 2.7027551 0.1377953 3 P 0 0 ;0=1,1=0
P 2.7048425 0.3291339 6 P 0 0 ;0=4,1=0
P 2.7048425 0.3629922 6 P 0 0 ;0=4,1=0
P 2.7118425 3.0031338 6 P 0 0 ;0=4,1=0
P 2.7118425 3.0369921 6 P 0 0 ;0=4,1=0
P 2.7421251 0.1377953 3 P 0 0 ;0=1,1=0
P 2.7814951 0.1377953 3 P 0 0 ;0=1,1=0
P 2.8198425 0.3291339 6 P 0 0 ;0=4,1=0
P 2.8198425 0.3629922 6 P 0 0 ;0=4,1=0
P 2.8208651 0.1377953 3 P 0 0 ;0=1,1=0
P 2.8548425 0.3291339 6 P 0 0 ;0=4,1=0
P 2.8548425 0.3629922 6 P 0 0 ;0=4,1=0
P 2.8602351 0.1377953 3 P 0 0 ;0=1,1=0
P 2.8996051 0.1377953 3 P 0 0 ;0=1,1=0
P 2.9389751 0.1377953 3 P 0 0 ;0=1,1=0
P 2.9783451 0.1377953 3 P 0 0 ;0=1,1=0
P 2.9798425 0.3291339 6 P 0 0 ;0=4,1=0
P 2.9798425 0.3629922 6 P 0 0 ;0=4,1=0
P 3.0177151 0.1377953 3 P 0 0 ;0=1,1=0
P 3.0198425 0.3291339 6 P 0 0 ;0=4,1=0
P 3.0198425 0.3629922 6 P 0 0 ;0=4,1=0
P 3.0570851 0.1377953 3 P 0 0 ;0=1,1=0
P 3.0964551 0.1377953 3 P 0 0 ;0=1,1=0

### steps/pcb/layers/bottom_solder/features
#Layer_Color=16711935
#
#Feature symbol names
#
$0 r3.937
$1 r1
$2 rect314.9607x135.8267
$3 rect1354.3307x230.315
$4 rect90.874x52.0945
$5 rect36x173
$6 rect36x134
$7 rect53.2756x65.0866
$8 rect33.1969x34.7717
$9 rect65.0866x53.2756
$10 rect34.7717x33.1969
$11 r8
$12 s8
$13 r29.66
$14 r250
$15 r63
$16 s63
$17 r83
$18 r69.0236
$19 s69.0236
$20 r39.4961
$21 r73.9843
$22 r106.4252
$23 oval204.8504x106.4252
$24 oval185.1654x96.5827
$25 oval96.5827x185.1654
$26 r128
$27 r120
$28 r58
$29 r24
$30 r208

#
#Feature attribute names
#
@0 .geometry
@1 .pad_usage

#
#Feature attribute text strings
#
&0 SMD_RoundX82.8740Y44.0945
&1 SMD_RoundX28.0000Y165.0000
&2 SMD_RoundX28.0000Y126.0000
&3 SMD_RoundX45.2756Y57.0866
&4 SMD_RoundX25.1969Y26.7717
&5 SMD_RoundX57.0866Y45.2756
&6 SMD_RoundX26.7717Y25.1969
&7 Pad_Simple_X0.0000Y0.0000H29.9213C69.9213
&8 Pad_Simple_X0.0000Y0.0000H118.1100C158.1100
&9 Pad_Simple_X21.6600Y21.6600H21.6600C61.6600
&10 Pad_Simple_X250.0000Y250.0000H125.1969C165.1969
&11 Pad_Simple_X55.0000Y55.0000H30.0000C70.0000
&12 Pad_Simple_X75.0000Y75.0000H50.0000C90.0000
&13 Pad_Simple_X61.0236Y61.0236H41.3386C81.3386
&14 Pad_Simple_X31.4961Y31.4961H35.4331C75.4331
&15 Pad_Simple_X65.9843Y65.9843H65.9843C105.9843
&16 Pad_Simple_X98.4252Y98.4252H64.9606C104.9606
&17 Pad_Simple_X196.8504Y98.4252H39.3701C79.3701
&18 Pad_Simple_X177.1654Y88.5827H39.3701C79.3701
&19 Pad_Simple_X88.5827Y177.1654H39.3701C79.3701
&20 Pad_Simple_X120.0000Y120.0000H68.0000C108.0000
&21 Pad_Simple_X112.0000Y112.0000H60.0000C100.0000
&22 Pad_Complex_X50.0000Y50.0000H118.1102C158.1102
&23 Pad_Simple_X98.4252Y98.4252H70.8661C110.8661
&24 Pad_Simple_X50.0000Y50.0000H118.1102C158.1102
&25 VIA_RoundD16.0000H8.0000C48.0000
&26 VIA_RoundD200.0000H125.9843C165.9843

#
#Layer features
#
A 1.7712204 0.4310709 1.6275196 0.4310709 1.69937 0.4310709 0 P 0 N
L -0.0001175 0.177913 0.5908825 0.177913 1 P 0
L -0.0004331 0.1781182 0.5901181 0.1781182 0 P 0
L 0.5901181 0.1781182 0.5901181 0.5029213 0 P 0
L 0.5901181 0.5029213 1.312559 0.5029213 0 P 0
L 0.5908825 0.177913 0.5908825 0.502913 1 P 0
L 1.312559 0.313945 1.312559 0.5029213 0 P 0
L 1.312559 0.313945 1.6275197 0.313945 0 P 0
L 1.6275197 0.313945 1.6275197 0.4310709 0 P 0
P 0.0998425 0.806063 26 P 0 0 ;0=20,1=0
P 0.0998425 1.006063 26 P 0 0 ;0=20,1=0
P 0.0998425 1.331063 26 P 0 0 ;0=20,1=0
P 0.0998425 1.531063 26 P 0 0 ;0=20,1=0
P 0.0998425 1.856063 26 P 0 0 ;0=20,1=0
P 0.0998425 2.056063 26 P 0 0 ;0=20,1=0
P 0.0998425 2.381063 26 P 0 0 ;0=20,1=0
P 0.0998425 2.581063 26 P 0 0 ;0=20,1=0
P 0.1998425 0.906063 27 P 0 0 ;0=21,1=0
P 0.1998425 1.431063 27 P 0 0 ;0=21,1=0
P 0.1998425 1.956063 27 P 0 0 ;0=21,1=0
P 0.1998425 2.481063 27 P 0 0 ;0=21,1=0
P 0.285433 4.152063 14 P 0 0 ;0=10,1=0
P 0.2854331 0.3681102 14 P 0 0 ;0=10,1=0
P 0.2998425 0.806063 26 P 0 0 ;0=20,1=0
P 0.2998425 1.006063 26 P 0 0 ;0=20,1=0
P 0.2998425 1.331063 26 P 0 0 ;0=20,1=0
P 0.2998425 1.531063 26 P 0 0 ;0=20,1=0
P 0.2998425 1.856063 26 P 0 0 ;0=20,1=0
P 0.2998425 2.056063 26 P 0 0 ;0=20,1=0
P 0.2998425 2.381063 26 P 0 0 ;0=20,1=0
P 0.2998425 2.581063 26 P 0 0 ;0=20,1=0
P 1.4576771 4.053937 15 P 0 0 ;0=11,1=0
P 1.4576771 4.153937 15 P 0 0 ;0=11,1=0
P 1.4576771 4.253937 16 P 0 0 ;0=11,1=0
P 1.4704724 0.2450787 2 P 0 0
P 1.6519425 2.486293 12 P 0 0 ;0=8,1=0
P 1.6529425 0.916293 12 P 0 0 ;0=8,1=0
P 1.6968325 1.309833 13 P 0 0 ;0=9,1=0
P 1.6968325 2.097233 13 P 0 0 ;0=9,1=0
P 1.7972451 0.1572953 6 P 0 0 ;0=2,1=0
P 1.8366151 0.1377953 5 P 0 0 ;0=1,1=0
P 1.8759851 0.1377953 5 P 0 0 ;0=1,1=0
P 1.9153551 0.1377953 5 P 0 0 ;0=1,1=0
P 1.9547251 0.1377953 5 P 0 0 ;0=1,1=0
P 1.9940951 0.1377953 5 P 0 0 ;0=1,1=0
P 2.0334651 0.1377953 5 P 0 0 ;0=1,1=0
P 2.0433071 4.057874 15 P 0 0 ;0=11,1=0
P 2.0433071 4.157874 15 P 0 0 ;0=11,1=0
P 2.0433071 4.257874 16 P 0 0 ;0=11,1=0
P 2.0728351 0.1377953 5 P 0 0 ;0=1,1=0
P 2.1122051 0.1377953 5 P 0 0 ;0=1,1=0
P 2.1515751 0.1377953 5 P 0 0 ;0=1,1=0
P 2.1909451 0.1377953 5 P 0 0 ;0=1,1=0
P 2.2031325 2.438533 13 P 0 0 ;0=9,1=0
P 2.2031425 0.958593 13 P 0 0 ;0=9,1=0
P 2.3090551 0.1377953 5 P 0 0 ;0=1,1=0
P 2.3274094 2.944063 7 P 0 0 ;0=3,1=0
P 2.3348425 3.0428426 4 P 0 0 ;0=0,1=0
P 2.3348425 3.1215827 4 P 0 0 ;0=0,1=0
P 2.3348425 3.2003229 4 P 0 0 ;0=0,1=0
P 2.3348425 3.279063 4 P 0 0 ;0=0,1=0
P 2.3484251 0.1377953 5 P 0 0 ;0=1,1=0
P 2.3498425 0.3291339 8 P 0 0 ;0=4,1=0
P 2.3498425 0.3629922 8 P 0 0 ;0=4,1=0
P 2.3519134 2.854063 10 P 0 0 ;0=6,1=0
P 2.3857717 2.854063 10 P 0 0 ;0=6,1=0
P 2.3877951 0.1377953 5 P 0 0 ;0=1,1=0
P 2.3898425 0.3291339 8 P 0 0 ;0=4,1=0
P 2.3898425 0.3629922 8 P 0 0 ;0=4,1=0
P 2.3982756 2.944063 7 P 0 0 ;0=3,1=0
P 2.4223425 3.0822126 11 P 0 0 ;0=7,1=0
P 2.4223425 3.2396929 11 P 0 0 ;0=7,1=0
P 2.4223425 3.4438977 11 P 0 0 ;0=7,1=0
P 2.4223425 3.601378 11 P 0 0 ;0=7,1=0
P 2.4271651 0.1377953 5 P 0 0 ;0=1,1=0
P 2.4468503 0.1112205 3 P 0 0
P 2.4665351 0.1377953 5 P 0 0 ;0=1,1=0
P 2.4688425 0.3291339 8 P 0 0 ;0=4,1=0
P 2.4688425 0.3629922 8 P 0 0 ;0=4,1=0
P 2.5059051 0.1377953 5 P 0 0 ;0=1,1=0
P 2.5098425 3.0428426 4 P 0 0 ;0=0,1=0
P 2.5098425 3.1215827 4 P 0 0 ;0=0,1=0
P 2.5098425 3.2003229 4 P 0 0 ;0=0,1=0
P 2.5098425 3.279063 4 P 0 0 ;0=0,1=0
P 2.5118425 0.3291339 8 P 0 0 ;0=4,1=0
P 2.5118425 0.3629922 8 P 0 0 ;0=4,1=0
P 2.5452751 0.1377953 5 P 0 0 ;0=1,1=0
P 2.5846451 0.1377953 5 P 0 0 ;0=1,1=0
P 2.6240151 0.1377953 5 P 0 0 ;0=1,1=0
P 2.6328425 2.9716299 9 P 0 0 ;0=5,1=0
P 2.6328425 3.0424961 9 P 0 0 ;0=5,1=0
P 2.6633851 0.1377953 5 P 0 0 ;0=1,1=0
P 2.6648425 0.3291339 8 P 0 0 ;0=4,1=0
P 2.6648425 0.3629922 8 P 0 0 ;0=4,1=0
P 2.7027551 0.1377953 5 P 0 0 ;0=1,1=0
P 2.7048425 0.3291339 8 P 0 0 ;0=4,1=0
P 2.7048425 0.3629922 8 P 0 0 ;0=4,1=0
P 2.7118425 3.0031338 8 P 0 0 ;0=4,1=0
P 2.7118425 3.0369921 8 P 0 0 ;0=4,1=0
P 2.7421251 0.1377953 5 P 0 0 ;0=1,1=0
P 2.7814951 0.1377953 5 P 0 0 ;0=1,1=0
P 2.8198425 0.3291339 8 P 0 0 ;0=4,1=0
P 2.8198425 0.3629922 8 P 0 0 ;0=4,1=0
P 2.8208651 0.1377953 5 P 0 0 ;0=1,1=0
P 2.8548425 0.3291339 8 P 0 0 ;0=4,1=0
P 2.8548425 0.3629922 8 P 0 0 ;0=4,1=0
P 2.8602351 0.1377953 5 P 0 0 ;0=1,1=0
P 2.8996051 0.1377953 5 P 0 0 ;0=1,1=0
P 2.9389751 0.1377953 5 P 0 0 ;0=1,1=0
P 2.9783451 0.1377953 5 P 0 0 ;0=1,1=0
P 2.9798425 0.3291339 8 P 0 0 ;0=4,1=0
P 2.9798425 0.3629922 8 P 0 0 ;0=4,1=0
P 2.9905325 2.438533 13 P 0 0 ;0=9,1=0
P 2.9905425 0.958593 13 P 0 0 ;0=9,1=0
P 2.9948425 4.0861024 21 P 0 0 ;0=15,1=0
P 3.0177151 0.1377953 5 P 0 0 ;0=1,1=0
P 3.0198425 0.3291339 8 P 0 0 ;0=4,1=0
P 3.0198425 0.3629922 8 P 0 0 ;0=4,1=0
P 3.0570851 0.1377953 5 P 0 0 ;0=1,1=0
P 3.0964551 0.1377953 5 P 0 0 ;0=1,1=0
P 3.2948425 4.0861024 21 P 0 0 ;0=15,1=0
P 3.5717425 1.309793 13 P 0 0 ;0=9,1=0
P 3.5717425 2.097193 13 P 0 0 ;0=9,1=0
P 3.6179425 0.916293 12 P 0 0 ;0=8,1=0
P 3.6179425 2.486293 12 P 0 0 ;0=8,1=0
P 3.7848425 4.126063 20 P 0 0 ;0=14,1=0
P 3.9580709 4.126063 20 P 0 0 ;0=14,1=0
P 3.9797272 0.8906186 17 P 0 0 ;0=12,1=0
P 3.9797272 2.4890438 17 P 0 0 ;0=12,1=0
P 4.0624044 2.595343 17 P 0 0 ;0=12,1=0
P 4.1805146 2.595343 17 P 0 0 ;0=12,1=0
P 4.2986248 2.595343 17 P 0 0 ;0=12,1=0
P 4.3277559 1.0074803 19 P 0 0 ;0=13,1=0
P 4.3277559 2.3074803 18 P 0 0 ;0=13,1=0
P 4.7277559 2.3074803 18 P 0 0 ;0=13,1=0
P 4.9277559 1.0074803 18 P 0 0 ;0=13,1=0
P 4.9277559 2.3074803 18 P 0 0 ;0=13,1=0
P 5.1277559 1.0074803 18 P 0 0 ;0=13,1=0
P 5.1277559 2.3074803 18 P 0 0 ;0=13,1=0
P 5.3277559 1.0074803 18 P 0 0 ;0=13,1=0
P 5.3277559 2.3074803 18 P 0 0 ;0=13,1=0
P 5.5781524 0.8906186 17 P 0 0 ;0=12,1=0
P 5.5781524 1.6898312 17 P 0 0 ;0=12,1=0
P 5.5781524 2.4890438 17 P 0 0 ;0=12,1=0
P 5.7234252 3.8444882 22 P 0 0 ;0=16,1=0
P 5.7234252 4.0255906 22 P 0 0 ;0=16,1=0
P 5.9348031 3.9379527 25 P 0 0 ;0=19,1=0
P 6.1198425 3.8198425 23 P 0 0 ;0=17,1=0
P 6.1198425 4.056063 24 P 0 0 ;0=18,1=0
P 6.5694882 3.5895276 22 P 0 0 ;0=23,1=0
P 6.5694882 3.806063 22 P 0 0 ;0=23,1=0
P 6.5694882 4.0934646 28 P 0 0 ;0=22,1=0
P 6.7348425 3.5895276 22 P 0 0 ;0=23,1=0
P 6.7348425 3.806063 22 P 0 0 ;0=23,1=0
P 6.9001969 3.5895276 22 P 0 0 ;0=23,1=0
P 6.9001969 3.806063 22 P 0 0 ;0=23,1=0
P 6.9001969 4.0934646 28 P 0 0 ;0=24,1=0
P 0.149508 2.830047 30 P 0 0 ;0=26,1=1
P 0.149508 3.853669 30 P 0 0 ;0=26,1=1
P 0.6538425 1.551063 29 P 0 0 ;0=25,1=1
P 0.6539669 2.5938902 29 P 0 0 ;0=25,1=1
P 0.6548425 0.790063 29 P 0 0 ;0=25,1=1
P 0.6548425 1.314063 29 P 0 0 ;0=25,1=1
P 0.6548425 1.839063 29 P 0 0 ;0=25,1=1
P 0.6548425 2.073063 29 P 0 0 ;0=25,1=1
P 0.6548425 2.365063 29 P 0 0 ;0=25,1=1
P 0.6558425 1.028063 29 P 0 0 ;0=25,1=1
P 0.9370078 2.3179133 29 P 0 0 ;0=25,1=1
P 0.988189 1.7175197 29 P 0 0 ;0=25,1=1
P 0.9901575 0.6870079 29 P 0 0 ;0=25,1=1
P 0.996063 1.1870079 29 P 0 0 ;0=25,1=1
P 0.9968357 2.256036 29 P 0 0 ;0=25,1=1
P 1.0048425 0.906063 29 P 0 0 ;0=25,1=1
P 1.0088425 1.430063 29 P 0 0 ;0=25,1=1
P 1.0098425 1.956063 29 P 0 0 ;0=25,1=1
P 1.0208425 2.481063 29 P 0 0 ;0=25,1=1
P 1.2428425 1.472063 29 P 0 0 ;0=25,1=1
P 1.2488425 2.000063 29 P 0 0 ;0=25,1=1
P 1.2568425 0.942063 29 P 0 0 ;0=25,1=1
P 1.2618425 2.482063 29 P 0 0 ;0=25,1=1
P 1.2948425 4.256063 29 P 0 0 ;0=25,1=1
P 1.3454724 4.1751969 29 P 0 0 ;0=25,1=1
P 1.3937008 1.8169291 29 P 0 0 ;0=25,1=1
P 1.4084645 3.980315 29 P 0 0 ;0=25,1=1
P 1.4408425 3.557063 29 P 0 0 ;0=25,1=1
P 1.4598425 3.147063 29 P 0 0 ;0=25,1=1
P 1.5498425 3.621063 29 P 0 0 ;0=25,1=1
P 1.5578425 4.229063 29 P 0 0 ;0=25,1=1
P 1.5679134 1.2854331 29 P 0 0 ;0=25,1=1
P 1.5682025 2.067703 29 P 0 0 ;0=25,1=1
P 1.5698819 4.1712599 29 P 0 0 ;0=25,1=1
P 1.5748425 3.596063 29 P 0 0 ;0=25,1=1
P 1.6198425 2.121063 29 P 0 0 ;0=25,1=1
P 1.6708425 1.595063 29 P 0 0 ;0=25,1=1
P 1.6708425 1.694063 29 P 0 0 ;0=25,1=1
P 1.6718425 1.399063 29 P 0 0 ;0=25,1=1
P 1.6718425 1.497063 29 P 0 0 ;0=25,1=1
P 1.6718425 1.792063 29 P 0 0 ;0=25,1=1
P 1.6748425 1.989063 29 P 0 0 ;0=25,1=1
P 1.6758425 1.891063 29 P 0 0 ;0=25,1=1
P 1.6918425 4.079063 29 P 0 0 ;0=25,1=1
P 1.7148425 1.595063 29 P 0 0 ;0=25,1=1
P 1.7168425 1.399063 29 P 0 0 ;0=25,1=1
P 1.7188425 1.497063 29 P 0 0 ;0=25,1=1
P 1.7188425 1.792063 29 P 0 0 ;0=25,1=1
P 1.7198425 1.536063 29 P 0 0 ;0=25,1=1
P 1.7218425 1.694063 29 P 0 0 ;0=25,1=1
P 1.7218425 1.890063 29 P 0 0 ;0=25,1=1
P 1.7218425 1.989063 29 P 0 0 ;0=25,1=1
P 1.7268425 4.329374 29 P 0 0 ;0=25,1=1
P 1.7498425 4.110063 29 P 0 0 ;0=25,1=1
P 1.7548425 2.126063 29 P 0 0 ;0=25,1=1
P 1.7548425 3.661063 29 P 0 0 ;0=25,1=1
P 1.7798425 4.156063 29 P 0 0 ;0=25,1=1
P 1.7888425 4.329374 29 P 0 0 ;0=25,1=1
P 1.7978425 0.355063 29 P 0 0 ;0=25,1=1
P 1.7982283 1.3041339 29 P 0 0 ;0=25,1=1
P 1.8227825 1.674003 29 P 0 0 ;0=25,1=1
P 1.8326771 0.2559055 29 P 0 0 ;0=25,1=1
P 1.8326771 0.2874016 29 P 0 0 ;0=25,1=1
P 1.8498425 3.701063 29 P 0 0 ;0=25,1=1
P 1.8523622 0.2559055 29 P 0 0 ;0=25,1=1
P 1.8523622 0.2874016 29 P 0 0 ;0=25,1=1
P 1.8720472 0.2559055 29 P 0 0 ;0=25,1=1
P 1.8720472 0.2874016 29 P 0 0 ;0=25,1=1
P 1.8799377 1.811803 29 P 0 0 ;0=25,1=1
P 1.8848425 2.071063 29 P 0 0 ;0=25,1=1
P 1.8848425 3.601063 29 P 0 0 ;0=25,1=1
P 1.8938425 1.693063 29 P 0 0 ;0=25,1=1
P 1.8973025 1.516523 29 P 0 0 ;0=25,1=1
P 1.9038425 4.018063 29 P 0 0 ;0=25,1=1
P 1.9161425 0.244763 29 P 0 0 ;0=25,1=1
P 2.0048425 1.336063 29 P 0 0 ;0=25,1=1
P 2.0048425 3.816063 29 P 0 0 ;0=25,1=1
P 2.0288425 1.361663 29 P 0 0 ;0=25,1=1
P 2.0298425 3.836063 29 P 0 0 ;0=25,1=1
P 2.0348425 0.246063 29 P 0 0 ;0=25,1=1
P 2.0598425 1.386063 29 P 0 0 ;0=25,1=1
P 2.0598425 3.871063 29 P 0 0 ;0=25,1=1
P 2.0767716 0.2559055 29 P 0 0 ;0=25,1=1
P 2.0767716 0.2874016 29 P 0 0 ;0=25,1=1
P 2.0838425 1.411663 29 P 0 0 ;0=25,1=1
P 2.0848425 3.896063 29 P 0 0 ;0=25,1=1
P 2.1122047 0.2559055 29 P 0 0 ;0=25,1=1
P 2.1122047 0.2874016 29 P 0 0 ;0=25,1=1
P 2.1398425 3.611063 29 P 0 0 ;0=25,1=1
P 2.1398425 3.738063 29 P 0 0 ;0=25,1=1
P 2.1460663 4.1037909 29 P 0 0 ;0=25,1=1
P 2.1468425 2.753063 29 P 0 0 ;0=25,1=1
P 2.1515748 0.2559055 29 P 0 0 ;0=25,1=1
P 2.1515748 0.2874016 29 P 0 0 ;0=25,1=1
P 2.2058425 3.200063 29 P 0 0 ;0=25,1=1
P 2.2068425 1.298063 29 P 0 0 ;0=25,1=1
P 2.2317425 2.584163 29 P 0 0 ;0=25,1=1
P 2.2348425 3.506063 29 P 0 0 ;0=25,1=1
P 2.2523425 2.613563 29 P 0 0 ;0=25,1=1
P 2.2538425 2.279063 29 P 0 0 ;0=25,1=1
P 2.253937 4.0866142 29 P 0 0 ;0=25,1=1
P 2.2548425 3.536063 29 P 0 0 ;0=25,1=1
P 2.2588425 3.741063 29 P 0 0 ;0=25,1=1
P 2.2598425 3.261063 29 P 0 0 ;0=25,1=1
P 2.2720325 2.463873 29 P 0 0 ;0=25,1=1
P 2.2748425 1.506063 29 P 0 0 ;0=25,1=1
P 2.2908425 4.217063 29 P 0 0 ;0=25,1=1
P 2.2998425 1.916063 29 P 0 0 ;0=25,1=1
P 2.3098425 0.246063 29 P 0 0 ;0=25,1=1
P 2.3114125 1.0900094 29 P 0 0 ;0=25,1=1
P 2.3118425 0.934063 29 P 0 0 ;0=25,1=1
P 2.3215354 2.586063 29 P 0 0 ;0=25,1=1
P 2.3215354 3.361063 29 P 0 0 ;0=25,1=1
P 2.3308425 2.215063 29 P 0 0 ;0=25,1=1
P 2.3503937 0.4055118 29 P 0 0 ;0=25,1=1
P 2.3533464 4.0177165 29 P 0 0 ;0=25,1=1
P 2.3848425 1.941063 29 P 0 0 ;0=25,1=1
P 2.3897638 0.4055118 29 P 0 0 ;0=25,1=1
P 2.3898425 3.481063 29 P 0 0 ;0=25,1=1
P 2.394685 2.7204724 29 P 0 0 ;0=25,1=1
P 2.4048425 2.412063 29 P 0 0 ;0=25,1=1
P 2.4098325 0.932053 29 P 0 0 ;0=25,1=1
P 2.4098325 1.088053 29 P 0 0 ;0=25,1=1
P 2.4098425 1.967063 29 P 0 0 ;0=25,1=1
P 2.4098425 2.283063 29 P 0 0 ;0=25,1=1
P 2.4098425 2.314063 29 P 0 0 ;0=25,1=1
P 2.4098425 2.579063 29 P 0 0 ;0=25,1=1
P 2.4133858 0.2795276 29 P 0 0 ;0=25,1=1
P 2.4138425 3.295063 29 P 0 0 ;0=25,1=1
P 2.4140551 3.1998504 29 P 0 0 ;0=25,1=1
P 2.4187174 3.1185066 29 P 0 0 ;0=25,1=1
P 2.4192759 2.7886295 29 P 0 0 ;0=25,1=1
P 2.4291925 2.621063 29 P 0 0 ;0=25,1=1
P 2.4348425 3.546063 29 P 0 0 ;0=25,1=1
P 2.4448819 0.2795276 29 P 0 0 ;0=25,1=1
P 2.4468425 1.437063 29 P 0 0 ;0=25,1=1
P 2.4470546 0.2425914 29 P 0 0 ;0=25,1=1
P 2.4508425 2.282063 29 P 0 0 ;0=25,1=1
P 2.462374 3.1722441 29 P 0 0 ;0=25,1=1
P 2.4698827 0.4109883 29 P 0 0 ;0=25,1=1
P 2.4738425 2.980063 29 P 0 0 ;0=25,1=1
P 2.4758425 2.291063 29 P 0 0 ;0=25,1=1
P 2.4758425 2.456063 29 P 0 0 ;0=25,1=1
P 2.4788425 0.937063 29 P 0 0 ;0=25,1=1
P 2.4888425 2.413063 29 P 0 0 ;0=25,1=1
P 2.4948425 2.661063 29 P 0 0 ;0=25,1=1
P 2.4948425 2.696063 29 P 0 0 ;0=25,1=1
P 2.4998425 2.236063 29 P 0 0 ;0=25,1=1
P 2.5028425 1.316063 29 P 0 0 ;0=25,1=1
P 2.5082625 0.931483 29 P 0 0 ;0=25,1=1
P 2.5088425 1.090063 29 P 0 0 ;0=25,1=1
P 2.511811 0.4055118 29 P 0 0 ;0=25,1=1
P 2.5258425 2.463063 29 P 0 0 ;0=25,1=1
P 2.531398 2.830047 30 P 0 0 ;0=26,1=1
P 2.531398 3.853669 30 P 0 0 ;0=26,1=1
P 2.5460625 0.244843 29 P 0 0 ;0=25,1=1
P 2.5498425 1.755063 29 P 0 0 ;0=25,1=1
P 2.5708425 4.283063 29 P 0 0 ;0=25,1=1
P 2.5758425 2.412063 29 P 0 0 ;0=25,1=1
P 2.5787402 0.2795276 29 P 0 0 ;0=25,1=1
P 2.5798425 1.790063 29 P 0 0 ;0=25,1=1
P 2.5798425 2.281063 29 P 0 0 ;0=25,1=1
P 2.5798425 3.486063 29 P 0 0 ;0=25,1=1
P 2.5818425 2.308063 29 P 0 0 ;0=25,1=1
P 2.5868425 2.569063 29 P 0 0 ;0=25,1=1
P 2.5908425 3.288063 29 P 0 0 ;0=25,1=1
P 2.5918425 3.1862205 29 P 0 0 ;0=25,1=1
P 2.5984252 0.7952756 29 P 0 0 ;0=25,1=1
P 2.5998425 2.436063 29 P 0 0 ;0=25,1=1
P 2.6048425 1.734063 29 P 0 0 ;0=25,1=1
P 2.6066825 0.931903 29 P 0 0 ;0=25,1=1
P 2.6068425 1.091063 29 P 0 0 ;0=25,1=1
P 2.6102362 0.2795276 29 P 0 0 ;0=25,1=1
P 2.6220472 0.976378 29 P 0 0 ;0=25,1=1
P 2.6248425 2.461063 29 P 0 0 ;0=25,1=1
P 2.6259843 0.7952756 29 P 0 0 ;0=25,1=1
P 2.6268425 1.770063 29 P 0 0 ;0=25,1=1
P 2.6318425 2.876063 29 P 0 0 ;0=25,1=1
P 2.6348425 3.406063 29 P 0 0 ;0=25,1=1
P 2.636874 0.2479055 29 P 0 0 ;0=25,1=1
P 2.6438425 1.616063 29 P 0 0 ;0=25,1=1
P 2.6458425 2.274063 29 P 0 0 ;0=25,1=1
P 2.6496063 0.976378 29 P 0 0 ;0=25,1=1
P 2.6653543 0.4055118 29 P 0 0 ;0=25,1=1
P 2.6653543 0.7952756 29 P 0 0 ;0=25,1=1
P 2.6658425 1.092063 29 P 0 0 ;0=25,1=1
P 2.6658425 2.291063 29 P 0 0 ;0=25,1=1
P 2.6668425 1.640063 29 P 0 0 ;0=25,1=1
P 2.6748425 3.501063 29 P 0 0 ;0=25,1=1
P 2.6798425 3.661063 29 P 0 0 ;0=25,1=1
P 2.6811024 0.976378 29 P 0 0 ;0=25,1=1
P 2.6858425 2.311063 29 P 0 0 ;0=25,1=1
P 2.6858425 2.568063 29 P 0 0 ;0=25,1=1
P 2.6929134 0.7952756 29 P 0 0 ;0=25,1=1
P 2.6929134 2.7214567 29 P 0 0 ;0=25,1=1
P 2.6948425 1.481063 29 P 0 0 ;0=25,1=1
P 2.7028425 2.289063 29 P 0 0 ;0=25,1=1
P 2.7047244 0.4055118 29 P 0 0 ;0=25,1=1
P 2.7086614 0.976378 29 P 0 0 ;0=25,1=1
P 2.7198425 1.591063 29 P 0 0 ;0=25,1=1
P 2.7224094 3.7860709 29 P 0 0 ;0=25,1=1
P 2.7244825 1.093063 29 P 0 0 ;0=25,1=1
P 2.7248425 3.521063 29 P 0 0 ;0=25,1=1
P 2.7248425 3.729063 29 P 0 0 ;0=25,1=1
P 2.7268425 2.293063 29 P 0 0 ;0=25,1=1
P 2.7322835 0.7952756 29 P 0 0 ;0=25,1=1
P 2.7401575 0.976378 29 P 0 0 ;0=25,1=1
P 2.74882 0.282312 29 P 0 0 ;0=25,1=1
P 2.7598425 0.7952756 29 P 0 0 ;0=25,1=1
P 2.7677165 0.976378 29 P 0 0 ;0=25,1=1
P 2.7748425 3.566063 29 P 0 0 ;0=25,1=1
P 2.7795276 0.2795276 29 P 0 0 ;0=25,1=1
P 2.7838425 2.429063 29 P 0 0 ;0=25,1=1
P 2.7838425 2.568063 29 P 0 0 ;0=25,1=1
P 2.7841625 1.094063 29 P 0 0 ;0=25,1=1
P 2.7992126 0.7952756 29 P 0 0 ;0=25,1=1
P 2.7992126 0.976378 29 P 0 0 ;0=25,1=1
P 2.7998425 3.616063 29 P 0 0 ;0=25,1=1
P 2.7999951 0.2519685 29 P 0 0 ;0=25,1=1
P 2.8038425 2.307063 29 P 0 0 ;0=25,1=1
P 2.8218425 2.601063 29 P 0 0 ;0=25,1=1
P 2.8219832 0.4078519 29 P 0 0 ;0=25,1=1
P 2.8267717 0.7952756 29 P 0 0 ;0=25,1=1
P 2.8267717 0.976378 29 P 0 0 ;0=25,1=1
P 2.8418425 2.263063 29 P 0 0 ;0=25,1=1
P 2.8428425 1.095063 29 P 0 0 ;0=25,1=1
P 2.8543307 0.4055118 29 P 0 0 ;0=25,1=1
P 2.8608425 3.787063 29 P 0 0 ;0=25,1=1
P 2.8622047 0.7952756 29 P 0 0 ;0=25,1=1
P 2.8718425 2.297063 29 P 0 0 ;0=25,1=1
P 2.8782843 0.2495967 29 P 0 0 ;0=25,1=1
P 2.8818425 2.566063 29 P 0 0 ;0=25,1=1
P 2.8888425 4.221063 29 P 0 0 ;0=25,1=1
P 2.8937008 0.7952756 29 P 0 0 ;0=25,1=1
P 2.8948425 1.561063 29 P 0 0 ;0=25,1=1
P 2.8948425 2.431063 29 P 0 0 ;0=25,1=1
P 2.9018425 1.095063 29 P 0 0 ;0=25,1=1
P 2.9054946 0.2795104 29 P 0 0 ;0=25,1=1
P 2.9198425 1.536063 29 P 0 0 ;0=25,1=1
P 2.9208425 2.428063 29 P 0 0 ;0=25,1=1
P 2.9338425 0.953063 29 P 0 0 ;0=25,1=1
P 2.9370079 0.2795276 29 P 0 0 ;0=25,1=1
P 2.9428425 2.286063 29 P 0 0 ;0=25,1=1
P 2.9488425 2.456063 29 P 0 0 ;0=25,1=1
P 2.9574751 0.2519685 29 P 0 0 ;0=25,1=1
P 2.9588425 2.621063 29 P 0 0 ;0=25,1=1
P 2.980457 0.4091539 29 P 0 0 ;0=25,1=1
P 2.9858425 2.287063 29 P 0 0 ;0=25,1=1
P 2.9933858 3.751063 29 P 0 0 ;0=25,1=1
P 3.0148425 3.831063 29 P 0 0 ;0=25,1=1
P 3.019685 0.4055118 29 P 0 0 ;0=25,1=1
P 3.0568817 1.811803 29 P 0 0 ;0=25,1=1
P 3.0688976 3.3956693 29 P 0 0 ;0=25,1=1
P 3.0974409 0.2519685 29 P 0 0 ;0=25,1=1
P 3.1830708 3.1358268 29 P 0 0 ;0=25,1=1
P 3.1889764 3.1870079 29 P 0 0 ;0=25,1=1
P 3.1972633 1.714063 29 P 0 0 ;0=25,1=1
P 3.1978425 2.970063 29 P 0 0 ;0=25,1=1
P 3.2198425 3.806063 29 P 0 0 ;0=25,1=1
P 3.2248425 1.6613472 29 P 0 0 ;0=25,1=1
P 3.2308425 3.235063 29 P 0 0 ;0=25,1=1
P 3.2398425 3.596063 29 P 0 0 ;0=25,1=1
P 3.2528425 1.661063 29 P 0 0 ;0=25,1=1
P 3.2636972 3.3039177 29 P 0 0 ;0=25,1=1
P 3.2698425 3.788063 29 P 0 0 ;0=25,1=1
P 3.2755905 3.1417323 29 P 0 0 ;0=25,1=1
P 3.277559 2.9635827 29 P 0 0 ;0=25,1=1
P 3.2988425 1.971063 29 P 0 0 ;0=25,1=1
P 3.3028425 3.344063 29 P 0 0 ;0=25,1=1
P 3.3291721 1.826063 29 P 0 0 ;0=25,1=1
P 3.3308425 3.301063 29 P 0 0 ;0=25,1=1
P 3.3428425 2.263063 29 P 0 0 ;0=25,1=1
P 3.3448425 2.996063 29 P 0 0 ;0=25,1=1
P 3.3588425 3.448063 29 P 0 0 ;0=25,1=1
P 3.3688425 3.050063 29 P 0 0 ;0=25,1=1
P 3.3708425 2.888063 29 P 0 0 ;0=25,1=1
P 3.3748425 3.273063 29 P 0 0 ;0=25,1=1
P 3.3798425 1.336063 29 P 0 0 ;0=25,1=1
P 3.3798425 1.386063 29 P 0 0 ;0=25,1=1
P 3.3928425 1.871063 29 P 0 0 ;0=25,1=1
P 3.3948425 3.447063 29 P 0 0 ;0=25,1=1
P 3.3958425 4.222063 29 P 0 0 ;0=25,1=1
P 3.4048425 1.363323 29 P 0 0 ;0=25,1=1
P 3.4068425 1.461063 29 P 0 0 ;0=25,1=1
P 3.4072822 1.411323 29 P 0 0 ;0=25,1=1
P 3.4108425 1.7136509 29 P 0 0 ;0=25,1=1
P 3.4138425 1.573063 29 P 0 0 ;0=25,1=1
P 3.4144661 1.805063 29 P 0 0 ;0=25,1=1
P 3.4248425 3.636063 29 P 0 0 ;0=25,1=1
P 3.4368425 3.457063 29 P 0 0 ;0=25,1=1
P 3.4392507 1.870938 29 P 0 0 ;0=25,1=1
P 3.4698425 3.456063 29 P 0 0 ;0=25,1=1
P 3.4918425 3.103063 29 P 0 0 ;0=25,1=1
P 3.4918425 3.297063 29 P 0 0 ;0=25,1=1
P 3.4988425 2.341063 29 P 0 0 ;0=25,1=1
P 3.5048425 4.086063 29 P 0 0 ;0=25,1=1
P 3.5298425 3.481063 29 P 0 0 ;0=25,1=1
P 3.5318425 3.660063 29 P 0 0 ;0=25,1=1
P 3.5398425 3.806063 29 P 0 0 ;0=25,1=1
P 3.542865 3.3190405 29 P 0 0 ;0=25,1=1
P 3.5498425 1.413063 29 P 0 0 ;0=25,1=1
P 3.5498425 1.441063 29 P 0 0 ;0=25,1=1
P 3.5548425 1.841063 29 P 0 0 ;0=25,1=1
P 3.5548425 1.891063 29 P 0 0 ;0=25,1=1
P 3.5548425 1.941063 29 P 0 0 ;0=25,1=1
P 3.5548425 1.991063 29 P 0 0 ;0=25,1=1
P 3.5718425 2.033063 29 P 0 0 ;0=25,1=1
P 3.5718425 2.058063 29 P 0 0 ;0=25,1=1
P 3.5898425 1.711063 29 P 0 0 ;0=25,1=1
P 3.5908425 1.662063 29 P 0 0 ;0=25,1=1
P 3.5948425 1.514063 29 P 0 0 ;0=25,1=1
P 3.6038425 0.682063 29 P 0 0 ;0=25,1=1
P 3.6228425 3.486063 29 P 0 0 ;0=25,1=1
P 3.6238425 2.587063 29 P 0 0 ;0=25,1=1
P 3.6428425 0.636063 29 P 0 0 ;0=25,1=1
P 3.6538425 3.293063 29 P 0 0 ;0=25,1=1
P 3.6998425 3.751063 29 P 0 0 ;0=25,1=1
P 3.6998425 3.836063 29 P 0 0 ;0=25,1=1
P 3.7178425 3.072063 29 P 0 0 ;0=25,1=1
P 3.7188425 1.713063 29 P 0 0 ;0=25,1=1
P 3.7198425 1.766063 29 P 0 0 ;0=25,1=1
P 3.7198425 1.921063 29 P 0 0 ;0=25,1=1
P 3.7198425 1.996063 29 P 0 0 ;0=25,1=1
P 3.7248425 1.675063 29 P 0 0 ;0=25,1=1
P 3.7328425 1.418063 29 P 0 0 ;0=25,1=1
P 3.7448425 3.261063 29 P 0 0 ;0=25,1=1
P 3.7448425 3.342063 29 P 0 0 ;0=25,1=1
P 3.7738632 1.6661021 29 P 0 0 ;0=25,1=1
P 3.7778425 4.023063 29 P 0 0 ;0=25,1=1
P 3.7998425 3.201063 29 P 0 0 ;0=25,1=1
P 3.8038425 1.691063 29 P 0 0 ;0=25,1=1
P 3.8048425 1.840063 29 P 0 0 ;0=25,1=1
P 3.8068425 3.235063 29 P 0 0 ;0=25,1=1
P 3.8298425 3.176063 29 P 0 0 ;0=25,1=1
P 3.8298425 3.806063 29 P 0 0 ;0=25,1=1
P 3.8308425 3.762063 29 P 0 0 ;0=25,1=1
P 3.8348425 1.481063 29 P 0 0 ;0=25,1=1
P 3.8548425 3.151063 29 P 0 0 ;0=25,1=1
P 3.8648425 1.511063 29 P 0 0 ;0=25,1=1
P 3.8808425 3.109063 29 P 0 0 ;0=25,1=1
P 3.8948425 1.566063 29 P 0 0 ;0=25,1=1
P 3.9248425 1.536063 29 P 0 0 ;0=25,1=1
P 3.9398425 3.121063 29 P 0 0 ;0=25,1=1
P 3.9448425 1.816063 29 P 0 0 ;0=25,1=1
P 3.9608425 2.724063 29 P 0 0 ;0=25,1=1
P 3.9688425 1.671063 29 P 0 0 ;0=25,1=1
P 3.9698425 1.552063 29 P 0 0 ;0=25,1=1
P 3.9948425 1.551063 29 P 0 0 ;0=25,1=1
P 3.9968425 1.711063 29 P 0 0 ;0=25,1=1
P 4.0348425 1.546063 29 P 0 0 ;0=25,1=1
P 4.0398425 2.406063 29 P 0 0 ;0=25,1=1
P 4.0398425 3.784063 29 P 0 0 ;0=25,1=1
P 4.0498425 3.665063 29 P 0 0 ;0=25,1=1
P 4.0648425 1.511063 29 P 0 0 ;0=25,1=1
P 4.0648425 1.796063 29 P 0 0 ;0=25,1=1
P 4.0648425 2.722063 29 P 0 0 ;0=25,1=1
P 4.0688425 3.135063 29 P 0 0 ;0=25,1=1
P 4.0858425 3.892063 29 P 0 0 ;0=25,1=1
P 4.1148425 3.135063 29 P 0 0 ;0=25,1=1
P 4.1203866 3.5941508 29 P 0 0 ;0=25,1=1
P 4.1318425 1.686063 29 P 0 0 ;0=25,1=1
P 4.1348425 1.651063 29 P 0 0 ;0=25,1=1
P 4.1348425 1.751063 29 P 0 0 ;0=25,1=1
P 4.1513063 1.6236232 29 P 0 0 ;0=25,1=1
P 4.1528425 3.135063 29 P 0 0 ;0=25,1=1
P 4.1798425 1.601063 29 P 0 0 ;0=25,1=1
P 4.1948425 3.884063 29 P 0 0 ;0=25,1=1
P 4.2088425 3.135063 29 P 0 0 ;0=25,1=1
P 4.2348425 2.725063 29 P 0 0 ;0=25,1=1
P 4.2548425 3.776063 29 P 0 0 ;0=25,1=1
P 4.2728425 3.135063 29 P 0 0 ;0=25,1=1
P 4.3338425 3.135063 29 P 0 0 ;0=25,1=1
P 4.3398425 2.725063 29 P 0 0 ;0=25,1=1
P 4.3878425 4.206063 29 P 0 0 ;0=25,1=1
P 4.4318425 3.135063 29 P 0 0 ;0=25,1=1
P 4.4778425 3.135063 29 P 0 0 ;0=25,1=1
P 4.5036614 2.7898819 29 P 0 0 ;0=25,1=1
P 4.7547119 4.1159324 29 P 0 0 ;0=25,1=1
P 4.7942913 2.8080709 29 P 0 0 ;0=25,1=1
P 4.9108425 4.203063 29 P 0 0 ;0=25,1=1
P 5.2670079 4.0888976 29 P 0 0 ;0=25,1=1
P 5.2748425 3.511063 29 P 0 0 ;0=25,1=1
P 5.5778425 2.214063 29 P 0 0 ;0=25,1=1
P 5.6348425 2.236063 29 P 0 0 ;0=25,1=1
P 5.6768425 3.546063 29 P 0 0 ;0=25,1=1
P 5.7338425 3.556063 29 P 0 0 ;0=25,1=1
P 5.9948425 3.552063 29 P 0 0 ;0=25,1=1
P 6.0048425 2.434063 29 P 0 0 ;0=25,1=1
P 6.0488425 2.171063 29 P 0 0 ;0=25,1=1
P 6.253937 2.9094488 29 P 0 0 ;0=25,1=1
P 6.2748425 2.391063 29 P 0 0 ;0=25,1=1
P 6.2824161 3.226063 29 P 0 0 ;0=25,1=1
P 6.2848425 2.501063 29 P 0 0 ;0=25,1=1
P 6.2948425 3.701063 29 P 0 0 ;0=25,1=1
P 6.3048425 3.121063 29 P 0 0 ;0=25,1=1
P 6.3094161 3.199063 29 P 0 0 ;0=25,1=1
P 6.3348425 3.266063 29 P 0 0 ;0=25,1=1
P 6.3398425 3.151063 29 P 0 0 ;0=25,1=1
P 6.3547483 3.3311384 29 P 0 0 ;0=25,1=1
P 6.3720472 2.9094488 29 P 0 0 ;0=25,1=1
P 6.3958425 2.111063 29 P 0 0 ;0=25,1=1
P 6.3968425 2.556063 29 P 0 0 ;0=25,1=1
P 6.3978425 2.501063 29 P 0 0 ;0=25,1=1
P 6.3978425 2.610063 29 P 0 0 ;0=25,1=1
P 6.3988425 2.453063 29 P 0 0 ;0=25,1=1
P 6.3988425 2.657063 29 P 0 0 ;0=25,1=1
P 6.4098425 3.371063 29 P 0 0 ;0=25,1=1
P 6.4248425 2.181063 29 P 0 0 ;0=25,1=1
P 6.4398425 3.191063 29 P 0 0 ;0=25,1=1
P 6.4448425 3.291063 29 P 0 0 ;0=25,1=1
P 6.4475772 3.396063 29 P 0 0 ;0=25,1=1
P 6.4568425 3.009063 29 P 0 0 ;0=25,1=1
P 6.4768425 3.231063 29 P 0 0 ;0=25,1=1
P 6.4798425 3.426063 29 P 0 0 ;0=25,1=1
P 6.5098425 3.456063 29 P 0 0 ;0=25,1=1
P 6.5488425 1.531063 29 P 0 0 ;0=25,1=1
P 6.6018425 1.777063 29 P 0 0 ;0=25,1=1
P 6.6028425 1.612063 29 P 0 0 ;0=25,1=1
P 6.6028425 1.672063 29 P 0 0 ;0=25,1=1
P 6.6028425 1.722063 29 P 0 0 ;0=25,1=1
P 6.6078425 2.176063 29 P 0 0 ;0=25,1=1
P 6.6268425 3.032063 29 P 0 0 ;0=25,1=1
P 6.6288425 1.372063 29 P 0 0 ;0=25,1=1
P 6.6476378 3.1299213 29 P 0 0 ;0=25,1=1
P 6.6488425 3.341063 29 P 0 0 ;0=25,1=1
P 6.6858425 1.828063 29 P 0 0 ;0=25,1=1
P 6.6998425 1.881063 29 P 0 0 ;0=25,1=1
P 6.8448425 1.661063 29 P 0 0 ;0=25,1=1
P 6.9498425 2.095063 29 P 0 0 ;0=25,1=1
P 6.9744094 1.9399606 29 P 0 0 ;0=25,1=1

### steps/pcb/layers/comp_+_bot/features


### steps/pcb/layers/comp_+_top/features


### steps/pcb/layers/drill/features
#Layer_Color=9474304
#
#Feature symbol names
#
$0 r8
$1 r21.66
$2 r29.9213
$3 r30
$4 r39.3701
$5 r41.3386
$6 r50
$7 r60
$8 r64.9606
$9 r68
$10 r70.8661
$11 r118.11
$12 r125.9843
$13 r35.4331
$14 r65.9843
$15 r118.1102
$16 r125.1969

#
#Feature attribute names
#
@0 .geometry
@1 .drill

#
#Feature attribute text strings
#
&0 Pad_Simple_X0.0000Y0.0000H118.1100C158.1100
&1 Pad_Simple_X50.0000Y50.0000H118.1102C158.1102
&2 Pad_Complex_X50.0000Y50.0000H118.1102C158.1102
&3 Pad_Simple_X250.0000Y250.0000H125.1969C165.1969
&4 VIA_RoundD200.0000H125.9843C165.9843
&5 Pad_Simple_X21.6600Y21.6600H21.6600C61.6600
&6 Pad_Simple_X0.0000Y0.0000H29.9213C69.9213
&7 Pad_Simple_X55.0000Y55.0000H30.0000C70.0000
&8 Pad_Simple_X31.4961Y31.4961H35.4331C75.4331
&9 Pad_Simple_88.5827X177.1654D118.1102X39.3701
&10 Pad_Simple_177.1654X88.5827D118.1102X39.3701
&11 Pad_Simple_196.8504X98.4252D137.7953X39.3701
&12 Pad_Simple_X61.0236Y61.0236H41.3386C81.3386
&13 Pad_Simple_X75.0000Y75.0000H50.0000C90.0000
&14 Pad_Simple_X112.0000Y112.0000H60.0000C100.0000
&15 Pad_Simple_X98.4252Y98.4252H64.9606C104.9606
&16 Pad_Simple_X65.9843Y65.9843H65.9843C105.9843
&17 Pad_Simple_X120.0000Y120.0000H68.0000C108.0000
&18 Pad_Simple_X98.4252Y98.4252H70.8661C110.8661
&19 VIA_RoundD16.0000H8.0000C48.0000

#
#Layer features
#
P 0.0998425 0.806063 9 P 0 0 ;0=17,1=0
P 0.0998425 1.006063 9 P 0 0 ;0=17,1=0
P 0.0998425 1.331063 9 P 0 0 ;0=17,1=0
P 0.0998425 1.531063 9 P 0 0 ;0=17,1=0
P 0.0998425 1.856063 9 P 0 0 ;0=17,1=0
P 0.0998425 2.056063 9 P 0 0 ;0=17,1=0
P 0.0998425 2.381063 9 P 0 0 ;0=17,1=0
P 0.0998425 2.581063 9 P 0 0 ;0=17,1=0
P 0.1998425 0.906063 7 P 0 0 ;0=14,1=0
P 0.1998425 1.431063 7 P 0 0 ;0=14,1=0
P 0.1998425 1.956063 7 P 0 0 ;0=14,1=0
P 0.1998425 2.481063 7 P 0 0 ;0=14,1=0
P 0.285433 4.152063 16 P 0 0 ;0=3,1=1
P 0.2854331 0.3681102 16 P 0 0 ;0=3,1=1
P 0.2998425 0.806063 9 P 0 0 ;0=17,1=0
P 0.2998425 1.006063 9 P 0 0 ;0=17,1=0
P 0.2998425 1.331063 9 P 0 0 ;0=17,1=0
P 0.2998425 1.531063 9 P 0 0 ;0=17,1=0
P 0.2998425 1.856063 9 P 0 0 ;0=17,1=0
P 0.2998425 2.056063 9 P 0 0 ;0=17,1=0
P 0.2998425 2.381063 9 P 0 0 ;0=17,1=0
P 0.2998425 2.581063 9 P 0 0 ;0=17,1=0
P 1.4576771 4.053937 3 P 0 0 ;0=7,1=0
P 1.4576771 4.153937 3 P 0 0 ;0=7,1=0
P 1.4576771 4.253937 3 P 0 0 ;0=7,1=0
P 1.6519425 2.486293 11 P 0 0 ;0=0,1=0
P 1.6529425 0.916293 11 P 0 0 ;0=0,1=0
P 1.6968325 1.309833 1 P 0 0 ;0=5,1=0
P 1.6968325 2.097233 1 P 0 0 ;0=5,1=0
P 2.0433071 4.057874 3 P 0 0 ;0=7,1=0
P 2.0433071 4.157874 3 P 0 0 ;0=7,1=0
P 2.0433071 4.257874 3 P 0 0 ;0=7,1=0
P 2.2031325 2.438533 1 P 0 0 ;0=5,1=0
P 2.2031425 0.958593 1 P 0 0 ;0=5,1=0
P 2.4223425 3.0822126 2 P 0 0 ;0=6,1=0
P 2.4223425 3.2396929 2 P 0 0 ;0=6,1=0
P 2.4223425 3.4438977 2 P 0 0 ;0=6,1=0
P 2.4223425 3.601378 2 P 0 0 ;0=6,1=0
P 2.9905325 2.438533 1 P 0 0 ;0=5,1=0
P 2.9905425 0.958593 1 P 0 0 ;0=5,1=0
P 2.9948425 4.0861024 14 P 0 0 ;0=16,1=1
P 3.2948425 4.0861024 14 P 0 0 ;0=16,1=1
P 3.5717425 1.309793 1 P 0 0 ;0=5,1=0
P 3.5717425 2.097193 1 P 0 0 ;0=5,1=0
P 3.6179425 0.916293 11 P 0 0 ;0=0,1=0
P 3.6179425 2.486293 11 P 0 0 ;0=0,1=0
P 3.7848425 4.126063 13 P 0 0 ;0=8,1=1
P 3.9580709 4.126063 13 P 0 0 ;0=8,1=1
P 3.9797272 0.8906186 6 P 0 0 ;0=13,1=0
P 3.9797272 2.4890438 6 P 0 0 ;0=13,1=0
P 4.0624044 2.595343 6 P 0 0 ;0=13,1=0
P 4.1805146 2.595343 6 P 0 0 ;0=13,1=0
P 4.2986248 2.595343 6 P 0 0 ;0=13,1=0
P 4.3277559 1.0074803 5 P 0 0 ;0=12,1=0
P 4.3277559 2.3074803 5 P 0 0 ;0=12,1=0
P 4.7277559 2.3074803 5 P 0 0 ;0=12,1=0
P 4.9277559 1.0074803 5 P 0 0 ;0=12,1=0
P 4.9277559 2.3074803 5 P 0 0 ;0=12,1=0
P 5.1277559 1.0074803 5 P 0 0 ;0=12,1=0
P 5.1277559 2.3074803 5 P 0 0 ;0=12,1=0
P 5.3277559 1.0074803 5 P 0 0 ;0=12,1=0
P 5.3277559 2.3074803 5 P 0 0 ;0=12,1=0
P 5.5781524 0.8906186 6 P 0 0 ;0=13,1=0
P 5.5781524 1.6898312 6 P 0 0 ;0=13,1=0
P 5.5781524 2.4890438 6 P 0 0 ;0=13,1=0
P 5.7234252 3.8444882 8 P 0 0 ;0=15,1=0
P 5.7234252 4.0255906 8 P 0 0 ;0=15,1=0
L 5.9348031 3.9773227 5.9348031 3.8985827 4 P 0 ;0=9,1=0
L 6.1690551 3.8198425 6.0706299 3.8198425 4 P 0 ;0=11,1=0
L 6.1592125 4.056063 6.0804725 4.056063 4 P 0 ;0=10,1=0
P 6.5694882 3.5895276 10 P 0 0 ;0=18,1=0
P 6.5694882 3.806063 10 P 0 0 ;0=18,1=0
P 6.5694882 4.0934646 15 P 0 0 ;0=2,1=1
P 6.7348425 3.5895276 10 P 0 0 ;0=18,1=0
P 6.7348425 3.806063 10 P 0 0 ;0=18,1=0
P 6.9001969 3.5895276 10 P 0 0 ;0=18,1=0
P 6.9001969 3.806063 10 P 0 0 ;0=18,1=0
P 6.9001969 4.0934646 15 P 0 0 ;0=1,1=1
P 0.149508 2.830047 12 P 0 0 ;0=4,1=2
P 0.149508 3.853669 12 P 0 0 ;0=4,1=2
P 0.6538425 1.551063 0 P 0 0 ;0=19,1=2
P 0.6539669 2.5938902 0 P 0 0 ;0=19,1=2
P 0.6548425 0.790063 0 P 0 0 ;0=19,1=2
P 0.6548425 1.314063 0 P 0 0 ;0=19,1=2
P 0.6548425 1.839063 0 P 0 0 ;0=19,1=2
P 0.6548425 2.073063 0 P 0 0 ;0=19,1=2
P 0.6548425 2.365063 0 P 0 0 ;0=19,1=2
P 0.6558425 1.028063 0 P 0 0 ;0=19,1=2
P 0.9370078 2.3179133 0 P 0 0 ;0=19,1=2
P 0.988189 1.7175197 0 P 0 0 ;0=19,1=2
P 0.9901575 0.6870079 0 P 0 0 ;0=19,1=2
P 0.996063 1.1870079 0 P 0 0 ;0=19,1=2
P 0.9968357 2.256036 0 P 0 0 ;0=19,1=2
P 1.0048425 0.906063 0 P 0 0 ;0=19,1=2
P 1.0088425 1.430063 0 P 0 0 ;0=19,1=2
P 1.0098425 1.956063 0 P 0 0 ;0=19,1=2
P 1.0208425 2.481063 0 P 0 0 ;0=19,1=2
P 1.2428425 1.472063 0 P 0 0 ;0=19,1=2
P 1.2488425 2.000063 0 P 0 0 ;0=19,1=2
P 1.2568425 0.942063 0 P 0 0 ;0=19,1=2
P 1.2618425 2.482063 0 P 0 0 ;0=19,1=2
P 1.2948425 4.256063 0 P 0 0 ;0=19,1=2
P 1.3454724 4.1751969 0 P 0 0 ;0=19,1=2
P 1.3937008 1.8169291 0 P 0 0 ;0=19,1=2
P 1.4084645 3.980315 0 P 0 0 ;0=19,1=2
P 1.4408425 3.557063 0 P 0 0 ;0=19,1=2
P 1.4598425 3.147063 0 P 0 0 ;0=19,1=2
P 1.5498425 3.621063 0 P 0 0 ;0=19,1=2
P 1.5578425 4.229063 0 P 0 0 ;0=19,1=2
P 1.5679134 1.2854331 0 P 0 0 ;0=19,1=2
P 1.5682025 2.067703 0 P 0 0 ;0=19,1=2
P 1.5698819 4.1712599 0 P 0 0 ;0=19,1=2
P 1.5748425 3.596063 0 P 0 0 ;0=19,1=2
P 1.6198425 2.121063 0 P 0 0 ;0=19,1=2
P 1.6708425 1.595063 0 P 0 0 ;0=19,1=2
P 1.6708425 1.694063 0 P 0 0 ;0=19,1=2
P 1.6718425 1.399063 0 P 0 0 ;0=19,1=2
P 1.6718425 1.497063 0 P 0 0 ;0=19,1=2
P 1.6718425 1.792063 0 P 0 0 ;0=19,1=2
P 1.6748425 1.989063 0 P 0 0 ;0=19,1=2
P 1.6758425 1.891063 0 P 0 0 ;0=19,1=2
P 1.6918425 4.079063 0 P 0 0 ;0=19,1=2
P 1.7148425 1.595063 0 P 0 0 ;0=19,1=2
P 1.7168425 1.399063 0 P 0 0 ;0=19,1=2
P 1.7188425 1.497063 0 P 0 0 ;0=19,1=2
P 1.7188425 1.792063 0 P 0 0 ;0=19,1=2
P 1.7198425 1.536063 0 P 0 0 ;0=19,1=2
P 1.7218425 1.694063 0 P 0 0 ;0=19,1=2
P 1.7218425 1.890063 0 P 0 0 ;0=19,1=2
P 1.7218425 1.989063 0 P 0 0 ;0=19,1=2
P 1.7268425 4.329374 0 P 0 0 ;0=19,1=2
P 1.7498425 4.110063 0 P 0 0 ;0=19,1=2
P 1.7548425 2.126063 0 P 0 0 ;0=19,1=2
P 1.7548425 3.661063 0 P 0 0 ;0=19,1=2
P 1.7798425 4.156063 0 P 0 0 ;0=19,1=2
P 1.7888425 4.329374 0 P 0 0 ;0=19,1=2
P 1.7978425 0.355063 0 P 0 0 ;0=19,1=2
P 1.7982283 1.3041339 0 P 0 0 ;0=19,1=2
P 1.8227825 1.674003 0 P 0 0 ;0=19,1=2
P 1.8326771 0.2559055 0 P 0 0 ;0=19,1=2
P 1.8326771 0.2874016 0 P 0 0 ;0=19,1=2
P 1.8498425 3.701063 0 P 0 0 ;0=19,1=2
P 1.8523622 0.2559055 0 P 0 0 ;0=19,1=2
P 1.8523622 0.2874016 0 P 0 0 ;0=19,1=2
P 1.8720472 0.2559055 0 P 0 0 ;0=19,1=2
P 1.8720472 0.2874016 0 P 0 0 ;0=19,1=2
P 1.8799377 1.811803 0 P 0 0 ;0=19,1=2
P 1.8848425 2.071063 0 P 0 0 ;0=19,1=2
P 1.8848425 3.601063 0 P 0 0 ;0=19,1=2
P 1.8938425 1.693063 0 P 0 0 ;0=19,1=2
P 1.8973025 1.516523 0 P 0 0 ;0=19,1=2
P 1.9038425 4.018063 0 P 0 0 ;0=19,1=2
P 1.9161425 0.244763 0 P 0 0 ;0=19,1=2
P 2.0048425 1.336063 0 P 0 0 ;0=19,1=2
P 2.0048425 3.816063 0 P 0 0 ;0=19,1=2
P 2.0288425 1.361663 0 P 0 0 ;0=19,1=2
P 2.0298425 3.836063 0 P 0 0 ;0=19,1=2
P 2.0348425 0.246063 0 P 0 0 ;0=19,1=2
P 2.0598425 1.386063 0 P 0 0 ;0=19,1=2
P 2.0598425 3.871063 0 P 0 0 ;0=19,1=2
P 2.0767716 0.2559055 0 P 0 0 ;0=19,1=2
P 2.0767716 0.2874016 0 P 0 0 ;0=19,1=2
P 2.0838425 1.411663 0 P 0 0 ;0=19,1=2
P 2.0848425 3.896063 0 P 0 0 ;0=19,1=2
P 2.1122047 0.2559055 0 P 0 0 ;0=19,1=2
P 2.1122047 0.2874016 0 P 0 0 ;0=19,1=2
P 2.1398425 3.611063 0 P 0 0 ;0=19,1=2
P 2.1398425 3.738063 0 P 0 0 ;0=19,1=2
P 2.1460663 4.1037909 0 P 0 0 ;0=19,1=2
P 2.1468425 2.753063 0 P 0 0 ;0=19,1=2
P 2.1515748 0.2559055 0 P 0 0 ;0=19,1=2
P 2.1515748 0.2874016 0 P 0 0 ;0=19,1=2
P 2.2058425 3.200063 0 P 0 0 ;0=19,1=2
P 2.2068425 1.298063 0 P 0 0 ;0=19,1=2
P 2.2317425 2.584163 0 P 0 0 ;0=19,1=2
P 2.2348425 3.506063 0 P 0 0 ;0=19,1=2
P 2.2523425 2.613563 0 P 0 0 ;0=19,1=2
P 2.2538425 2.279063 0 P 0 0 ;0=19,1=2
P 2.253937 4.0866142 0 P 0 0 ;0=19,1=2
P 2.2548425 3.536063 0 P 0 0 ;0=19,1=2
P 2.2588425 3.741063 0 P 0 0 ;0=19,1=2
P 2.2598425 3.261063 0 P 0 0 ;0=19,1=2
P 2.2720325 2.463873 0 P 0 0 ;0=19,1=2
P 2.2748425 1.506063 0 P 0 0 ;0=19,1=2
P 2.2908425 4.217063 0 P 0 0 ;0=19,1=2
P 2.2998425 1.916063 0 P 0 0 ;0=19,1=2
P 2.3098425 0.246063 0 P 0 0 ;0=19,1=2
P 2.3114125 1.0900094 0 P 0 0 ;0=19,1=2
P 2.3118425 0.934063 0 P 0 0 ;0=19,1=2
P 2.3215354 2.586063 0 P 0 0 ;0=19,1=2
P 2.3215354 3.361063 0 P 0 0 ;0=19,1=2
P 2.3308425 2.215063 0 P 0 0 ;0=19,1=2
P 2.3503937 0.4055118 0 P 0 0 ;0=19,1=2
P 2.3533464 4.0177165 0 P 0 0 ;0=19,1=2
P 2.3848425 1.941063 0 P 0 0 ;0=19,1=2
P 2.3897638 0.4055118 0 P 0 0 ;0=19,1=2
P 2.3898425 3.481063 0 P 0 0 ;0=19,1=2
P 2.394685 2.7204724 0 P 0 0 ;0=19,1=2
P 2.4048425 2.412063 0 P 0 0 ;0=19,1=2
P 2.4098325 0.932053 0 P 0 0 ;0=19,1=2
P 2.4098325 1.088053 0 P 0 0 ;0=19,1=2
P 2.4098425 1.967063 0 P 0 0 ;0=19,1=2
P 2.4098425 2.283063 0 P 0 0 ;0=19,1=2
P 2.4098425 2.314063 0 P 0 0 ;0=19,1=2
P 2.4098425 2.579063 0 P 0 0 ;0=19,1=2
P 2.4133858 0.2795276 0 P 0 0 ;0=19,1=2
P 2.4138425 3.295063 0 P 0 0 ;0=19,1=2
P 2.4140551 3.1998504 0 P 0 0 ;0=19,1=2
P 2.4187174 3.1185066 0 P 0 0 ;0=19,1=2
P 2.4192759 2.7886295 0 P 0 0 ;0=19,1=2
P 2.4291925 2.621063 0 P 0 0 ;0=19,1=2
P 2.4348425 3.546063 0 P 0 0 ;0=19,1=2
P 2.4448819 0.2795276 0 P 0 0 ;0=19,1=2
P 2.4468425 1.437063 0 P 0 0 ;0=19,1=2
P 2.4470546 0.2425914 0 P 0 0 ;0=19,1=2
P 2.4508425 2.282063 0 P 0 0 ;0=19,1=2
P 2.462374 3.1722441 0 P 0 0 ;0=19,1=2
P 2.4698827 0.4109883 0 P 0 0 ;0=19,1=2
P 2.4738425 2.980063 0 P 0 0 ;0=19,1=2
P 2.4758425 2.291063 0 P 0 0 ;0=19,1=2
P 2.4758425 2.456063 0 P 0 0 ;0=19,1=2
P 2.4788425 0.937063 0 P 0 0 ;0=19,1=2
P 2.4888425 2.413063 0 P 0 0 ;0=19,1=2
P 2.4948425 2.661063 0 P 0 0 ;0=19,1=2
P 2.4948425 2.696063 0 P 0 0 ;0=19,1=2
P 2.4998425 2.236063 0 P 0 0 ;0=19,1=2
P 2.5028425 1.316063 0 P 0 0 ;0=19,1=2
P 2.5082625 0.931483 0 P 0 0 ;0=19,1=2
P 2.5088425 1.090063 0 P 0 0 ;0=19,1=2
P 2.511811 0.4055118 0 P 0 0 ;0=19,1=2
P 2.5258425 2.463063 0 P 0 0 ;0=19,1=2
P 2.531398 2.830047 12 P 0 0 ;0=4,1=2
P 2.531398 3.853669 12 P 0 0 ;0=4,1=2
P 2.5460625 0.244843 0 P 0 0 ;0=19,1=2
P 2.5498425 1.755063 0 P 0 0 ;0=19,1=2
P 2.5708425 4.283063 0 P 0 0 ;0=19,1=2
P 2.5758425 2.412063 0 P 0 0 ;0=19,1=2
P 2.5787402 0.2795276 0 P 0 0 ;0=19,1=2
P 2.5798425 1.790063 0 P 0 0 ;0=19,1=2
P 2.5798425 2.281063 0 P 0 0 ;0=19,1=2
P 2.5798425 3.486063 0 P 0 0 ;0=19,1=2
P 2.5818425 2.308063 0 P 0 0 ;0=19,1=2
P 2.5868425 2.569063 0 P 0 0 ;0=19,1=2
P 2.5908425 3.288063 0 P 0 0 ;0=19,1=2
P 2.5918425 3.1862205 0 P 0 0 ;0=19,1=2
P 2.5984252 0.7952756 0 P 0 0 ;0=19,1=2
P 2.5998425 2.436063 0 P 0 0 ;0=19,1=2
P 2.6048425 1.734063 0 P 0 0 ;0=19,1=2
P 2.6066825 0.931903 0 P 0 0 ;0=19,1=2
P 2.6068425 1.091063 0 P 0 0 ;0=19,1=2
P 2.6102362 0.2795276 0 P 0 0 ;0=19,1=2
P 2.6220472 0.976378 0 P 0 0 ;0=19,1=2
P 2.6248425 2.461063 0 P 0 0 ;0=19,1=2
P 2.6259843 0.7952756 0 P 0 0 ;0=19,1=2
P 2.6268425 1.770063 0 P 0 0 ;0=19,1=2
P 2.6318425 2.876063 0 P 0 0 ;0=19,1=2
P 2.6348425 3.406063 0 P 0 0 ;0=19,1=2
P 2.636874 0.2479055 0 P 0 0 ;0=19,1=2
P 2.6438425 1.616063 0 P 0 0 ;0=19,1=2
P 2.6458425 2.274063 0 P 0 0 ;0=19,1=2
P 2.6496063 0.976378 0 P 0 0 ;0=19,1=2
P 2.6653543 0.4055118 0 P 0 0 ;0=19,1=2
P 2.6653543 0.7952756 0 P 0 0 ;0=19,1=2
P 2.6658425 1.092063 0 P 0 0 ;0=19,1=2
P 2.6658425 2.291063 0 P 0 0 ;0=19,1=2
P 2.6668425 1.640063 0 P 0 0 ;0=19,1=2
P 2.6748425 3.501063 0 P 0 0 ;0=19,1=2
P 2.6798425 3.661063 0 P 0 0 ;0=19,1=2
P 2.6811024 0.976378 0 P 0 0 ;0=19,1=2
P 2.6858425 2.311063 0 P 0 0 ;0=19,1=2
P 2.6858425 2.568063 0 P 0 0 ;0=19,1=2
P 2.6929134 0.7952756 0 P 0 0 ;0=19,1=2
P 2.6929134 2.7214567 0 P 0 0 ;0=19,1=2
P 2.6948425 1.481063 0 P 0 0 ;0=19,1=2
P 2.7028425 2.289063 0 P 0 0 ;0=19,1=2
P 2.7047244 0.4055118 0 P 0 0 ;0=19,1=2
P 2.7086614 0.976378 0 P 0 0 ;0=19,1=2
P 2.7198425 1.591063 0 P 0 0 ;0=19,1=2
P 2.7224094 3.7860709 0 P 0 0 ;0=19,1=2
P 2.7244825 1.093063 0 P 0 0 ;0=19,1=2
P 2.7248425 3.521063 0 P 0 0 ;0=19,1=2
P 2.7248425 3.729063 0 P 0 0 ;0=19,1=2
P 2.7268425 2.293063 0 P 0 0 ;0=19,1=2
P 2.7322835 0.7952756 0 P 0 0 ;0=19,1=2
P 2.7401575 0.976378 0 P 0 0 ;0=19,1=2
P 2.74882 0.282312 0 P 0 0 ;0=19,1=2
P 2.7598425 0.7952756 0 P 0 0 ;0=19,1=2
P 2.7677165 0.976378 0 P 0 0 ;0=19,1=2
P 2.7748425 3.566063 0 P 0 0 ;0=19,1=2
P 2.7795276 0.2795276 0 P 0 0 ;0=19,1=2
P 2.7838425 2.429063 0 P 0 0 ;0=19,1=2
P 2.7838425 2.568063 0 P 0 0 ;0=19,1=2
P 2.7841625 1.094063 0 P 0 0 ;0=19,1=2
P 2.7992126 0.7952756 0 P 0 0 ;0=19,1=2
P 2.7992126 0.976378 0 P 0 0 ;0=19,1=2
P 2.7998425 3.616063 0 P 0 0 ;0=19,1=2
P 2.7999951 0.2519685 0 P 0 0 ;0=19,1=2
P 2.8038425 2.307063 0 P 0 0 ;0=19,1=2
P 2.8218425 2.601063 0 P 0 0 ;0=19,1=2
P 2.8219832 0.4078519 0 P 0 0 ;0=19,1=2
P 2.8267717 0.7952756 0 P 0 0 ;0=19,1=2
P 2.8267717 0.976378 0 P 0 0 ;0=19,1=2
P 2.8418425 2.263063 0 P 0 0 ;0=19,1=2
P 2.8428425 1.095063 0 P 0 0 ;0=19,1=2
P 2.8543307 0.4055118 0 P 0 0 ;0=19,1=2
P 2.8608425 3.787063 0 P 0 0 ;0=19,1=2
P 2.8622047 0.7952756 0 P 0 0 ;0=19,1=2
P 2.8718425 2.297063 0 P 0 0 ;0=19,1=2
P 2.8782843 0.2495967 0 P 0 0 ;0=19,1=2
P 2.8818425 2.566063 0 P 0 0 ;0=19,1=2
P 2.8888425 4.221063 0 P 0 0 ;0=19,1=2
P 2.8937008 0.7952756 0 P 0 0 ;0=19,1=2
P 2.8948425 1.561063 0 P 0 0 ;0=19,1=2
P 2.8948425 2.431063 0 P 0 0 ;0=19,1=2
P 2.9018425 1.095063 0 P 0 0 ;0=19,1=2
P 2.9054946 0.2795104 0 P 0 0 ;0=19,1=2
P 2.9198425 1.536063 0 P 0 0 ;0=19,1=2
P 2.9208425 2.428063 0 P 0 0 ;0=19,1=2
P 2.9338425 0.953063 0 P 0 0 ;0=19,1=2
P 2.9370079 0.2795276 0 P 0 0 ;0=19,1=2
P 2.9428425 2.286063 0 P 0 0 ;0=19,1=2
P 2.9488425 2.456063 0 P 0 0 ;0=19,1=2
P 2.9574751 0.2519685 0 P 0 0 ;0=19,1=2
P 2.9588425 2.621063 0 P 0 0 ;0=19,1=2
P 2.980457 0.4091539 0 P 0 0 ;0=19,1=2
P 2.9858425 2.287063 0 P 0 0 ;0=19,1=2
P 2.9933858 3.751063 0 P 0 0 ;0=19,1=2
P 3.0148425 3.831063 0 P 0 0 ;0=19,1=2
P 3.019685 0.4055118 0 P 0 0 ;0=19,1=2
P 3.0568817 1.811803 0 P 0 0 ;0=19,1=2
P 3.0688976 3.3956693 0 P 0 0 ;0=19,1=2
P 3.0974409 0.2519685 0 P 0 0 ;0=19,1=2
P 3.1830708 3.1358268 0 P 0 0 ;0=19,1=2
P 3.1889764 3.1870079 0 P 0 0 ;0=19,1=2
P 3.1972633 1.714063 0 P 0 0 ;0=19,1=2
P 3.1978425 2.970063 0 P 0 0 ;0=19,1=2
P 3.2198425 3.806063 0 P 0 0 ;0=19,1=2
P 3.2248425 1.6613472 0 P 0 0 ;0=19,1=2
P 3.2308425 3.235063 0 P 0 0 ;0=19,1=2
P 3.2398425 3.596063 0 P 0 0 ;0=19,1=2
P 3.2528425 1.661063 0 P 0 0 ;0=19,1=2
P 3.2636972 3.3039177 0 P 0 0 ;0=19,1=2
P 3.2698425 3.788063 0 P 0 0 ;0=19,1=2
P 3.2755905 3.1417323 0 P 0 0 ;0=19,1=2
P 3.277559 2.9635827 0 P 0 0 ;0=19,1=2
P 3.2988425 1.971063 0 P 0 0 ;0=19,1=2
P 3.3028425 3.344063 0 P 0 0 ;0=19,1=2
P 3.3291721 1.826063 0 P 0 0 ;0=19,1=2
P 3.3308425 3.301063 0 P 0 0 ;0=19,1=2
P 3.3428425 2.263063 0 P 0 0 ;0=19,1=2
P 3.3448425 2.996063 0 P 0 0 ;0=19,1=2
P 3.3588425 3.448063 0 P 0 0 ;0=19,1=2
P 3.3688425 3.050063 0 P 0 0 ;0=19,1=2
P 3.3708425 2.888063 0 P 0 0 ;0=19,1=2
P 3.3748425 3.273063 0 P 0 0 ;0=19,1=2
P 3.3798425 1.336063 0 P 0 0 ;0=19,1=2
P 3.3798425 1.386063 0 P 0 0 ;0=19,1=2
P 3.3928425 1.871063 0 P 0 0 ;0=19,1=2
P 3.3948425 3.447063 0 P 0 0 ;0=19,1=2
P 3.3958425 4.222063 0 P 0 0 ;0=19,1=2
P 3.4048425 1.363323 0 P 0 0 ;0=19,1=2
P 3.4068425 1.461063 0 P 0 0 ;0=19,1=2
P 3.4072822 1.411323 0 P 0 0 ;0=19,1=2
P 3.4108425 1.7136509 0 P 0 0 ;0=19,1=2
P 3.4138425 1.573063 0 P 0 0 ;0=19,1=2
P 3.4144661 1.805063 0 P 0 0 ;0=19,1=2
P 3.4248425 3.636063 0 P 0 0 ;0=19,1=2
P 3.4368425 3.457063 0 P 0 0 ;0=19,1=2
P 3.4392507 1.870938 0 P 0 0 ;0=19,1=2
P 3.4698425 3.456063 0 P 0 0 ;0=19,1=2
P 3.4918425 3.103063 0 P 0 0 ;0=19,1=2
P 3.4918425 3.297063 0 P 0 0 ;0=19,1=2
P 3.4988425 2.341063 0 P 0 0 ;0=19,1=2
P 3.5048425 4.086063 0 P 0 0 ;0=19,1=2
P 3.5298425 3.481063 0 P 0 0 ;0=19,1=2
P 3.5318425 3.660063 0 P 0 0 ;0=19,1=2
P 3.5398425 3.806063 0 P 0 0 ;0=19,1=2
P 3.542865 3.3190405 0 P 0 0 ;0=19,1=2
P 3.5498425 1.413063 0 P 0 0 ;0=19,1=2
P 3.5498425 1.441063 0 P 0 0 ;0=19,1=2
P 3.5548425 1.841063 0 P 0 0 ;0=19,1=2
P 3.5548425 1.891063 0 P 0 0 ;0=19,1=2
P 3.5548425 1.941063 0 P 0 0 ;0=19,1=2
P 3.5548425 1.991063 0 P 0 0 ;0=19,1=2
P 3.5718425 2.033063 0 P 0 0 ;0=19,1=2
P 3.5718425 2.058063 0 P 0 0 ;0=19,1=2
P 3.5898425 1.711063 0 P 0 0 ;0=19,1=2
P 3.5908425 1.662063 0 P 0 0 ;0=19,1=2
P 3.5948425 1.514063 0 P 0 0 ;0=19,1=2
P 3.6038425 0.682063 0 P 0 0 ;0=19,1=2
P 3.6228425 3.486063 0 P 0 0 ;0=19,1=2
P 3.6238425 2.587063 0 P 0 0 ;0=19,1=2
P 3.6428425 0.636063 0 P 0 0 ;0=19,1=2
P 3.6538425 3.293063 0 P 0 0 ;0=19,1=2
P 3.6998425 3.751063 0 P 0 0 ;0=19,1=2
P 3.6998425 3.836063 0 P 0 0 ;0=19,1=2
P 3.7178425 3.072063 0 P 0 0 ;0=19,1=2
P 3.7188425 1.713063 0 P 0 0 ;0=19,1=2
P 3.7198425 1.766063 0 P 0 0 ;0=19,1=2
P 3.7198425 1.921063 0 P 0 0 ;0=19,1=2
P 3.7198425 1.996063 0 P 0 0 ;0=19,1=2
P 3.7248425 1.675063 0 P 0 0 ;0=19,1=2
P 3.7328425 1.418063 0 P 0 0 ;0=19,1=2
P 3.7448425 3.261063 0 P 0 0 ;0=19,1=2
P 3.7448425 3.342063 0 P 0 0 ;0=19,1=2
P 3.7738632 1.6661021 0 P 0 0 ;0=19,1=2
P 3.7778425 4.023063 0 P 0 0 ;0=19,1=2
P 3.7998425 3.201063 0 P 0 0 ;0=19,1=2
P 3.8038425 1.691063 0 P 0 0 ;0=19,1=2
P 3.8048425 1.840063 0 P 0 0 ;0=19,1=2
P 3.8068425 3.235063 0 P 0 0 ;0=19,1=2
P 3.8298425 3.176063 0 P 0 0 ;0=19,1=2
P 3.8298425 3.806063 0 P 0 0 ;0=19,1=2
P 3.8308425 3.762063 0 P 0 0 ;0=19,1=2
P 3.8348425 1.481063 0 P 0 0 ;0=19,1=2
P 3.8548425 3.151063 0 P 0 0 ;0=19,1=2
P 3.8648425 1.511063 0 P 0 0 ;0=19,1=2
P 3.8808425 3.109063 0 P 0 0 ;0=19,1=2
P 3.8948425 1.566063 0 P 0 0 ;0=19,1=2
P 3.9248425 1.536063 0 P 0 0 ;0=19,1=2
P 3.9398425 3.121063 0 P 0 0 ;0=19,1=2
P 3.9448425 1.816063 0 P 0 0 ;0=19,1=2
P 3.9608425 2.724063 0 P 0 0 ;0=19,1=2
P 3.9688425 1.671063 0 P 0 0 ;0=19,1=2
P 3.9698425 1.552063 0 P 0 0 ;0=19,1=2
P 3.9948425 1.551063 0 P 0 0 ;0=19,1=2
P 3.9968425 1.711063 0 P 0 0 ;0=19,1=2
P 4.0348425 1.546063 0 P 0 0 ;0=19,1=2
P 4.0398425 2.406063 0 P 0 0 ;0=19,1=2
P 4.0398425 3.784063 0 P 0 0 ;0=19,1=2
P 4.0498425 3.665063 0 P 0 0 ;0=19,1=2
P 4.0648425 1.511063 0 P 0 0 ;0=19,1=2
P 4.0648425 1.796063 0 P 0 0 ;0=19,1=2
P 4.0648425 2.722063 0 P 0 0 ;0=19,1=2
P 4.0688425 3.135063 0 P 0 0 ;0=19,1=2
P 4.0858425 3.892063 0 P 0 0 ;0=19,1=2
P 4.1148425 3.135063 0 P 0 0 ;0=19,1=2
P 4.1203866 3.5941508 0 P 0 0 ;0=19,1=2
P 4.1318425 1.686063 0 P 0 0 ;0=19,1=2
P 4.1348425 1.651063 0 P 0 0 ;0=19,1=2
P 4.1348425 1.751063 0 P 0 0 ;0=19,1=2
P 4.1513063 1.6236232 0 P 0 0 ;0=19,1=2
P 4.1528425 3.135063 0 P 0 0 ;0=19,1=2
P 4.1798425 1.601063 0 P 0 0 ;0=19,1=2
P 4.1948425 3.884063 0 P 0 0 ;0=19,1=2
P 4.2088425 3.135063 0 P 0 0 ;0=19,1=2
P 4.2348425 2.725063 0 P 0 0 ;0=19,1=2
P 4.2548425 3.776063 0 P 0 0 ;0=19,1=2
P 4.2728425 3.135063 0 P 0 0 ;0=19,1=2
P 4.3338425 3.135063 0 P 0 0 ;0=19,1=2
P 4.3398425 2.725063 0 P 0 0 ;0=19,1=2
P 4.3878425 4.206063 0 P 0 0 ;0=19,1=2
P 4.4318425 3.135063 0 P 0 0 ;0=19,1=2
P 4.4778425 3.135063 0 P 0 0 ;0=19,1=2
P 4.5036614 2.7898819 0 P 0 0 ;0=19,1=2
P 4.7547119 4.1159324 0 P 0 0 ;0=19,1=2
P 4.7942913 2.8080709 0 P 0 0 ;0=19,1=2
P 4.9108425 4.203063 0 P 0 0 ;0=19,1=2
P 5.2670079 4.0888976 0 P 0 0 ;0=19,1=2
P 5.2748425 3.511063 0 P 0 0 ;0=19,1=2
P 5.5778425 2.214063 0 P 0 0 ;0=19,1=2
P 5.6348425 2.236063 0 P 0 0 ;0=19,1=2
P 5.6768425 3.546063 0 P 0 0 ;0=19,1=2
P 5.7338425 3.556063 0 P 0 0 ;0=19,1=2
P 5.9948425 3.552063 0 P 0 0 ;0=19,1=2
P 6.0048425 2.434063 0 P 0 0 ;0=19,1=2
P 6.0488425 2.171063 0 P 0 0 ;0=19,1=2
P 6.253937 2.9094488 0 P 0 0 ;0=19,1=2
P 6.2748425 2.391063 0 P 0 0 ;0=19,1=2
P 6.2824161 3.226063 0 P 0 0 ;0=19,1=2
P 6.2848425 2.501063 0 P 0 0 ;0=19,1=2
P 6.2948425 3.701063 0 P 0 0 ;0=19,1=2
P 6.3048425 3.121063 0 P 0 0 ;0=19,1=2
P 6.3094161 3.199063 0 P 0 0 ;0=19,1=2
P 6.3348425 3.266063 0 P 0 0 ;0=19,1=2
P 6.3398425 3.151063 0 P 0 0 ;0=19,1=2
P 6.3547483 3.3311384 0 P 0 0 ;0=19,1=2
P 6.3720472 2.9094488 0 P 0 0 ;0=19,1=2
P 6.3958425 2.111063 0 P 0 0 ;0=19,1=2
P 6.3968425 2.556063 0 P 0 0 ;0=19,1=2
P 6.3978425 2.501063 0 P 0 0 ;0=19,1=2
P 6.3978425 2.610063 0 P 0 0 ;0=19,1=2
P 6.3988425 2.453063 0 P 0 0 ;0=19,1=2
P 6.3988425 2.657063 0 P 0 0 ;0=19,1=2
P 6.4098425 3.371063 0 P 0 0 ;0=19,1=2
P 6.4248425 2.181063 0 P 0 0 ;0=19,1=2
P 6.4398425 3.191063 0 P 0 0 ;0=19,1=2
P 6.4448425 3.291063 0 P 0 0 ;0=19,1=2
P 6.4475772 3.396063 0 P 0 0 ;0=19,1=2
P 6.4568425 3.009063 0 P 0 0 ;0=19,1=2
P 6.4768425 3.231063 0 P 0 0 ;0=19,1=2
P 6.4798425 3.426063 0 P 0 0 ;0=19,1=2
P 6.5098425 3.456063 0 P 0 0 ;0=19,1=2
P 6.5488425 1.531063 0 P 0 0 ;0=19,1=2
P 6.6018425 1.777063 0 P 0 0 ;0=19,1=2
P 6.6028425 1.612063 0 P 0 0 ;0=19,1=2
P 6.6028425 1.672063 0 P 0 0 ;0=19,1=2
P 6.6028425 1.722063 0 P 0 0 ;0=19,1=2
P 6.6078425 2.176063 0 P 0 0 ;0=19,1=2
P 6.6268425 3.032063 0 P 0 0 ;0=19,1=2
P 6.6288425 1.372063 0 P 0 0 ;0=19,1=2
P 6.6476378 3.1299213 0 P 0 0 ;0=19,1=2
P 6.6488425 3.341063 0 P 0 0 ;0=19,1=2
P 6.6858425 1.828063 0 P 0 0 ;0=19,1=2
P 6.6998425 1.881063 0 P 0 0 ;0=19,1=2
P 6.8448425 1.661063 0 P 0 0 ;0=19,1=2
P 6.9498425 2.095063 0 P 0 0 ;0=19,1=2
P 6.9744094 1.9399606 0 P 0 0 ;0=19,1=2

### steps/pcb/layers/in1/features
#Layer_Physical_Order=3
#Layer_Color=16440176
#
#Feature symbol names
#
$0 r8
$1 r5
$2 r20
$3 r6
$4 r3.937
$5 r1
$6 r55
$7 r75
$8 r16

#
#Feature attribute names
#
@0 .geometry
@1 .pad_usage

#
#Feature attribute text strings
#
&0 Pad_Simple_X55.0000Y55.0000H30.0000C70.0000
&1 Pad_Simple_X75.0000Y75.0000H50.0000C90.0000
&2 VIA_RoundD16.0000H8.0000C48.0000

#
#Layer features
#
A 1.7712204 0.4310709 1.6275196 0.4310709 1.69937 0.4310709 4 P 0 N
A 2.3962788 2.7188785 2.4019357 2.7165354 2.4019357 2.7245354 0 P 0 N
A 2.4268055 0.2755913 2.4633018 0.2812475 2.4448819 0.2795276 1 P 0 N
A 2.4268055 0.2755914 2.4218883 0.2795276 2.4219199 0.2745276 1 P 0 N
A 2.4591027 0.3215522 2.4591028 0.3109457 2.4644061 0.316249 1 P 0 N
A 2.462398 0.2970437 2.462398 0.3076503 2.4570947 0.302347 1 P 0 N
A 2.4647316 0.2852354 2.4633016 0.2812476 2.46828 0.2817126 1 P 0 N
A 2.4697093 0.3215522 2.4591027 0.3215522 2.464406 0.3162489 1 P 0 N
A 2.4730045 0.3182572 2.483611 0.3182571 2.4783078 0.3235605 1 P 0 N
A 2.481143 0.3419383 2.4811431 0.3313318 2.4864464 0.3366351 1 P 0 N
A 2.483611 0.3182571 2.483611 0.3288637 2.4783077 0.3235604 1 P 0 N
A 2.4917496 0.3419383 2.481143 0.3419383 2.4864463 0.336635 1 P 0 N
A 2.4942177 0.3394704 2.5048242 0.3394703 2.499521 0.3447737 1 P 0 N
A 2.5048234 0.3606843 2.5048235 0.3500778 2.5101268 0.3553811 1 P 0 N
A 2.5048242 0.3394703 2.5048242 0.3500769 2.4995209 0.3447736 1 P 0 N
A 2.51543 0.3606843 2.5048234 0.3606843 2.5101267 0.355381 1 P 0 N
A 2.515431 0.3606833 2.5260376 0.3606833 2.5207343 0.3659866 1 P 0 N
A 2.5537186 0.3883645 2.555929 0.3937008 2.5483823 0.3937008 1 P 0 N
A 2.5633894 0.3838931 2.5669291 0.3909404 2.554478 0.3927817 1 P 0 N
A 2.5708465 0.8385633 2.555929 0.8025492 2.6068606 0.8025492 1 P 0 N
A 2.5772301 0.2979659 2.5967244 0.2751896 2.5787402 0.2795276 1 P 0 N
A 2.5772302 0.2979658 2.5811607 0.3004636 2.5768222 0.3029492 1 P 0 N
A 2.5786444 0.8308046 2.5669292 0.8025514 2.6069273 0.8025217 1 P 0 N
A 2.5787402 0.2795276 2.590997 0.2952757 2.5217118 0.3365568 1 P 0 N
A 2.5833241 0.3038795 2.5811607 0.3004636 2.6207554 0.27778 1 P 0 N
A 2.5833241 0.3038795 2.5840758 0.305536 2.5792227 0.3067394 1 P 0 N
A 2.589472 0.324767 2.587926 0.3207438 2.6049102 0.3165262 1 P 0 N
A 2.5894721 0.324767 2.5900612 0.3271215 2.5850611 0.3271216 1 P 0 N
A 2.590077 0.4048252 2.5900615 0.4044314 2.5950619 0.4044314 1 P 0 N
A 2.590997 0.2952757 2.5924267 0.2977757 2.5217118 0.3365568 1 P 0 N
A 2.6000644 0.2788024 2.5967439 0.2752696 2.6015907 0.274041 1 P 0 N
A 2.6010375 0.8687542 2.6303268 0.9394649 2.5303268 0.9394649 1 P 0 N
A 2.6023617 0.3765263 2.6098617 0.3690262 2.6098617 0.3765262 1 P 0 N
A 2.60464 0.2795276 2.6000644 0.2788025 2.60464 0.2647277 1 P 0 N
A 2.6049102 0.3240262 2.5976396 0.3183668 2.6049102 0.3165262 1 P 0 N
A 2.6075616 0.3540262 2.6075616 0.3390262 2.6075616 0.3465262 1 P 0 N
A 2.6085063 0.4571723 2.5900772 0.4048252 2.697819 0.3963118 1 P 0 N
A 2.6088541 0.8610146 2.6413267 0.9394103 2.5304584 0.9394103 1 P 0 N
A 2.6160907 0.3540262 2.6160907 0.3690262 2.6160907 0.3615262 1 P 0 N
A 2.6197278 0.3240262 2.6197278 0.3390262 2.6197278 0.3315262 1 P 0 N
A 2.625896 0.4802268 2.6085063 0.4571724 2.6994991 0.4066233 1 P 0 N
A 2.6266076 2.7165354 2.6322781 2.7188922 2.6266076 2.7245354 0 P 0 N
A 2.6303268 0.9562399 2.6220472 0.9762286 2.6020585 0.9562399 1 P 0 N
A 2.6337624 0.472537 2.6023621 0.3968183 2.7095689 0.3967302 1 P 0 N
A 2.6443446 0.4986753 2.6736339 0.569386 2.5736339 0.569386 1 P 0 N
A 2.6496063 0.9762283 2.6413269 0.95624 2.6695948 0.95624 1 P 0 N
A 2.6521612 0.4909357 2.6846338 0.5693314 2.5737655 0.5693314 1 P 0 N
A 2.6715808 2.7549212 2.6659503 2.7525644 2.671621 2.746921 0 P 0 N
A 2.6736339 0.7751375 2.6653543 0.7951262 2.6453656 0.7751375 1 P 0 N
A 2.6929134 0.7951259 2.684634 0.7751376 2.7129019 0.7751376 1 P 0 N
A 2.7130379 0.3275528 2.7374167 0.2674147 2.7995431 0.3276098 1 P 0 N
A 2.7339149 0.3181179 2.7339149 0.3031179 2.7339149 0.3106179 1 P 0 N
A 2.7339267 0.3481179 2.7339267 0.3331179 2.7339267 0.3406179 1 P 0 N
A 2.7374436 0.2673869 2.7661079 0.2755913 2.7495712 0.2791913 1 P 0 N
A 2.7379035 0.38751 2.7130379 0.3275528 2.7978525 0.3275131 1 P 0 N
A 2.7405615 0.3481179 2.7480615 0.3556149 2.7405615 0.3556179 1 P 0 N
A 2.7480334 0.2850057 2.7488197 0.2823122 2.7530335 0.2850038 1 P 0 N
A 2.7480377 0.295615 2.7405377 0.3031179 2.7405377 0.2956179 1 P 0 N
A 2.748437 0.9408906 2.7624692 0.9070139 2.7963459 0.9408906 1 P 0 N
A 2.748437 0.95624 2.7401575 0.9762285 2.720169 0.95624 1 P 0 N
A 2.7495358 0.3835858 2.7480713 0.3800522 2.7530713 0.3800503 1 P 0 N
A 2.7505469 0.3181179 2.7505469 0.3331179 2.7505469 0.3256179 1 P 0 N
A 2.759437 0.940945 2.7702859 0.9147536 2.7964773 0.940945 1 P 0 N
A 2.7677165 0.9762283 2.7594371 0.95624 2.787705 0.95624 1 P 0 N
A 2.771025 0.2795276 2.7661078 0.2755914 2.7709934 0.2745276 1 P 0 N
A 2.7818567 0.8876264 2.8602814 0.8551418 2.8602814 0.9660511 1 P 0 N
A 2.7874016 0.4370081 2.8074921 0.4855108 2.7388989 0.4855108 1 P 0 N
A 2.7896083 0.8954311 2.860319 0.8661418 2.860319 0.9661418 1 P 0 N
A 2.7952139 0.429264 2.8184921 0.4854626 2.7390153 0.4854626 1 P 0 N
A 2.8074922 0.7751375 2.7992126 0.7951262 2.7792239 0.7751375 1 P 0 N
A 2.8267717 0.7951259 2.8184923 0.7751376 2.8467602 0.7751376 1 P 0 N
A 2.8858267 0.2761384 2.8859824 0.2749003 2.8908271 0.2761384 1 P 0 N
A 2.8859825 0.2749004 2.9235738 0.2755876 2.904697 0.2796828 1 P 0 N
A 2.8976378 0.2894382 2.8991023 0.2859027 2.9026378 0.2894382 1 P 0 N
A 2.9033267 0.3444387 2.9033267 0.3294387 2.9033267 0.3369387 1 P 0 N
A 2.9051377 0.3144387 2.8976377 0.3069387 2.9051377 0.3069387 1 P 0 N
A 2.9073889 0.8445797 2.8818899 0.8551417 2.8818899 0.8190807 1 P 0 N
A 2.9091203 0.3669387 2.9166203 0.3594387 2.9166203 0.3669387 1 P 0 N
A 2.9111366 0.4003551 2.8858265 0.3525952 2.9436686 0.3525286 1 P 0 N
A 2.9111917 0.4003926 2.9127084 0.4020274 2.9083767 0.4045254 1 P 0 N
A 2.9127082 0.4020274 2.9173228 0.4191344 2.8829772 0.4192232 1 P 0 N
A 2.9150082 0.3144387 2.9150082 0.3294387 2.9150082 0.3219387 1 P 0 N
A 2.915133 0.8523918 2.8819379 0.8661417 2.8819379 0.8191967 1 P 0 N
A 2.9166213 0.3444387 2.9166213 0.3594387 2.9166213 0.3519387 1 P 0 N
A 2.9173229 0.820597 2.907389 0.8445797 2.883406 0.820597 1 P 0 N
A 2.9268527 0.4009545 2.928323 0.4044959 2.9233229 0.4044959 1 P 0 N
A 2.9283229 0.8346456 2.925101 0.842424 2.9173226 0.8346456 1 P 0 N
A 2.9284918 0.2795276 2.9235738 0.2755877 2.9284602 0.2745276 1 P 0 N
L -0.0001175 0.177913 0.5908825 0.177913 5 P 0
L -0.0004331 0.1781182 0.5901181 0.1781182 4 P 0
L 0.5901181 0.1781182 0.5901181 0.5029213 4 P 0
L 0.5901181 0.5029213 1.312559 0.5029213 4 P 0
L 0.5908825 0.177913 0.5908825 0.502913 5 P 0
L 0.8602362 1.3228347 0.8602362 2.0984252 0 P 0
L 0.8602362 1.3228347 0.996063 1.1870079 0 P 0
L 0.8602362 2.0984252 0.997847 2.236036 0 P 0
L 0.988189 1.7175197 2.5882992 1.7175197 0 P 0
L 0.9968357 2.256036 1.7322579 2.256036 0 P 0
L 0.997847 2.236036 2.4998155 2.236036 0 P 0
L 1.0048425 0.906063 1.2966929 0.906063 0 P 0
L 1.0088425 1.430063 1.0105288 1.430063 0 P 0
L 1.0098425 1.956063 1.0208425 1.967063 0 P 0
L 1.0105288 1.430063 1.0175288 1.437063 0 P 0
L 1.0175288 1.437063 2.4468425 1.437063 0 P 0
L 1.0208425 1.967063 2.4098425 1.967063 0 P 0
L 1.0208425 2.481063 1.1878425 2.314063 0 P 0
L 1.1878425 2.314063 2.4098425 2.314063 0 P 0
L 1.2948425 4.256063 1.3623867 4.256063 2 P 0
L 1.2966929 0.906063 1.3956693 0.8070866 0 P 0
L 1.312559 0.313945 1.312559 0.5029213 4 P 0
L 1.312559 0.313945 1.6275197 0.313945 4 P 0
L 1.3623867 4.256063 1.4137253 4.2047244 2 P 0
L 1.3937008 1.8169291 1.5178347 1.941063 0 P 0
L 1.3956693 0.8070866 1.769685 0.8070866 0 P 0
L 1.3996063 3.0757874 1.3996063 3.5225396 0 P 0
L 1.3996063 3.0757874 1.6348425 2.8405512 0 P 0
L 1.3996063 3.5225396 1.4005905 3.5235238 0 P 0
L 1.4005905 3.5235238 1.4005905 3.9716287 0 P 0
L 1.4005905 3.9716287 1.4084645 3.9795027 0 P 0
L 1.4084645 3.9795027 1.4084645 3.980315 0 P 0
L 1.4137253 4.2047244 1.4967344 4.2047244 2 P 0
L 1.4408425 3.557063 2.4238425 3.557063 0 P 0
L 1.4598425 3.147063 2.4354488 3.147063 0 P 0
L 1.4967344 4.2047244 1.5764588 4.2844488 2 P 0
L 1.5178347 1.941063 2.3848425 1.941063 0 P 0
L 1.5498425 3.621063 1.8709014 3.621063 0 P 0
L 1.5679134 1.2854331 1.5721654 1.2811811 0 P 0
L 1.5698819 4.1712599 1.6050788 4.136063 0 P 0
L 1.5721654 1.2811811 2.1899606 1.2811811 0 P 0
L 1.5748425 3.596063 1.5938425 3.577063 0 P 0
L 1.5764588 4.2844488 1.9094487 4.2844488 2 P 0
L 1.5938425 3.577063 2.117274 3.577063 0 P 0
L 1.6050788 4.136063 1.9863658 4.136063 0 P 0
L 1.6275197 0.313945 1.6275197 0.4310709 4 P 0
L 1.6348425 2.8405512 2.2175197 2.8405512 0 P 0
L 1.7322579 2.256036 1.7392309 2.249063 0 P 0
L 1.7392309 2.249063 2.4724882 2.249063 0 P 0
L 1.7548425 3.661063 1.7556536 3.6618741 0 P 0
L 1.7556536 3.6618741 2.6790314 3.6618741 0 P 0
L 1.769685 0.8070866 1.8686614 0.906063 0 P 0
L 1.7798425 4.156063 1.9651181 4.156063 0 P 0
L 1.7982283 1.3041339 1.8101574 1.316063 0 P 0
L 1.8101574 1.316063 2.0131267 1.316063 0 P 0
L 1.8227825 1.674003 1.8824983 1.674003 0 P 0
L 1.8498425 3.701063 6.2948425 3.701063 2 P 0
L 1.8686614 0.906063 2.4528425 0.906063 0 P 0
L 1.8709014 3.621063 1.8957125 3.6458741 0 P 0
L 1.8799377 1.811803 3.0568817 1.811803 0 P 0
L 1.8824983 1.674003 1.8835583 1.675063 0 P 0
L 1.8835583 1.675063 1.8855583 1.673063 0 P 0
L 1.8848425 3.601063 2.1159014 3.601063 0 P 0
L 1.8855583 1.673063 3.2029322 1.673063 0 P 0
L 1.8938425 1.693063 3.2045475 1.693063 0 P 0
L 1.8957125 3.6458741 2.6521765 3.6458741 0 P 0
L 1.9038425 4.018063 1.904189 4.0177165 0 P 0
L 1.904189 4.0177165 2.3533464 4.0177165 0 P 0
L 1.9094487 4.2844488 1.941929 4.3169291 2 P 0
L 1.941929 4.3169291 2.1525591 4.3169291 2 P 0
L 1.9651181 4.156063 2.0187008 4.2096457 0 P 0
L 1.9863658 4.136063 2.0023658 4.152063 0 P 0
L 2.0023658 4.152063 2.0433071 4.152063 0 P 0
L 2.0048425 1.336063 3.3798425 1.336063 0 P 0
L 2.0131267 1.316063 2.0161267 1.319063 0 P 0
L 2.0161267 1.319063 2.4998425 1.319063 0 P 0
L 2.0187008 4.2096457 2.0679106 4.2096457 0 P 0
L 2.0288425 1.361663 2.0294425 1.361063 0 P 0
L 2.0294425 1.361063 3.4025825 1.361063 0 P 0
L 2.0598425 1.386063 3.3798425 1.386063 0 P 0
L 2.0679106 4.2096457 2.1214933 4.156063 0 P 0
L 2.0838425 1.411663 2.0840125 1.411493 3 P 0
L 2.0840125 1.411493 3.4071122 1.411493 3 P 0
L 2.1159014 3.601063 2.1299014 3.587063 0 P 0
L 2.117274 3.577063 2.123274 3.571063 0 P 0
L 2.1214933 4.156063 3.9700965 4.156063 0 P 0
L 2.123274 3.571063 2.6119246 3.571063 0 P 0
L 2.1299014 3.587063 2.2578002 3.587063 0 P 0
L 2.1525591 4.3169291 2.1864252 4.283063 2 P 0
L 2.1864252 4.283063 2.5708425 4.283063 2 P 0
L 2.1899606 1.2811811 2.2068425 1.298063 0 P 0
L 2.2058425 3.200063 2.3855583 3.200063 0 P 0
L 2.2175197 2.8405512 2.3620079 2.696063 0 P 0
L 2.2348425 3.506063 2.5259014 3.506063 0 P 0
L 2.2578002 3.587063 2.3006113 3.6298741 0 P 0
L 2.2598425 3.261063 2.4055845 3.261063 0 P 0
L 2.2748425 1.506063 3.5448425 1.506063 0 P 0
L 2.2998425 1.916063 3.3344993 1.916063 0 P 0
L 2.3006113 3.6298741 2.5433214 3.6298741 0 P 0
L 2.3308425 2.215063 5.5778425 2.215063 0 P 0
L 2.3620079 2.696063 2.4948425 2.696063 0 P 0
L 2.3848425 1.941063 3.3321267 1.941063 0 P 0
L 2.3855583 3.200063 2.4115583 3.174063 0 P 0
L 2.394685 2.7204724 2.3962788 2.7188785 0 P 0
L 2.4019357 2.7165354 2.6266076 2.7165354 0 P 0
L 2.4055845 3.261063 2.4111751 3.2666536 0 P 0
L 2.4111751 3.2666536 2.6936282 3.2666536 0 P 0
L 2.4115583 3.174063 2.4281267 3.174063 0 P 0
L 2.4133858 0.2795276 2.4218882 0.2795276 1 P 0
L 2.4140551 3.1998504 2.4162199 3.1998504 0 P 0
L 2.4162199 3.1998504 2.4291017 3.2127322 0 P 0
L 2.4187174 3.1185066 2.4283989 3.1185066 0 P 0
L 2.4218882 0.2795276 2.4218883 0.2795276 1 P 0
L 2.4238425 3.557063 2.4348425 3.546063 0 P 0
L 2.4281267 3.174063 2.4541267 3.200063 0 P 0
L 2.4283989 3.1185066 2.5774173 2.9694882 0 P 0
L 2.4291017 3.2127322 2.4385117 3.2127322 0 P 0
L 2.4291925 2.621063 2.9588425 2.621063 0 P 0
L 2.4354488 3.147063 2.4606299 3.1722441 0 P 0
L 2.4385117 3.2127322 2.4608425 3.235063 0 P 0
L 2.4448819 0.2795276 2.4606299 0.2952756 1 P 0
L 2.4528425 0.906063 2.4788425 0.932063 0 P 0
L 2.4541267 3.200063 2.5774008 3.200063 0 P 0
L 2.4591027 0.3109456 2.462398 0.3076503 1 P 0
L 2.4606299 0.2952756 2.462398 0.2970437 1 P 0
L 2.4606299 3.1722441 2.462374 3.1722441 0 P 0
L 2.4608425 3.235063 2.6804223 3.235063 0 P 0
L 2.4633015 0.2812475 2.4633017 0.2812476 1 P 0
L 2.4647316 0.2852354 2.5633894 0.3838931 1 P 0
L 2.4697093 0.3215522 2.4730044 0.3182571 1 P 0
L 2.4724882 2.249063 2.4940945 2.2706693 0 P 0
L 2.4788425 0.932063 2.4788425 0.937063 0 P 0
L 2.481143 0.3313317 2.483611 0.3288637 1 P 0
L 2.4917496 0.3419383 2.4942176 0.3394703 1 P 0
L 2.4940945 2.2706693 2.5295275 2.2706693 0 P 0
L 2.4948425 2.661063 4.1147946 2.661063 0 P 0
L 2.4948425 2.696063 2.5098425 2.681063 0 P 0
L 2.4998155 2.236036 2.4998425 2.236063 0 P 0
L 2.4998425 1.319063 2.5028425 1.316063 0 P 0
L 2.4998425 2.236063 5.6348425 2.236063 0 P 0
L 2.5048234 0.3500777 2.5048242 0.3500769 1 P 0
L 2.5098425 2.681063 4.2129048 2.681063 0 P 0
L 2.51543 0.3606843 2.515431 0.3606833 1 P 0
L 2.5154309 0.3606832 2.515431 0.3606833 1 P 0
L 2.5258425 2.463063 2.5985583 2.463063 0 P 0
L 2.5259014 3.506063 2.5699014 3.462063 0 P 0
L 2.5260376 0.3606833 2.5435917 0.3782374 1 P 0
L 2.5295275 2.2706693 2.5492125 2.2509843 0 P 0
L 2.5433214 3.6298741 2.5571325 3.616063 0 P 0
L 2.5435917 0.3782374 2.5537187 0.3883644 1 P 0
L 2.5492125 2.2509843 2.6082678 2.2509843 0 P 0
L 2.5498425 1.755063 2.6121267 1.755063 0 P 0
L 2.555929 0.3937008 2.5559291 0.3937008 1 P 0
L 2.5559291 0.3937008 2.5559291 0.8025492 1 P 0
L 2.5571325 3.616063 2.7998425 3.616063 0 P 0
L 2.5669291 0.3909404 2.5669292 0.8025514 1 P 0
L 2.5699014 3.462063 3.0371764 3.462063 0 P 0
L 2.5708466 0.8385633 2.6010375 0.8687542 1 P 0
L 2.5758425 2.412063 2.5801721 2.412063 0 P 0
L 2.5772301 0.2979658 2.5772302 0.2979657 1 P 0
L 2.5774008 3.200063 2.5912433 3.1862205 0 P 0
L 2.5774173 2.9694882 3.0965519 2.9694882 0 P 0
L 2.5786443 0.8308047 2.5786444 0.8308046 1 P 0
L 2.5786443 0.8308047 2.6088541 0.8610145 1 P 0
L 2.5798425 1.790063 2.6351267 1.790063 0 P 0
L 2.5801721 2.412063 2.5861721 2.406063 0 P 0
L 2.5840758 0.305536 2.587926 0.3207438 1 P 0
L 2.5861721 2.406063 4.0398425 2.406063 0 P 0
L 2.5882992 1.7175197 2.6048425 1.734063 0 P 0
L 2.5900611 0.3271215 2.5900615 0.4044314 1 P 0
L 2.590077 0.4048252 2.5900772 0.4048252 1 P 0
L 2.5908425 3.288063 2.5930073 3.288063 0 P 0
L 2.5912433 3.1862205 2.5918425 3.1862205 0 P 0
L 2.5924267 0.2977757 2.5976396 0.3183668 1 P 0
L 2.5930073 3.288063 2.5980073 3.293063 0 P 0
L 2.5967244 0.2751896 2.5967439 0.2752696 1 P 0
L 2.5976395 0.3183668 2.5976396 0.3183668 1 P 0
L 2.5980073 3.293063 3.2528425 3.293063 0 P 0
L 2.5985583 2.463063 2.6165583 2.481063 0 P 0
L 2.6000644 0.2788024 2.6000644 0.2788025 1 P 0
L 2.6023617 0.3765263 2.6023619 0.3872638 1 P 0
L 2.6023619 0.3872638 2.602362 0.3897637 1 P 0
L 2.602362 0.3897637 2.602362 0.3897638 1 P 0
L 2.602362 0.3897637 2.6023622 0.3968183 1 P 0
L 2.60464 0.2795276 2.6102362 0.2795276 1 P 0
L 2.6048425 1.734063 3.5789014 1.734063 0 P 0
L 2.6049102 0.3240262 2.6197278 0.3240262 1 P 0
L 2.6075616 0.3390262 2.6197278 0.3390262 1 P 0
L 2.6075616 0.3540262 2.6160907 0.3540262 1 P 0
L 2.6082678 2.2509843 2.6298158 2.2725323 0 P 0
L 2.6085063 0.4571723 2.6085063 0.4571724 1 P 0
L 2.6098617 0.3690262 2.6160907 0.3690262 1 P 0
L 2.6119246 3.571063 2.6369246 3.596063 0 P 0
L 2.6121267 1.755063 2.6171267 1.750063 0 P 0
L 2.6165583 2.481063 2.9238425 2.481063 0 P 0
L 2.6171267 1.750063 3.4838639 1.750063 0 P 0
L 2.6220472 0.9762286 2.6220472 0.976378 1 P 0
L 2.6258961 0.4802268 2.6443446 0.4986753 1 P 0
L 2.6268425 1.770063 2.6290073 1.770063 0 P 0
L 2.6290073 1.770063 2.6330073 1.766063 0 P 0
L 2.6298158 2.2725323 2.6443118 2.2725323 0 P 0
L 2.6303268 0.9394649 2.6303268 0.9562399 1 P 0
L 2.6322781 2.7188922 2.6659503 2.7525644 0 P 0
L 2.6330073 1.766063 3.4758425 1.766063 0 P 0
L 2.6337624 0.472537 2.6337625 0.4725369 1 P 0
L 2.6337625 0.4725369 2.6521612 0.4909356 1 P 0
L 2.6351267 1.790063 2.6461267 1.779063 0 P 0
L 2.6369246 3.596063 3.2398425 3.596063 0 P 0
L 2.6413268 0.9394103 2.6413268 0.95624 1 P 0
L 2.6438425 1.616063 3.4696294 1.616063 0 P 0
L 2.6443118 2.2725323 2.6458425 2.274063 0 P 0
L 2.6461267 1.779063 3.4658425 1.779063 0 P 0
L 2.6496063 0.9762283 2.6496063 0.9762285 1 P 0
L 2.6496063 0.9762285 2.6496063 0.976378 1 P 0
L 2.6521765 3.6458741 2.6619876 3.636063 0 P 0
L 2.6619876 3.636063 3.4248425 3.636063 0 P 0
L 2.6653543 0.7951262 2.6653543 0.7952756 1 P 0
L 2.6668425 1.640063 2.6678425 1.641063 0 P 0
L 2.6678425 1.641063 3.7827652 1.641063 0 P 0
L 2.6715808 2.7549211 2.6716209 2.7549213 0 P 0
L 2.6716209 2.7549213 3.089567 2.7549213 0 P 0
L 2.6736339 0.569386 2.6736339 0.7751375 1 P 0
L 2.6790314 3.6618741 2.6798425 3.661063 0 P 0
L 2.6804223 3.235063 2.7029223 3.257563 0 P 0
L 2.6846339 0.5693314 2.6846339 0.7751376 1 P 0
L 2.6929134 0.7951259 2.6929134 0.7952756 1 P 0
L 2.6936282 3.2666536 2.7000376 3.273063 0 P 0
L 2.6948425 1.481063 3.5437836 1.481063 0 P 0
L 2.7000376 3.273063 3.3748425 3.273063 0 P 0
L 2.7029223 3.257563 2.9746059 3.257563 0 P 0
L 2.7198425 1.591063 3.0823425 1.591063 0 P 0
L 2.7339149 0.3031179 2.7405377 0.3031179 1 P 0
L 2.7339149 0.3181179 2.7505469 0.3181179 1 P 0
L 2.7339267 0.3331179 2.7505469 0.3331179 1 P 0
L 2.7339267 0.3481179 2.7405615 0.3481179 1 P 0
L 2.7374166 0.2674146 2.7374436 0.2673869 1 P 0
L 2.7379035 0.38751 2.7874016 0.4370081 1 P 0
L 2.7401575 0.9762285 2.7401575 0.976378 1 P 0
L 2.7480334 0.2850057 2.7480335 0.2850057 1 P 0
L 2.7480335 0.2850057 2.7480353 0.2893674 1 P 0
L 2.7480353 0.2893674 2.7480362 0.2918674 1 P 0
L 2.7480362 0.2918674 2.7480377 0.295615 1 P 0
L 2.7480376 0.295615 2.7480377 0.295615 1 P 0
L 2.7480614 0.3556149 2.7480615 0.3556149 1 P 0
L 2.7480615 0.3556149 2.7480703 0.3775521 1 P 0
L 2.7480703 0.3775521 2.7480712 0.3800521 1 P 0
L 2.7480712 0.380052 2.7480713 0.3800522 1 P 0
L 2.748437 0.9408906 2.748437 0.95624 1 P 0
L 2.7488196 0.2823122 2.74882 0.282312 1 P 0
L 2.7495358 0.3835858 2.7952139 0.4292639 1 P 0
L 2.759437 0.940945 2.759437 0.95624 1 P 0
L 2.7624692 0.9070139 2.7818567 0.8876264 1 P 0
L 2.7677165 0.9762283 2.7677165 0.976378 1 P 0
L 2.7702859 0.9147535 2.7896083 0.8954311 1 P 0
L 2.771025 0.2795276 2.7795276 0.2795276 1 P 0
L 2.7992126 0.7951262 2.7992126 0.7952756 1 P 0
L 2.8038425 2.307063 2.8378425 2.341063 0 P 0
L 2.8074922 0.4855108 2.8074922 0.7751375 1 P 0
L 2.8184922 0.4854626 2.8184922 0.7751376 1 P 0
L 2.8218425 2.601063 3.5665583 2.601063 0 P 0
L 2.8267717 0.7951259 2.8267717 0.7952756 1 P 0
L 2.8378425 2.341063 3.4988425 2.341063 0 P 0
L 2.8418425 2.263063 3.3428425 2.263063 0 P 0
L 2.8602814 0.8551418 2.8818899 0.8551418 1 P 0
L 2.860319 0.8661418 2.8819379 0.8661418 1 P 0
L 2.8818899 0.8551417 2.8818899 0.8551418 1 P 0
L 2.8858266 0.3525952 2.8858267 0.3525504 1 P 0
L 2.8858267 0.2761384 2.8858267 0.3525504 1 P 0
L 2.8948425 1.561063 3.3278424 1.561063 0 P 0
L 2.8976377 0.2919382 2.8976377 0.3069387 1 P 0
L 2.8976377 0.2919382 2.8976378 0.2894382 1 P 0
L 2.8991022 0.2859026 2.8991023 0.2859027 1 P 0
L 2.8991023 0.2859027 2.9054946 0.2795104 1 P 0
L 2.9033267 0.3294387 2.9150082 0.3294387 1 P 0
L 2.9033267 0.3444387 2.9166213 0.3444387 1 P 0
L 2.9051377 0.3144387 2.9150082 0.3144387 1 P 0
L 2.9091203 0.3669387 2.9091203 0.3811515 1 P 0
L 2.9091203 0.3811515 2.9105847 0.384687 1 P 0
L 2.9105847 0.384687 2.9239307 0.3980326 1 P 0
L 2.9111366 0.4003551 2.9111917 0.4003926 1 P 0
L 2.9127082 0.4020274 2.9127084 0.4020274 1 P 0
L 2.9151331 0.8523919 2.925101 0.842424 1 P 0
L 2.9166203 0.3594387 2.9166213 0.3594387 1 P 0
L 2.9173227 0.4191344 2.9173229 0.4192037 1 P 0
L 2.9173229 0.4192037 2.9173229 0.820597 1 P 0
L 2.9198425 1.536063 3.8737836 1.536063 0 P 0
L 2.9235737 0.2755877 2.9235738 0.2755876 1 P 0
L 2.9238425 2.481063 2.9488425 2.456063 0 P 0
L 2.9239307 0.3980326 2.9264307 0.4005326 1 P 0
L 2.9264307 0.4005325 2.9268527 0.4009545 1 P 0
L 2.9283229 0.4044959 2.9283229 0.8346456 1 P 0
L 2.9284918 0.2795276 2.9370079 0.2795276 1 P 0
L 2.9746059 3.257563 2.9971059 3.235063 0 P 0
L 2.9933858 3.751063 3.6998425 3.751063 0 P 0
L 2.9971059 3.235063 3.2308425 3.235063 0 P 0
L 3.0148425 3.831063 3.0148425 3.8313767 0 P 0
L 3.0148425 3.8313767 3.0195288 3.836063 0 P 0
L 3.0195288 3.836063 3.6998425 3.836063 0 P 0
L 3.0371764 3.462063 3.0561764 3.481063 0 P 0
L 3.0561764 3.481063 3.5298425 3.481063 0 P 0
L 3.0823425 1.591063 3.0913425 1.600063 0 P 0
L 3.089567 2.7549213 3.2322834 2.8976377 0 P 0
L 3.0913425 1.600063 3.6993192 1.600063 0 P 0
L 3.0965519 2.9694882 3.0971267 2.970063 0 P 0
L 3.0971267 2.970063 3.1978425 2.970063 0 P 0
L 3.1830708 3.1358268 3.2106299 3.1358268 0 P 0
L 3.1889764 3.1870079 3.2322834 3.1870079 0 P 0
L 3.2029322 1.673063 3.2112164 1.6813472 0 P 0
L 3.2045475 1.693063 3.2058317 1.6943472 0 P 0
L 3.2058317 1.6943472 3.3121311 1.6943472 0 P 0
L 3.2106299 3.1358268 3.2627952 3.1879921 0 P 0
L 3.2112164 1.6813472 3.3067464 1.6813472 0 P 0
L 3.2322834 2.8976377 3.2322834 3.0984252 0 P 0
L 3.2322834 3.0984252 3.2755905 3.1417323 0 P 0
L 3.2322834 3.1870079 3.2608267 3.2155512 0 P 0
L 3.2528425 3.293063 3.2636972 3.3039177 0 P 0
L 3.2608267 3.2155512 3.468504 3.2155512 0 P 0
L 3.2627952 3.1879921 3.2972441 3.1879921 0 P 0
L 3.2755905 2.984252 3.2755905 3.019685 0 P 0
L 3.2755905 2.984252 3.2762598 2.9835827 0 P 0
L 3.2755905 3.019685 3.3316929 3.0757874 0 P 0
L 3.2762598 2.9648819 3.2762598 2.9835827 0 P 0
L 3.2762598 2.9648819 3.277559 2.9635827 0 P 0
L 3.277559 2.9635827 3.351548 2.8895937 0 P 0
L 3.2972441 3.1879921 3.3316929 3.1535433 0 P 0
L 3.3028425 3.344063 3.6125583 3.344063 0 P 0
L 3.3067464 1.6813472 3.3074427 1.6806509 0 P 0
L 3.3074427 1.6806509 3.4296266 1.6806509 0 P 0
L 3.3121311 1.6943472 3.3128274 1.6936509 0 P 0
L 3.3128274 1.6936509 3.4191267 1.6936509 0 P 0
L 3.3278424 1.561063 3.3368424 1.552063 0 P 0
L 3.3316929 3.0757874 3.3316929 3.1535433 0 P 0
L 3.3321267 1.941063 3.3571267 1.916063 0 P 0
L 3.3344993 1.916063 3.3504993 1.900063 0 P 0
L 3.3368424 1.552063 3.7698425 1.552063 0 P 0
L 3.3504993 1.900063 3.4440668 1.900063 0 P 0
L 3.351548 2.8895937 3.3693118 2.8895937 0 P 0
L 3.3571267 1.916063 3.5697836 1.916063 0 P 0
L 3.3666857 3.270563 3.367655 3.2715323 0 P 0
L 3.367655 3.2715323 3.3733118 3.2715323 0 P 0
L 3.3693118 2.8895937 3.3708425 2.888063 0 P 0
L 3.3733118 3.2715323 3.3748425 3.273063 0 P 0
L 3.3948425 3.447063 3.4413149 3.4005906 0 P 0
L 3.4025825 1.361063 3.4048425 1.363323 0 P 0
L 3.4071122 1.411493 3.4072822 1.411323 3 P 0
L 3.4191267 1.6936509 3.4365388 1.711063 0 P 0
L 3.4296266 1.6806509 3.4310387 1.682063 0 P 0
L 3.4310387 1.682063 3.5991267 1.682063 0 P 0
L 3.4365388 1.711063 3.5898425 1.711063 0 P 0
L 3.4368425 3.457063 3.4578425 3.436063 0 P 0
L 3.4413149 3.4005906 4.9268701 3.4005906 0 P 0
L 3.4440668 1.900063 3.4530668 1.891063 0 P 0
L 3.4530668 1.891063 3.5548425 1.891063 0 P 0
L 3.4578425 3.436063 6.4698425 3.436063 0 P 0
L 3.4658425 1.779063 3.4868425 1.800063 0 P 0
L 3.468504 3.2155512 3.6870079 2.9970473 0 P 0
L 3.4696294 1.616063 3.4771896 1.6236232 0 P 0
L 3.4698425 3.456063 6.5098425 3.456063 0 P 0
L 3.4758425 1.766063 3.4938425 1.784063 0 P 0
L 3.4771896 1.6236232 4.1513063 1.6236232 0 P 0
L 3.4838639 1.750063 3.4998639 1.766063 0 P 0
L 3.4868425 1.800063 3.6358639 1.800063 0 P 0
L 3.4938425 1.784063 3.7039014 1.784063 0 P 0
L 3.4998639 1.766063 3.7198425 1.766063 0 P 0
L 3.5048425 4.086063 3.5076771 4.0888976 0 P 0
L 3.5076771 4.0888976 5.2670079 4.0888976 0 P 0
L 3.542865 3.3190405 6.3426504 3.3190405 0 P 0
L 3.5437836 1.481063 3.5847836 1.440063 0 P 0
L 3.5448425 1.506063 3.5948425 1.456063 0 P 0
L 3.5665583 2.601063 3.5715583 2.606063 0 P 0
L 3.5697836 1.916063 3.5887836 1.897063 0 P 0
L 3.5715583 2.606063 3.6048425 2.606063 0 P 0
L 3.5789014 1.734063 3.5799014 1.735063 0 P 0
L 3.5799014 1.735063 4.1169015 1.735063 0 P 0
L 3.5847836 1.440063 3.9938425 1.440063 0 P 0
L 3.5887836 1.897063 3.7478425 1.897063 0 P 0
L 3.5948425 1.456063 3.9228425 1.456063 0 P 0
L 3.5991267 1.682063 3.6061267 1.675063 0 P 0
L 3.6048425 2.606063 3.6238425 2.587063 0 P 0
L 3.6061267 1.675063 3.7248425 1.675063 0 P 0
L 3.6125583 3.344063 3.6395583 3.371063 0 P 0
L 3.6358639 1.800063 3.6518639 1.816063 0 P 0
L 3.6395583 3.371063 6.4098425 3.371063 0 P 0
L 3.6518639 1.816063 3.9448425 1.816063 0 P 0
L 3.6538425 3.293063 3.6553732 3.2945937 0 P 0
L 3.6553732 3.2945937 3.66103 3.2945937 0 P 0
L 3.66103 3.2945937 3.6624993 3.296063 0 P 0
L 3.6624993 3.296063 6.4333481 3.296063 0 P 0
L 3.6870079 2.9970473 4.6053149 2.9970473 0 P 0
L 3.6993192 1.600063 3.7053192 1.606063 0 P 0
L 3.7039014 1.784063 3.7099015 1.7900631 0 P 0
L 3.7053192 1.606063 3.9529609 1.606063 0 P 0
L 3.7099015 1.7900631 3.9937072 1.7900631 0 P 0
L 3.7448425 3.261063 3.7470073 3.261063 0 P 0
L 3.7470073 3.261063 3.7507081 3.2647638 0 P 0
L 3.7478425 1.897063 3.8048425 1.840063 0 P 0
L 3.7507081 3.2647638 5.0495433 3.2647638 0 P 0
L 3.7698425 1.552063 3.8078425 1.590063 0 P 0
L 3.7827652 1.641063 3.7927652 1.651063 0 P 0
L 3.7927652 1.651063 4.1348425 1.651063 0 P 0
L 3.7998425 3.201063 3.8008425 3.200063 0 P 0
L 3.8008425 3.200063 6.3084161 3.200063 0 P 0
L 3.8068425 3.235063 6.2690865 3.235063 0 P 0
L 3.8078425 1.590063 3.9047836 1.590063 0 P 0
L 3.8298425 3.176063 6.2748425 3.176063 0 P 0
L 3.8548425 3.151063 3.8570073 3.151063 0 P 0
L 3.8570073 3.151063 3.8610072 3.1550629 0 P 0
L 3.8610072 3.1550629 4.0605582 3.1550629 0 P 0
L 3.8737836 1.536063 3.8977836 1.512063 0 P 0
L 3.8977836 1.512063 3.9581267 1.512063 0 P 0
L 3.9047836 1.590063 3.9308425 1.5640041 0 P 0
L 3.9228425 1.456063 3.9398425 1.473063 0 P 0
L 3.9308425 1.5640041 3.9519014 1.5640041 0 P 0
L 3.9398425 1.473063 3.9618425 1.473063 0 P 0
L 3.9398425 3.121063 3.9420073 3.121063 0 P 0
L 3.9420073 3.121063 3.9480072 3.1150631 0 P 0
L 3.9480072 3.1150631 4.0125669 3.1150631 0 P 0
L 3.9519014 1.5640041 3.9638425 1.552063 0 P 0
L 3.9529609 1.606063 3.9594007 1.5996232 0 P 0
L 3.9581267 1.512063 3.9898425 1.5437788 0 P 0
L 3.9594007 1.5996232 4.1784027 1.5996232 0 P 0
L 3.9618425 1.473063 4.0348425 1.546063 0 P 0
L 3.9638425 1.552063 3.9698425 1.552063 0 P 0
L 3.9700965 4.156063 4.0102271 4.1159324 0 P 0
L 3.9898425 1.5437788 3.9898425 1.5438982 0 P 0
L 3.9898425 1.5438982 3.9948425 1.5488982 0 P 0
L 3.9937072 1.7900631 3.9997071 1.796063 0 P 0
L 3.9938425 1.440063 4.0648425 1.511063 0 P 0
L 3.9948425 1.5488982 3.9948425 1.551063 0 P 0
L 3.9997071 1.796063 4.0648425 1.796063 0 P 0
L 4.0102271 4.1159324 4.7547119 4.1159324 0 P 0
L 4.0125669 3.1150631 4.012567 3.115063 0 P 0
L 4.012567 3.115063 6.2966777 3.115063 0 P 0
L 4.0605582 3.1550629 4.0605583 3.155063 0 P 0
L 4.0605583 3.155063 6.3336777 3.155063 0 P 0
L 4.1147946 2.661063 4.1805146 2.595343 0 P 0
L 4.1169015 1.735063 4.1329015 1.751063 0 P 0
L 4.1329015 1.751063 4.1348425 1.751063 0 P 0
L 4.1784027 1.5996232 4.1798425 1.601063 0 P 0
L 4.2129048 2.681063 4.2986248 2.595343 0 P 0
L 4.6053149 2.9970473 4.7942913 2.8080709 0 P 0
L 4.9268701 3.4005906 4.9273425 3.401063 0 P 0
L 4.9273425 3.401063 6.4404124 3.401063 0 P 0
L 5.0495433 3.2647638 5.0508425 3.266063 0 P 0
L 5.0508425 3.266063 6.3348425 3.266063 0 P 0
L 6.2690865 3.235063 6.2780865 3.226063 0 P 0
L 6.2748425 3.176063 6.2758425 3.175063 0 P 0
L 6.2758425 3.175063 6.3617929 3.175063 0 P 0
L 6.2780865 3.226063 6.2824161 3.226063 0 P 0
L 6.2966777 3.115063 6.3026777 3.121063 0 P 0
L 6.3026777 3.121063 6.3048425 3.121063 0 P 0
L 6.3084161 3.200063 6.3094161 3.199063 0 P 0
L 6.3336777 3.155063 6.3376777 3.151063 0 P 0
L 6.3376777 3.151063 6.3398425 3.151063 0 P 0
L 6.3426504 3.3190405 6.3547483 3.3311384 0 P 0
L 6.3617929 3.175063 6.3777929 3.191063 0 P 0
L 6.3777929 3.191063 6.4398425 3.191063 0 P 0
L 6.4333481 3.296063 6.4383481 3.291063 0 P 0
L 6.4383481 3.291063 6.4448425 3.291063 0 P 0
L 6.4404124 3.401063 6.4454124 3.396063 0 P 0
L 6.4454124 3.396063 6.4475772 3.396063 0 P 0
L 6.4698425 3.436063 6.4798425 3.426063 0 P 0
P 2.0433071 4.157874 6 P 0 0 ;0=0,1=0
P 4.1805146 2.595343 7 P 0 0 ;0=1,1=0
P 4.2986248 2.595343 7 P 0 0 ;0=1,1=0
P 0.988189 1.7175197 8 P 0 0 ;0=2,1=1
P 0.996063 1.1870079 8 P 0 0 ;0=2,1=1
P 0.9968357 2.256036 8 P 0 0 ;0=2,1=1
P 1.0048425 0.906063 8 P 0 0 ;0=2,1=1
P 1.0088425 1.430063 8 P 0 0 ;0=2,1=1
P 1.0098425 1.956063 8 P 0 0 ;0=2,1=1
P 1.0208425 2.481063 8 P 0 0 ;0=2,1=1
P 1.2948425 4.256063 8 P 0 0 ;0=2,1=1
P 1.3937008 1.8169291 8 P 0 0 ;0=2,1=1
P 1.4084645 3.980315 8 P 0 0 ;0=2,1=1
P 1.4408425 3.557063 8 P 0 0 ;0=2,1=1
P 1.4598425 3.147063 8 P 0 0 ;0=2,1=1
P 1.5498425 3.621063 8 P 0 0 ;0=2,1=1
P 1.5679134 1.2854331 8 P 0 0 ;0=2,1=1
P 1.5698819 4.1712599 8 P 0 0 ;0=2,1=1
P 1.5748425 3.596063 8 P 0 0 ;0=2,1=1
P 1.7548425 3.661063 8 P 0 0 ;0=2,1=1
P 1.7798425 4.156063 8 P 0 0 ;0=2,1=1
P 1.7982283 1.3041339 8 P 0 0 ;0=2,1=1
P 1.8227825 1.674003 8 P 0 0 ;0=2,1=1
P 1.8498425 3.701063 8 P 0 0 ;0=2,1=1
P 1.8799377 1.811803 8 P 0 0 ;0=2,1=1
P 1.8848425 3.601063 8 P 0 0 ;0=2,1=1
P 1.8938425 1.693063 8 P 0 0 ;0=2,1=1
P 1.9038425 4.018063 8 P 0 0 ;0=2,1=1
P 2.0048425 1.336063 8 P 0 0 ;0=2,1=1
P 2.0288425 1.361663 8 P 0 0 ;0=2,1=1
P 2.0598425 1.386063 8 P 0 0 ;0=2,1=1
P 2.0838425 1.411663 8 P 0 0 ;0=2,1=1
P 2.2058425 3.200063 8 P 0 0 ;0=2,1=1
P 2.2068425 1.298063 8 P 0 0 ;0=2,1=1
P 2.2348425 3.506063 8 P 0 0 ;0=2,1=1
P 2.2598425 3.261063 8 P 0 0 ;0=2,1=1
P 2.2748425 1.506063 8 P 0 0 ;0=2,1=1
P 2.2998425 1.916063 8 P 0 0 ;0=2,1=1
P 2.3308425 2.215063 8 P 0 0 ;0=2,1=1
P 2.3533464 4.0177165 8 P 0 0 ;0=2,1=1
P 2.3848425 1.941063 8 P 0 0 ;0=2,1=1
P 2.394685 2.7204724 8 P 0 0 ;0=2,1=1
P 2.4098425 1.967063 8 P 0 0 ;0=2,1=1
P 2.4098425 2.314063 8 P 0 0 ;0=2,1=1
P 2.4133858 0.2795276 8 P 0 0 ;0=2,1=1
P 2.4140551 3.1998504 8 P 0 0 ;0=2,1=1
P 2.4187174 3.1185066 8 P 0 0 ;0=2,1=1
P 2.4291925 2.621063 8 P 0 0 ;0=2,1=1
P 2.4348425 3.546063 8 P 0 0 ;0=2,1=1
P 2.4448819 0.2795276 8 P 0 0 ;0=2,1=1
P 2.4468425 1.437063 8 P 0 0 ;0=2,1=1
P 2.462374 3.1722441 8 P 0 0 ;0=2,1=1
P 2.4788425 0.937063 8 P 0 0 ;0=2,1=1
P 2.4948425 2.661063 8 P 0 0 ;0=2,1=1
P 2.4948425 2.696063 8 P 0 0 ;0=2,1=1
P 2.4998425 2.236063 8 P 0 0 ;0=2,1=1
P 2.5028425 1.316063 8 P 0 0 ;0=2,1=1
P 2.5258425 2.463063 8 P 0 0 ;0=2,1=1
P 2.5498425 1.755063 8 P 0 0 ;0=2,1=1
P 2.5708425 4.283063 8 P 0 0 ;0=2,1=1
P 2.5758425 2.412063 8 P 0 0 ;0=2,1=1
P 2.5787402 0.2795276 8 P 0 0 ;0=2,1=1
P 2.5798425 1.790063 8 P 0 0 ;0=2,1=1
P 2.5908425 3.288063 8 P 0 0 ;0=2,1=1
P 2.5918425 3.1862205 8 P 0 0 ;0=2,1=1
P 2.6048425 1.734063 8 P 0 0 ;0=2,1=1
P 2.6102362 0.2795276 8 P 0 0 ;0=2,1=1
P 2.6220472 0.976378 8 P 0 0 ;0=2,1=1
P 2.6268425 1.770063 8 P 0 0 ;0=2,1=1
P 2.6438425 1.616063 8 P 0 0 ;0=2,1=1
P 2.6458425 2.274063 8 P 0 0 ;0=2,1=1
P 2.6496063 0.976378 8 P 0 0 ;0=2,1=1
P 2.6653543 0.7952756 8 P 0 0 ;0=2,1=1
P 2.6668425 1.640063 8 P 0 0 ;0=2,1=1
P 2.6798425 3.661063 8 P 0 0 ;0=2,1=1
P 2.6929134 0.7952756 8 P 0 0 ;0=2,1=1
P 2.6948425 1.481063 8 P 0 0 ;0=2,1=1
P 2.7198425 1.591063 8 P 0 0 ;0=2,1=1
P 2.7401575 0.976378 8 P 0 0 ;0=2,1=1
P 2.74882 0.282312 8 P 0 0 ;0=2,1=1
P 2.7677165 0.976378 8 P 0 0 ;0=2,1=1
P 2.7795276 0.2795276 8 P 0 0 ;0=2,1=1
P 2.7992126 0.7952756 8 P 0 0 ;0=2,1=1
P 2.7998425 3.616063 8 P 0 0 ;0=2,1=1
P 2.8038425 2.307063 8 P 0 0 ;0=2,1=1
P 2.8218425 2.601063 8 P 0 0 ;0=2,1=1
P 2.8267717 0.7952756 8 P 0 0 ;0=2,1=1
P 2.8418425 2.263063 8 P 0 0 ;0=2,1=1
P 2.8948425 1.561063 8 P 0 0 ;0=2,1=1
P 2.9054946 0.2795104 8 P 0 0 ;0=2,1=1
P 2.9198425 1.536063 8 P 0 0 ;0=2,1=1
P 2.9370079 0.2795276 8 P 0 0 ;0=2,1=1
P 2.9488425 2.456063 8 P 0 0 ;0=2,1=1
P 2.9588425 2.621063 8 P 0 0 ;0=2,1=1
P 2.9933858 3.751063 8 P 0 0 ;0=2,1=1
P 3.0148425 3.831063 8 P 0 0 ;0=2,1=1
P 3.0568817 1.811803 8 P 0 0 ;0=2,1=1
P 3.1830708 3.1358268 8 P 0 0 ;0=2,1=1
P 3.1889764 3.1870079 8 P 0 0 ;0=2,1=1
P 3.1978425 2.970063 8 P 0 0 ;0=2,1=1
P 3.2308425 3.235063 8 P 0 0 ;0=2,1=1
P 3.2398425 3.596063 8 P 0 0 ;0=2,1=1
P 3.2636972 3.3039177 8 P 0 0 ;0=2,1=1
P 3.2755905 3.1417323 8 P 0 0 ;0=2,1=1
P 3.277559 2.9635827 8 P 0 0 ;0=2,1=1
P 3.3028425 3.344063 8 P 0 0 ;0=2,1=1
P 3.3428425 2.263063 8 P 0 0 ;0=2,1=1
P 3.3708425 2.888063 8 P 0 0 ;0=2,1=1
P 3.3748425 3.273063 8 P 0 0 ;0=2,1=1
P 3.3798425 1.336063 8 P 0 0 ;0=2,1=1
P 3.3798425 1.386063 8 P 0 0 ;0=2,1=1
P 3.3948425 3.447063 8 P 0 0 ;0=2,1=1
P 3.4048425 1.363323 8 P 0 0 ;0=2,1=1
P 3.4072822 1.411323 8 P 0 0 ;0=2,1=1
P 3.4248425 3.636063 8 P 0 0 ;0=2,1=1
P 3.4368425 3.457063 8 P 0 0 ;0=2,1=1
P 3.4698425 3.456063 8 P 0 0 ;0=2,1=1
P 3.4988425 2.341063 8 P 0 0 ;0=2,1=1
P 3.5048425 4.086063 8 P 0 0 ;0=2,1=1
P 3.5298425 3.481063 8 P 0 0 ;0=2,1=1
P 3.542865 3.3190405 8 P 0 0 ;0=2,1=1
P 3.5548425 1.891063 8 P 0 0 ;0=2,1=1
P 3.5898425 1.711063 8 P 0 0 ;0=2,1=1
P 3.6238425 2.587063 8 P 0 0 ;0=2,1=1
P 3.6538425 3.293063 8 P 0 0 ;0=2,1=1
P 3.6998425 3.751063 8 P 0 0 ;0=2,1=1
P 3.6998425 3.836063 8 P 0 0 ;0=2,1=1
P 3.7198425 1.766063 8 P 0 0 ;0=2,1=1
P 3.7248425 1.675063 8 P 0 0 ;0=2,1=1
P 3.7448425 3.261063 8 P 0 0 ;0=2,1=1
P 3.7998425 3.201063 8 P 0 0 ;0=2,1=1
P 3.8048425 1.840063 8 P 0 0 ;0=2,1=1
P 3.8068425 3.235063 8 P 0 0 ;0=2,1=1
P 3.8298425 3.176063 8 P 0 0 ;0=2,1=1
P 3.8548425 3.151063 8 P 0 0 ;0=2,1=1
P 3.9398425 3.121063 8 P 0 0 ;0=2,1=1
P 3.9448425 1.816063 8 P 0 0 ;0=2,1=1
P 3.9698425 1.552063 8 P 0 0 ;0=2,1=1
P 3.9948425 1.551063 8 P 0 0 ;0=2,1=1
P 4.0348425 1.546063 8 P 0 0 ;0=2,1=1
P 4.0398425 2.406063 8 P 0 0 ;0=2,1=1
P 4.0648425 1.511063 8 P 0 0 ;0=2,1=1
P 4.0648425 1.796063 8 P 0 0 ;0=2,1=1
P 4.1348425 1.651063 8 P 0 0 ;0=2,1=1
P 4.1348425 1.751063 8 P 0 0 ;0=2,1=1
P 4.1513063 1.6236232 8 P 0 0 ;0=2,1=1
P 4.1798425 1.601063 8 P 0 0 ;0=2,1=1
P 4.7547119 4.1159324 8 P 0 0 ;0=2,1=1
P 4.7942913 2.8080709 8 P 0 0 ;0=2,1=1
P 5.2670079 4.0888976 8 P 0 0 ;0=2,1=1
P 5.5778425 2.214063 8 P 0 0 ;0=2,1=1
P 5.6348425 2.236063 8 P 0 0 ;0=2,1=1
P 6.2824161 3.226063 8 P 0 0 ;0=2,1=1
P 6.2948425 3.701063 8 P 0 0 ;0=2,1=1
P 6.3048425 3.121063 8 P 0 0 ;0=2,1=1
P 6.3094161 3.199063 8 P 0 0 ;0=2,1=1
P 6.3348425 3.266063 8 P 0 0 ;0=2,1=1
P 6.3398425 3.151063 8 P 0 0 ;0=2,1=1
P 6.3547483 3.3311384 8 P 0 0 ;0=2,1=1
P 6.4098425 3.371063 8 P 0 0 ;0=2,1=1
P 6.4398425 3.191063 8 P 0 0 ;0=2,1=1
P 6.4448425 3.291063 8 P 0 0 ;0=2,1=1
P 6.4475772 3.396063 8 P 0 0 ;0=2,1=1
P 6.4798425 3.426063 8 P 0 0 ;0=2,1=1
P 6.5098425 3.456063 8 P 0 0 ;0=2,1=1

### steps/pcb/layers/in2/features
#Layer_Physical_Order=4
#Layer_Color=6736896
#
#Feature symbol names
#
$0 r8
$1 r5
$2 r20
$3 r6
$4 r3.937
$5 r1
$6 s55
$7 r75
$8 r61.0236
$9 r16

#
#Feature attribute names
#
@0 .geometry
@1 .pad_usage

#
#Feature attribute text strings
#
&0 Pad_Simple_X55.0000Y55.0000H30.0000C70.0000
&1 Pad_Simple_X75.0000Y75.0000H50.0000C90.0000
&2 Pad_Simple_X61.0236Y61.0236H41.3386C81.3386
&3 VIA_RoundD16.0000H8.0000C48.0000

#
#Layer features
#
A 1.7712204 0.4310709 1.6275196 0.4310709 1.69937 0.4310709 4 P 0 N
A 2.2942913 3.9019358 2.2966345 3.8962788 2.3022913 3.9019358 0 P 0 N
A 2.3503937 0.4055118 2.351997 0.4048477 2.351997 0.4071151 1 P 0 N
A 2.3631142 0.4033832 2.3595786 0.4048477 2.3595786 0.3998476 1 P 0 N
A 2.3645787 0.3975695 2.367654 0.3901451 2.3750784 0.3975695 1 P 0 N
A 2.3645787 0.3998476 2.3631142 0.4033832 2.3595786 0.3998476 1 P 0 N
A 2.3755787 0.3998477 2.3770431 0.3963123 2.3805785 0.3998477 1 P 0 N
A 2.3770432 0.403383 2.3755788 0.3998477 2.3805785 0.3998477 1 P 0 N
A 2.380579 0.4048477 2.3770431 0.4033831 2.380579 0.3998472 1 P 0 N
A 2.3881605 0.4048477 2.3897638 0.4055118 2.3881605 0.4071151 1 P 0 N
A 2.3896338 0.3681652 2.4495895 0.3433308 2.4495895 0.4281209 1 P 0 N
A 2.3973016 0.3760536 2.4094488 0.3662328 2.4497454 0.4284974 1 P 0 N
A 2.4094488 0.3662328 2.4119488 0.3646842 2.4497454 0.4284974 1 P 0 N
A 2.4190699 0.3627335 2.4285515 0.369967 2.4210515 0.369967 1 P 0 N
A 2.4251968 0.4367471 2.4717322 0.3902121 2.4717321 0.4367474 1 P 0 N
A 2.4426969 0.4831502 2.4426969 0.4681502 2.4426969 0.4756502 1 P 0 N
A 2.4435515 0.3617492 2.44907 0.3545157 2.4510515 0.3617492 1 P 0 N
A 2.4435515 0.372224 2.4285515 0.372224 2.4360515 0.372224 1 P 0 N
A 2.4448819 0.5056502 2.4523819 0.4981502 2.4523819 0.5056502 1 P 0 N
A 2.444882 0.4237558 2.4467999 0.4196224 2.4501986 0.423711 1 P 0 N
A 2.4523819 0.4531502 2.4448819 0.4456502 2.4523819 0.4456502 1 P 0 N
A 2.4531483 0.4142057 2.4531191 0.4142307 2.4498846 0.4104173 1 P 0 N
A 2.4531646 0.4141917 2.4696367 0.4109015 2.4643476 0.4273002 1 P 0 N
A 2.4567253 0.4831502 2.4567253 0.4981502 2.4567253 0.4906502 1 P 0 N
A 2.4588273 0.4531502 2.4588273 0.4681502 2.4588273 0.4606502 1 P 0 N
A 2.4663545 0.7301341 2.4251968 0.6308028 2.5657178 0.6307707 1 P 0 N
A 2.4741712 0.7223944 2.4448819 0.6516837 2.5448819 0.6516837 1 P 0 N
A 2.4965115 0.3902123 2.511811 0.4055118 2.4965115 0.4055118 1 P 0 N
A 2.5281855 2.6187369 2.5258424 2.61308 2.5338425 2.61308 0 P 0 N
A 2.5354811 0.3433308 2.543177 0.3465186 2.5354811 0.3542145 1 P 0 N
A 2.5521855 2.6151778 2.5498424 2.6095209 2.5578425 2.6095209 0 P 0 N
A 2.5774155 0.3963132 2.6067048 0.4670239 2.5067048 0.4670239 1 P 0 N
A 2.5798424 3.6097971 2.5774717 3.6154416 2.5718422 3.6097571 0 P 0 N
A 2.5852321 0.3885736 2.6177047 0.4669693 2.5068364 0.4669693 1 P 0 N
A 2.6067048 0.7751375 2.5984252 0.7951262 2.5784365 0.7751375 1 P 0 N
A 2.6259843 0.7951259 2.6177049 0.7751376 2.6459728 0.7751376 1 P 0 N
A 2.6649797 2.7555307 2.6673229 2.7611877 2.6593228 2.7611877 0 P 0 N
A 2.6715037 0.3993623 2.735091 0.3923416 2.7076684 0.4354416 1 P 0 N
A 2.6841536 0.9479333 2.6893818 0.9605552 2.6715317 0.9605552 1 P 0 N
A 2.6846648 2.7476567 2.687008 2.7533137 2.6790079 2.7533137 0 P 0 N
A 2.6893819 0.9605552 2.6841537 0.9731772 2.6715317 0.9605552 1 P 0 N
A 2.6935428 0.9417659 2.7003819 0.9582771 2.6770316 0.9582771 1 P 0 N
A 2.7047243 0.4055116 2.7340575 0.4061129 2.7190989 0.4200595 1 P 0 N
A 2.707221 0.974788 2.7003819 0.9582771 2.7237319 0.9582771 1 P 0 N
A 2.7310449 0.5184503 2.7310449 0.5034503 2.7310449 0.5109503 1 P 0 N
A 2.7322151 0.4884503 2.7322151 0.4734503 2.7322151 0.4809503 1 P 0 N
A 2.733062 0.4584503 2.733062 0.4434503 2.733062 0.4509503 1 P 0 N
A 2.733063 0.5184503 2.740563 0.5259503 2.733063 0.5259503 1 P 0 N
A 2.7340575 0.4061129 2.7353582 0.4076537 2.7190989 0.4200595 1 P 0 N
A 2.734063 0.4584503 2.734063 0.4734503 2.734063 0.4659503 1 P 0 N
A 2.734063 0.4884503 2.734063 0.5034503 2.734063 0.4959503 1 P 0 N
A 2.735091 0.3923416 2.7515629 0.4223505 2.7159911 0.4223507 1 P 0 N
A 2.7353742 0.4076749 2.736048 0.4086129 2.7147607 0.423194 1 P 0 N
A 2.740563 0.4359503 2.733063 0.4434503 2.733063 0.4359503 1 P 0 N
A 2.740563 0.7751376 2.7322835 0.7951261 2.712295 0.7751376 1 P 0 N
A 2.7598425 0.7951259 2.7515631 0.7751376 2.779831 0.7751376 1 P 0 N
A 2.8033685 0.4075234 2.8096946 0.3934558 2.8251276 0.4088521 1 P 0 N
A 2.8074922 0.9582771 2.8006531 0.974788 2.7841422 0.9582771 1 P 0 N
A 2.8074922 0.9582771 2.8143313 0.9417659 2.8308425 0.9582771 1 P 0 N
A 2.8097215 0.3934295 2.8405136 0.393003 2.8253402 0.4092878 1 P 0 N
A 2.8119314 0.430042 2.8033666 0.4075566 2.8331009 0.4091045 1 P 0 N
A 2.8184922 0.9605552 2.8237204 0.9479332 2.8363424 0.9605552 1 P 0 N
A 2.8237204 0.9731771 2.8184923 0.9605552 2.8363424 0.9605552 1 P 0 N
A 2.8405136 0.393003 2.8421142 0.3966697 2.8371141 0.3966697 1 P 0 N
A 2.8438426 0.4016785 2.8421142 0.3975056 2.8480156 0.3975056 1 P 0 N
A 2.8474989 0.4369234 2.8368923 0.4369235 2.8421956 0.4316201 1 P 0 N
A 2.8480156 0.4034071 2.8438426 0.4016786 2.8480156 0.3975056 1 P 0 N
A 2.8492495 0.4034071 2.8543307 0.4055118 2.8492495 0.410593 1 P 0 N
A 2.8515207 0.4329018 2.8621272 0.4329017 2.856824 0.4382051 1 P 0 N
A 2.8561371 0.460105 2.8561372 0.4494985 2.8614405 0.4548018 1 P 0 N
A 2.8621272 0.4329017 2.8621272 0.4435083 2.8568239 0.438205 1 P 0 N
A 2.8667437 0.460105 2.8561371 0.460105 2.8614404 0.4548017 1 P 0 N
A 2.8709826 0.4890923 2.8724529 0.4926337 2.8674528 0.4926337 1 P 0 N
A 2.8724528 0.7705345 2.8622047 0.7952756 2.8374636 0.7705345 1 P 0 N
A 2.872734 0.4541149 2.8833405 0.4541148 2.8780373 0.4594182 1 P 0 N
A 2.8793188 0.4793498 2.8793188 0.4687431 2.8846221 0.4740465 1 P 0 N
A 2.8819883 0.482019 2.8819663 0.4819972 2.8855022 0.4784614 1 P 0 N
A 2.8819883 0.482019 2.8834529 0.4855546 2.8784529 0.4855546 1 P 0 N
A 2.8833405 0.4541148 2.8833405 0.4647214 2.8780372 0.4594181 1 P 0 N
A 2.8937008 0.7952755 2.8834529 0.7705347 2.9184417 0.7705347 1 P 0 N
A 2.9251969 0.789479 2.8959076 0.8601896 2.8251969 0.789479 1 P 0 N
A 2.925197 0.4700228 2.9534811 0.3998375 3.0259409 0.46983 1 P 0 N
A 2.9361969 0.8087645 2.9173228 0.8543308 2.8717563 0.8087645 1 P 0 N
A 2.9380196 0.4933436 2.9450738 0.4883909 2.9450738 0.4958909 1 P 0 N
A 2.9452235 0.4733909 2.9452235 0.4583909 2.9452235 0.4658909 1 P 0 N
A 2.953481 0.3998374 2.9536063 0.3997118 2.957083 0.4033057 1 P 0 N
A 2.9539854 0.399345 2.9544564 0.3990509 2.982837 0.4450253 1 P 0 N
A 2.9544564 0.3990509 2.9740968 0.3917082 2.982837 0.4450253 1 P 0 N
A 2.9551168 0.4733909 2.9551168 0.4883909 2.9551168 0.4808909 1 P 0 N
A 2.9667398 0.4433909 2.9596857 0.4333435 2.9667398 0.4358909 1 P 0 N
A 2.9667408 0.4433909 2.9667408 0.4583909 2.9667408 0.4508909 1 P 0 N
A 2.9748134 0.3915357 2.9740968 0.3917083 2.973288 0.3867737 1 P 0 N
A 2.9748134 0.3915357 2.9837232 0.3909445 2.980457 0.4091539 1 P 0 N
A 2.975631 0.4123601 2.979314 0.4098601 3.0155239 0.4671675 1 P 0 N
A 2.979314 0.4098601 2.9804568 0.4091538 3.0155239 0.4671675 1 P 0 N
A 2.9844564 0.3910209 3.0196848 0.4055115 2.982837 0.4450253 1 P 0 N
A 2.9844564 0.391021 2.9837232 0.3909446 2.9846063 0.3860228 1 P 0 N
L -0.0001175 0.177913 0.5908825 0.177913 5 P 0
L -0.0004331 0.1781182 0.5901181 0.1781182 4 P 0
L 0.5901181 0.1781182 0.5901181 0.5029213 4 P 0
L 0.5901181 0.5029213 1.312559 0.5029213 4 P 0
L 0.5908825 0.177913 0.5908825 0.502913 5 P 0
L 0.9901575 0.6870079 1.2175197 0.6870079 0 P 0
L 1.2175197 0.6870079 1.363189 0.8326772 0 P 0
L 1.312559 0.313945 1.312559 0.5029213 4 P 0
L 1.312559 0.313945 1.6275197 0.313945 4 P 0
L 1.3454724 4.1751969 1.3454724 4.2667323 0 P 0
L 1.3454724 4.2667323 1.3937007 4.3149606 0 P 0
L 1.363189 0.8326772 1.363189 1.7864173 0 P 0
L 1.363189 1.7864173 1.3937008 1.8169291 0 P 0
L 1.3808425 3.617063 1.3808425 4.202063 0 P 0
L 1.3808425 3.617063 1.4408425 3.557063 0 P 0
L 1.3808425 4.202063 1.4388425 4.260063 0 P 0
L 1.3937007 4.3149606 1.5866142 4.3149606 0 P 0
L 1.4598425 3.147063 1.4598425 3.4637795 0 P 0
L 1.4598425 3.4637795 1.4783464 3.4822834 0 P 0
L 1.4783464 3.4822834 1.4783464 3.8928483 0 P 0
L 1.4783464 3.8928483 1.6318897 4.0463916 0 P 0
L 1.5498424 2.4652788 1.5498424 3.6210629 0 P 0
L 1.5498424 2.4652788 1.5498425 2.4652787 0 P 0
L 1.5498424 3.6210629 1.5498425 3.621063 0 P 0
L 1.5498425 2.4078367 1.5498425 2.4652787 0 P 0
L 1.5498425 2.4078367 1.5682025 2.3894767 0 P 0
L 1.5682025 2.067703 1.5682025 2.3894767 0 P 0
L 1.5748425 2.4202363 1.5748425 3.596063 0 P 0
L 1.5748425 2.4202363 1.6198425 2.3752363 0 P 0
L 1.5866142 4.3149606 1.625 4.2765748 0 P 0
L 1.6198425 2.121063 1.6198425 2.3752363 0 P 0
L 1.625 4.2765748 1.8818897 4.2765748 0 P 0
L 1.6275197 0.313945 1.6275197 0.4310709 4 P 0
L 1.6318897 4.0463916 1.6318897 4.1998032 0 P 0
L 1.6318897 4.1998032 1.6811023 4.2490158 0 P 0
L 1.6811023 4.2490158 1.8366141 4.2490158 0 P 0
L 1.7198425 1.536063 1.7798425 1.596063 0 P 0
L 1.7548425 2.126063 1.7548425 3.661063 0 P 0
L 1.7798425 1.596063 1.7798425 4.156063 0 P 0
L 1.8366141 4.2490158 1.9251968 4.1604331 0 P 0
L 1.8498425 0.271063 1.8498425 3.701063 2 P 0
L 1.8818897 4.2765748 1.9517716 4.2066929 0 P 0
L 1.8848425 2.071063 1.8848425 3.601063 0 P 0
L 1.9251968 4.160433 1.9251968 4.1604331 0 P 0
L 1.9251968 4.160433 1.9793306 4.1062992 0 P 0
L 1.9517716 4.2066929 2.1437008 4.2066929 0 P 0
L 1.9793306 4.1062992 2.143558 4.1062992 0 P 0
L 2.0048425 1.336063 2.0048425 3.816063 0 P 0
L 2.0288425 1.361663 2.0298425 1.362663 0 P 0
L 2.0298425 1.362663 2.0298425 3.836063 0 P 0
L 2.0433071 4.257874 2.1633858 4.257874 0 P 0
L 2.0598425 1.386063 2.0598425 3.871063 0 P 0
L 2.0838425 1.411663 2.0843425 1.412163 3 P 0
L 2.0843425 1.412163 2.0843425 3.895563 3 P 0
L 2.0843425 3.895563 2.0848425 3.896063 3 P 0
L 2.143558 4.1062992 2.1460663 4.1037909 0 P 0
L 2.1437008 4.2066929 2.2058425 4.1445512 0 P 0
L 2.1633858 4.257874 2.2942913 4.1269685 0 P 0
L 2.2058425 1.299063 2.2058425 2.4089566 0 P 0
L 2.2058425 1.299063 2.2068425 1.298063 0 P 0
L 2.2058425 2.4089566 2.2259625 2.4290766 0 P 0
L 2.2058425 2.4681094 2.2058425 3.200063 0 P 0
L 2.2058425 2.4681094 2.2259625 2.4479894 0 P 0
L 2.2058425 3.200063 2.2058425 4.1445512 0 P 0
L 2.2259625 2.4290766 2.2259625 2.4479894 0 P 0
L 2.2298425 2.586063 2.2298425 3.4988982 0 P 0
L 2.2298425 3.4988982 2.2348425 3.5038982 0 P 0
L 2.2348425 3.5038982 2.2348425 3.506063 0 P 0
L 2.2523425 2.613563 2.2598425 2.621063 0 P 0
L 2.253937 3.8474409 2.253937 4.0866142 0 P 0
L 2.253937 3.8474409 2.4793307 3.6220472 0 P 0
L 2.2548425 3.536063 2.2998425 3.491063 0 P 0
L 2.2598425 2.621063 2.2598425 3.261063 0 P 0
L 2.2720325 2.2891572 2.2720325 2.463873 0 P 0
L 2.2720325 2.2891572 2.2748425 2.2863472 0 P 0
L 2.2748425 1.506063 2.2748425 2.2863472 0 P 0
L 2.2942913 3.9019358 2.2942913 4.1269685 0 P 0
L 2.2966345 3.8962788 2.5774718 3.6154415 0 P 0
L 2.2998424 1.916063 2.2998425 3.491063 0 P 0
L 2.3415354 2.4470859 2.3415354 3.4305911 0 P 0
L 2.3415354 2.4470859 2.3898425 2.3987788 0 P 0
L 2.3415354 3.4305911 2.3898425 3.4788982 0 P 0
L 2.351997 0.4048477 2.3595786 0.4048477 1 P 0
L 2.3622047 2.6880508 2.3622047 3.2989023 0 P 0
L 2.3622047 2.6880508 2.4291925 2.621063 0 P 0
L 2.3622047 3.2989023 2.4594558 3.3961534 0 P 0
L 2.3645787 0.3975695 2.3645787 0.3998476 1 P 0
L 2.367654 0.3901451 2.3896338 0.3681653 1 P 0
L 2.3755787 0.3998477 2.3755788 0.3998477 1 P 0
L 2.3770431 0.3963123 2.3973017 0.3760537 1 P 0
L 2.380579 0.4048477 2.3881605 0.4048477 1 P 0
L 2.3848425 1.941063 2.3848425 1.9432278 0 P 0
L 2.3848425 1.9432278 2.3898425 1.9482278 0 P 0
L 2.3858268 3.019685 2.3858268 3.2982284 0 P 0
L 2.3858268 3.019685 2.3864999 3.0190119 0 P 0
L 2.3858268 3.2982284 2.4793307 3.3917323 0 P 0
L 2.3864999 2.7694056 2.3864999 3.0190119 0 P 0
L 2.3864999 2.7694056 2.4948425 2.661063 0 P 0
L 2.3898425 1.9482278 2.3898425 2.3987788 0 P 0
L 2.3898425 3.4788982 2.3898425 3.481063 0 P 0
L 2.4098425 1.967063 2.4098425 2.283063 0 P 0
L 2.4119488 0.3646842 2.41907 0.3627335 1 P 0
L 2.4190699 0.3627334 2.41907 0.3627335 1 P 0
L 2.4251968 0.6308028 2.4251969 0.4367472 1 P 0
L 2.4285515 0.369967 2.4285515 0.372224 1 P 0
L 2.4348425 3.546063 2.4594558 3.5214497 0 P 0
L 2.4426969 0.4681502 2.4588273 0.4681502 1 P 0
L 2.4426969 0.4831502 2.4567253 0.4831502 1 P 0
L 2.4435515 0.3617492 2.4435515 0.372224 1 P 0
L 2.4448819 0.4237558 2.4448819 0.4281497 1 P 0
L 2.4448819 0.4281497 2.4448819 0.4456502 1 P 0
L 2.4448819 0.5056502 2.4448819 0.5620079 1 P 0
L 2.4448819 0.5620079 2.4448819 0.6516837 1 P 0
L 2.4467998 0.4196223 2.4531191 0.4142306 1 P 0
L 2.4468425 1.437063 2.4468425 2.2758982 0 P 0
L 2.4468425 2.2758982 2.4508425 2.2798982 0 P 0
L 2.44907 0.3545156 2.4490701 0.3545157 1 P 0
L 2.4490701 0.3545157 2.4497454 0.3543307 1 P 0
L 2.4495895 0.3433308 2.5354811 0.3433308 1 P 0
L 2.4497454 0.3543307 2.4606299 0.3543308 1 P 0
L 2.4508425 2.2798982 2.4508425 2.282063 0 P 0
L 2.4523819 0.4531502 2.4588273 0.4531502 1 P 0
L 2.4523819 0.4981502 2.4567253 0.4981502 1 P 0
L 2.4531483 0.4142057 2.4531647 0.4141918 1 P 0
L 2.4594558 3.3961534 2.4594558 3.5214497 0 P 0
L 2.4606299 0.3543308 2.468552 0.3543308 1 P 0
L 2.462374 3.1722441 2.6535433 2.9810748 0 P 0
L 2.4663546 0.7301341 2.466393 0.7301725 1 P 0
L 2.466393 0.7301725 2.4763779 0.7401574 1 P 0
L 2.468552 0.3543308 2.5354331 0.3543308 1 P 0
L 2.4696367 0.4109016 2.469871 0.4109766 1 P 0
L 2.469871 0.4109766 2.4698827 0.4109883 1 P 0
L 2.4717322 0.3902122 2.4782363 0.3902122 1 P 0
L 2.4741712 0.7223944 2.4841561 0.7323793 1 P 0
L 2.4758425 2.291063 2.4788425 2.288063 0 P 0
L 2.4763779 0.7401574 2.6841537 0.9479332 1 P 0
L 2.4782363 0.3902122 2.478281 0.3902123 1 P 0
L 2.478281 0.3902123 2.4965115 0.3902123 1 P 0
L 2.4788425 0.937063 2.4788425 2.288063 0 P 0
L 2.4793307 3.3917323 2.4793307 3.6220472 0 P 0
L 2.4841561 0.7323793 2.6935428 0.941766 1 P 0
L 2.5028425 1.316063 2.5028425 2.2107788 0 P 0
L 2.5028425 2.2107788 2.5198425 2.2277788 0 P 0
L 2.5058425 2.4427789 2.5058425 2.6200157 0 P 0
L 2.5058425 2.4427789 2.5198425 2.4287789 0 P 0
L 2.5058425 2.6200157 2.6535433 2.7677165 0 P 0
L 2.5198425 2.2277788 2.5198425 2.4287789 0 P 0
L 2.5258424 2.61308 2.5258425 2.61308 0 P 0
L 2.5258425 2.463063 2.5258425 2.61308 0 P 0
L 2.5278425 3.2949922 2.5278425 3.434063 0 P 0
L 2.5278425 3.2949922 2.6673228 3.1555119 0 P 0
L 2.5278425 3.434063 2.5798425 3.486063 0 P 0
L 2.5281855 2.6187369 2.6649797 2.7555307 0 P 0
L 2.5354331 0.3543308 2.5774155 0.3963132 1 P 0
L 2.5431771 0.3465185 2.5852321 0.3885735 1 P 0
L 2.5498424 2.6095209 2.5498425 2.6095209 0 P 0
L 2.5498425 1.755063 2.5498425 2.6095209 0 P 0
L 2.5521855 2.6151778 2.6846648 2.7476567 0 P 0
L 2.5798423 3.6097971 2.5798425 3.6097572 0 P 0
L 2.5798425 1.790063 2.5798425 2.281063 0 P 0
L 2.5798425 3.486063 2.5798425 3.6097572 0 P 0
L 2.5984252 0.7951262 2.5984252 0.7952756 1 P 0
L 2.6048425 1.734063 2.6048425 2.4313767 0 P 0
L 2.6067048 0.4670239 2.6067048 0.7751375 1 P 0
L 2.6177048 0.4669693 2.6177048 0.7751376 1 P 0
L 2.6248425 1.7777198 2.6248425 2.461063 0 P 0
L 2.6248425 1.7777198 2.6253118 1.7772505 0 P 0
L 2.6253118 1.7715937 2.6253118 1.7772505 0 P 0
L 2.6253118 1.7715937 2.6268425 1.770063 0 P 0
L 2.6259843 0.7951259 2.6259843 0.7951261 1 P 0
L 2.6259843 0.7951261 2.6259843 0.7952756 1 P 0
L 2.6259843 0.7951261 2.6259844 0.795126 1 P 0
L 2.6348425 3.406063 2.6870079 3.3538976 0 P 0
L 2.6387795 2.5305119 2.6387795 2.6673228 0 P 0
L 2.6387795 2.5305119 2.6653543 2.5039371 0 P 0
L 2.6387795 2.6673228 2.6929134 2.7214567 0 P 0
L 2.6438425 1.616063 2.6438425 1.711063 0 P 0
L 2.6438425 1.711063 2.6488425 1.716063 0 P 0
L 2.6458425 2.274063 2.6458425 2.3791103 0 P 0
L 2.6458425 2.274063 2.6473732 2.2725323 0 P 0
L 2.6458425 2.3791103 2.6653543 2.3986221 0 P 0
L 2.6473732 2.2668755 2.6473732 2.2725323 0 P 0
L 2.6473732 2.2668755 2.6488425 2.2654062 0 P 0
L 2.6488425 1.716063 2.6488425 2.2654062 0 P 0
L 2.6535433 2.7677165 2.6535433 2.9810748 0 P 0
L 2.6653543 0.4055118 2.6715037 0.3993623 1 P 0
L 2.6653543 2.3986221 2.6653543 2.5039371 0 P 0
L 2.6658425 1.641063 2.6658425 2.291063 0 P 0
L 2.6658425 1.641063 2.6668425 1.640063 0 P 0
L 2.6673228 2.7611877 2.6673228 3.1555119 0 P 0
L 2.6715036 0.3993622 2.6715037 0.3993623 1 P 0
L 2.6811024 0.9762285 2.6811024 0.976378 1 P 0
L 2.6811024 0.9762285 2.6841537 0.9731772 1 P 0
L 2.6870079 2.7533137 2.6870079 3.3538976 0 P 0
L 2.6893818 0.9605552 2.6893819 0.9605552 1 P 0
L 2.6948425 1.481063 2.6948425 2.2843767 0 P 0
L 2.6948425 2.2843767 2.7028425 2.2923767 0 P 0
L 2.7028425 2.2923767 2.7028425 2.293063 0 P 0
L 2.7047243 0.4055116 2.7047244 0.4055118 1 P 0
L 2.707221 0.9747881 2.7086614 0.9762285 1 P 0
L 2.7086614 0.9762285 2.7086614 0.976378 1 P 0
L 2.7198425 1.591063 2.7198425 1.5927493 0 P 0
L 2.7198425 1.5927493 2.7268425 1.5997493 0 P 0
L 2.7268425 1.5997493 2.7268425 2.293063 0 P 0
L 2.7310449 0.5034503 2.734063 0.5034503 1 P 0
L 2.7310449 0.5184503 2.733063 0.5184503 1 P 0
L 2.7322151 0.4734503 2.734063 0.4734503 1 P 0
L 2.7322151 0.4884503 2.734063 0.4884503 1 P 0
L 2.7322835 0.7951261 2.7322835 0.7952756 1 P 0
L 2.733062 0.4434503 2.733063 0.4434503 1 P 0
L 2.733062 0.4584503 2.734063 0.4584503 1 P 0
L 2.7353582 0.4076537 2.7353742 0.4076749 1 P 0
L 2.736048 0.4086129 2.740563 0.423194 1 P 0
L 2.740563 0.423194 2.740563 0.4359503 1 P 0
L 2.740563 0.5259503 2.740563 0.5434508 1 P 0
L 2.740563 0.5434508 2.740563 0.7751376 1 P 0
L 2.7515629 0.4223505 2.751563 0.4223953 1 P 0
L 2.751563 0.4223953 2.751563 0.7751376 1 P 0
L 2.7598425 0.7951259 2.7598425 0.7951261 1 P 0
L 2.7598425 0.7951261 2.7598425 0.7952756 1 P 0
L 2.7992126 0.9762286 2.7992126 0.976378 1 P 0
L 2.7992126 0.9762286 2.8006531 0.9747881 1 P 0
L 2.8033665 0.4075566 2.8033685 0.4075234 1 P 0
L 2.8096947 0.3934559 2.8097215 0.3934295 1 P 0
L 2.8119314 0.430042 2.8119537 0.4300643 1 P 0
L 2.8119537 0.4300643 2.8709826 0.4890923 1 P 0
L 2.8143313 0.941766 2.8959076 0.8601897 1 P 0
L 2.8163193 0.4121203 2.8166357 0.4113091 1 P 0
L 2.8163193 0.4121203 2.8174418 0.4174731 1 P 0
L 2.8166357 0.4113091 2.8185055 0.4065166 1 P 0
L 2.8174418 0.4174731 2.8368923 0.4369235 1 P 0
L 2.8185055 0.4065166 2.8197456 0.4077567 1 P 0
L 2.8197456 0.4077567 2.8216839 0.4077567 1 P 0
L 2.8216839 0.4077567 2.8217791 0.4078519 1 P 0
L 2.8217791 0.4078519 2.8219832 0.4078519 1 P 0
L 2.8237204 0.9479332 2.9173228 0.8543308 1 P 0
L 2.8237204 0.9731772 2.8267717 0.9762285 1 P 0
L 2.8267717 0.9762285 2.8267717 0.976378 1 P 0
L 2.8421141 0.3966697 2.8421141 0.3975056 1 P 0
L 2.8474989 0.4369234 2.8515206 0.4329017 1 P 0
L 2.8480156 0.4034071 2.8492495 0.4034071 1 P 0
L 2.8561371 0.4494984 2.8621272 0.4435083 1 P 0
L 2.8667437 0.460105 2.8727339 0.4541148 1 P 0
L 2.8724528 0.4926337 2.8724528 0.7705345 1 P 0
L 2.8793188 0.4687431 2.8833405 0.4647214 1 P 0
L 2.8793188 0.4793498 2.8793191 0.4793501 1 P 0
L 2.8793191 0.4793501 2.8810868 0.4811178 1 P 0
L 2.8810868 0.4811178 2.8810869 0.4811179 1 P 0
L 2.8810868 0.4811178 2.8819663 0.4819972 1 P 0
L 2.8834528 0.5091763 2.8834528 0.7705347 1 P 0
L 2.8834529 0.4855546 2.8834529 0.5091763 1 P 0
L 2.8937008 0.7952756 2.8937009 0.7952755 1 P 0
L 2.8948425 1.561063 2.8948425 2.431063 0 P 0
L 2.9198425 1.536063 2.9208425 1.537063 0 P 0
L 2.9208425 1.537063 2.9208425 2.428063 0 P 0
L 2.9251969 0.4700228 2.9251969 0.789479 1 P 0
L 2.9361969 0.4983914 2.9361969 0.8087645 1 P 0
L 2.9361969 0.4983914 2.9370996 0.4958914 1 P 0
L 2.9370996 0.4958914 2.9380196 0.4933437 1 P 0
L 2.9380195 0.4933436 2.9380196 0.4933437 1 P 0
L 2.9428425 2.286063 2.9555625 2.286063 0 P 0
L 2.9450738 0.4883909 2.9551168 0.4883909 1 P 0
L 2.9452235 0.4583909 2.9667408 0.4583909 1 P 0
L 2.9452235 0.4733909 2.9551168 0.4733909 1 P 0
L 2.9534809 0.3998373 2.953481 0.3998374 1 P 0
L 2.9536062 0.3997117 2.9539854 0.399345 1 P 0
L 2.9555625 2.286063 2.9677025 2.298203 0 P 0
L 2.9596856 0.4333435 2.9596857 0.4333436 1 P 0
L 2.9596857 0.4333436 2.9629045 0.4244298 1 P 0
L 2.9629045 0.4244298 2.975631 0.4123601 1 P 0
L 2.9667398 0.4433909 2.9667408 0.4433909 1 P 0
L 2.9677025 2.298203 2.9677025 2.4479894 0 P 0
L 2.9677025 2.4479894 2.9798425 2.4601294 0 P 0
L 2.9798425 2.4601294 2.9798425 2.971631 0 P 0
L 2.9798425 2.971631 2.9933858 2.9851743 0 P 0
L 2.9804567 0.4091537 2.980457 0.4091539 1 P 0
L 2.9837232 0.3909445 2.9837232 0.3909446 1 P 0
L 2.9844564 0.3910208 2.9844564 0.3910209 1 P 0
L 2.9858425 2.287063 3.0133625 2.314583 0 P 0
L 2.9933858 2.9851743 2.9933858 3.751063 0 P 0
L 2.9988425 2.6183076 2.9988425 2.9722463 0 P 0
L 2.9988425 2.6183076 3.0133625 2.6037876 0 P 0
L 2.9988425 2.9722463 3.0218425 2.9952463 0 P 0
L 3.0133625 2.314583 3.0133625 2.6037876 0 P 0
L 3.0148425 3.8288982 3.0148425 3.831063 0 P 0
L 3.0148425 3.8288982 3.0218425 3.8218982 0 P 0
L 3.0218425 2.9952463 3.0218425 3.8218982 0 P 0
L 3.0568817 1.811803 3.0568817 2.2261731 0 P 0
L 3.0568817 2.2261731 3.0728346 2.242126 0 P 0
L 3.0649606 3.3996063 3.0688976 3.3956693 0 P 0
L 3.0688976 3.3956693 3.0728346 3.3917323 0 P 0
L 3.0728346 2.242126 3.0728346 3.3917323 0 P 0
L 3.1972633 1.714063 3.1972633 2.9694838 0 P 0
L 3.1972633 2.9694838 3.1978425 2.970063 0 P 0
L 3.2248425 1.6613472 3.2248425 3.229063 0 P 0
L 3.2248425 3.229063 3.2308425 3.235063 0 P 0
L 3.2528425 1.661063 3.2528425 3.293063 0 P 0
L 3.2528425 3.293063 3.2636972 3.3039177 0 P 0
L 3.2988425 1.971063 3.2988425 1.9732278 0 P 0
L 3.2988425 1.9732278 3.3028425 1.9772278 0 P 0
L 3.3028425 1.9772278 3.3028425 3.344063 0 P 0
L 3.3248425 1.941063 3.3291721 1.9367334 0 P 0
L 3.3248425 1.941063 3.3948425 2.011063 0 P 0
L 3.3291721 1.826063 3.3291721 1.9367334 0 P 0
L 3.3428425 2.263063 3.3448425 2.265063 0 P 0
L 3.3448425 2.265063 3.3448425 2.996063 0 P 0
L 3.3448425 2.996063 3.3448425 3.2867788 0 P 0
L 3.3448425 3.2867788 3.3588425 3.3007788 0 P 0
L 3.3588425 3.3007788 3.3588425 3.448063 0 P 0
L 3.3688425 3.050063 3.3688425 3.2648982 0 P 0
L 3.3688425 3.2648982 3.3748425 3.2708982 0 P 0
L 3.3748425 3.2708982 3.3748425 3.273063 0 P 0
L 3.3928425 1.871063 3.3928425 1.949063 0 P 0
L 3.3928425 1.949063 3.4398425 1.996063 0 P 0
L 3.3948425 2.011063 3.3948425 3.447063 0 P 0
L 3.4368425 1.999063 3.4368425 3.457063 0 P 0
L 3.4368425 1.999063 3.4398425 1.996063 0 P 0
L 3.4389125 1.875133 3.4392507 1.8747948 0 P 0
L 3.4389125 1.875133 3.4698425 1.906063 0 P 0
L 3.4392507 1.870938 3.4392507 1.8747948 0 P 0
L 3.4698425 1.906063 3.4698425 3.456063 0 P 0
L 3.4918425 3.297063 3.4928425 3.296063 0 P 0
L 3.4928425 2.357063 3.4928425 3.296063 0 P 0
L 3.4928425 2.357063 3.5018425 2.348063 0 P 0
L 3.4978425 2.344063 3.4998425 2.342063 0 P 0
L 3.4978425 2.344063 3.5018425 2.348063 0 P 0
L 3.4988425 2.341063 3.4998425 2.342063 0 P 0
L 3.5048425 4.086063 3.5198425 4.071063 0 P 0
L 3.5098425 3.3237788 3.5098425 3.7669208 0 P 0
L 3.5098425 3.3237788 3.523622 3.3099993 0 P 0
L 3.5098425 3.7669208 3.5198425 3.7769208 0 P 0
L 3.5198425 3.7769208 3.5198425 4.071063 0 P 0
L 3.523622 1.4672835 3.523622 3.3099993 0 P 0
L 3.523622 1.4672835 3.5498425 1.441063 0 P 0
L 3.542865 2.4157965 3.542865 3.3190405 0 P 0
L 3.542865 2.4157965 3.6048425 2.353819 0 P 0
L 3.5898425 1.711063 3.6138425 1.735063 0 P 0
L 3.6048425 2.0900041 3.6048425 2.353819 0 P 0
L 3.6048425 2.0900041 3.6138425 2.0810041 0 P 0
L 3.6138425 1.735063 3.6138425 2.0810041 0 P 0
L 3.6228425 2.588063 3.6228425 3.486063 0 P 0
L 3.6228425 2.588063 3.6238425 2.587063 0 P 0
L 3.6538425 3.293063 3.6958661 3.2510394 0 P 0
L 3.6958661 1.7000394 3.6958661 3.2510394 0 P 0
L 3.6958661 1.7000394 3.7208425 1.675063 0 P 0
L 3.7208425 1.675063 3.7248425 1.675063 0 P 0
L 3.7448425 1.711063 3.7448425 3.261063 0 P 0
L 3.7448425 1.711063 3.7748425 1.681063 0 P 0
L 3.7698425 1.726063 3.7698425 3.215063 0 P 0
L 3.7698425 1.726063 3.8038425 1.692063 0 P 0
L 3.7698425 3.215063 3.7898425 3.235063 0 P 0
L 3.7738632 1.6661021 3.7748425 1.6670814 0 P 0
L 3.7748425 1.6670814 3.7748425 1.681063 0 P 0
L 3.7898425 3.235063 3.8068425 3.235063 0 P 0
L 3.7998425 2.3563981 3.7998425 3.201063 0 P 0
L 3.7998425 2.3563981 3.8348425 2.3213981 0 P 0
L 3.8038425 1.691063 3.8038425 1.692063 0 P 0
L 3.8243425 2.3618981 3.8243425 2.8680238 0 P 0
L 3.8243425 2.3618981 3.8648425 2.3213981 0 P 0
L 3.8243425 2.8680238 3.8298425 2.8735238 0 P 0
L 3.8298425 2.8735238 3.8298425 3.176063 0 P 0
L 3.8348425 1.481063 3.8348425 2.3213981 0 P 0
L 3.8403425 2.3685255 3.8403425 2.8613964 0 P 0
L 3.8403425 2.3685255 3.8948425 2.3140255 0 P 0
L 3.8403425 2.8613964 3.8548425 2.8758964 0 P 0
L 3.8548425 2.8758964 3.8548425 3.151063 0 P 0
L 3.8648425 1.511063 3.8648425 2.3213981 0 P 0
L 3.8948425 1.566063 3.8948425 2.3140255 0 P 0
L 3.9208425 1.6851984 3.9208425 3.102063 0 P 0
L 3.9208425 1.6851984 3.9248425 1.6811984 0 P 0
L 3.9208425 3.102063 3.9398425 3.121063 0 P 0
L 3.9248425 1.536063 3.9248425 1.6811984 0 P 0
L 4.0398425 2.406063 4.0624044 2.4286249 0 P 0
L 4.0624044 2.4286249 4.0624044 2.595343 0 P 0
L 4.3277559 2.3074803 4.5348425 2.1003937 0 P 0
L 4.5348425 2.1003937 5.6348425 2.1003937 0 P 0
L 5.5778425 2.214063 5.5781524 2.2143729 0 P 0
L 5.5778425 2.214063 5.5800073 2.214063 0 P 0
L 5.5781524 0.8906186 5.6348425 0.9473087 0 P 0
L 5.5781524 2.2143729 5.5781524 2.4890438 0 P 0
L 5.5800073 2.214063 5.5844482 2.2185039 0 P 0
L 5.5844482 2.2185039 5.5866142 2.2185039 0 P 0
L 5.6348425 0.9473087 5.6348425 2.1003937 0 P 0
L 5.6348425 2.1003937 5.6348425 2.236063 0 P 0
P 1.4576771 4.253937 6 P 0 0 ;0=0,1=0
P 2.0433071 4.257874 6 P 0 0 ;0=0,1=0
P 4.0624044 2.595343 7 P 0 0 ;0=1,1=0
P 4.3277559 2.3074803 8 P 0 0 ;0=2,1=0
P 5.5781524 0.8906186 7 P 0 0 ;0=1,1=0
P 5.5781524 2.4890438 7 P 0 0 ;0=1,1=0
P 0.9901575 0.6870079 9 P 0 0 ;0=3,1=1
P 1.3454724 4.1751969 9 P 0 0 ;0=3,1=1
P 1.3937008 1.8169291 9 P 0 0 ;0=3,1=1
P 1.4408425 3.557063 9 P 0 0 ;0=3,1=1
P 1.4598425 3.147063 9 P 0 0 ;0=3,1=1
P 1.5498425 3.621063 9 P 0 0 ;0=3,1=1
P 1.5682025 2.067703 9 P 0 0 ;0=3,1=1
P 1.5748425 3.596063 9 P 0 0 ;0=3,1=1
P 1.6198425 2.121063 9 P 0 0 ;0=3,1=1
P 1.7198425 1.536063 9 P 0 0 ;0=3,1=1
P 1.7548425 2.126063 9 P 0 0 ;0=3,1=1
P 1.7548425 3.661063 9 P 0 0 ;0=3,1=1
P 1.7798425 4.156063 9 P 0 0 ;0=3,1=1
P 1.8326771 0.2874016 9 P 0 0 ;0=3,1=1
P 1.8498425 3.701063 9 P 0 0 ;0=3,1=1
P 1.8523622 0.2559055 9 P 0 0 ;0=3,1=1
P 1.8523622 0.2874016 9 P 0 0 ;0=3,1=1
P 1.8848425 2.071063 9 P 0 0 ;0=3,1=1
P 1.8848425 3.601063 9 P 0 0 ;0=3,1=1
P 2.0048425 1.336063 9 P 0 0 ;0=3,1=1
P 2.0048425 3.816063 9 P 0 0 ;0=3,1=1
P 2.0288425 1.361663 9 P 0 0 ;0=3,1=1
P 2.0298425 3.836063 9 P 0 0 ;0=3,1=1
P 2.0598425 1.386063 9 P 0 0 ;0=3,1=1
P 2.0598425 3.871063 9 P 0 0 ;0=3,1=1
P 2.0838425 1.411663 9 P 0 0 ;0=3,1=1
P 2.0848425 3.896063 9 P 0 0 ;0=3,1=1
P 2.1460663 4.1037909 9 P 0 0 ;0=3,1=1
P 2.2058425 3.200063 9 P 0 0 ;0=3,1=1
P 2.2068425 1.298063 9 P 0 0 ;0=3,1=1
P 2.2317425 2.584163 9 P 0 0 ;0=3,1=1
P 2.2348425 3.506063 9 P 0 0 ;0=3,1=1
P 2.2523425 2.613563 9 P 0 0 ;0=3,1=1
P 2.253937 4.0866142 9 P 0 0 ;0=3,1=1
P 2.2548425 3.536063 9 P 0 0 ;0=3,1=1
P 2.2598425 3.261063 9 P 0 0 ;0=3,1=1
P 2.2720325 2.463873 9 P 0 0 ;0=3,1=1
P 2.2748425 1.506063 9 P 0 0 ;0=3,1=1
P 2.2998425 1.916063 9 P 0 0 ;0=3,1=1
P 2.3503937 0.4055118 9 P 0 0 ;0=3,1=1
P 2.3848425 1.941063 9 P 0 0 ;0=3,1=1
P 2.3897638 0.4055118 9 P 0 0 ;0=3,1=1
P 2.3898425 3.481063 9 P 0 0 ;0=3,1=1
P 2.4098425 1.967063 9 P 0 0 ;0=3,1=1
P 2.4098425 2.283063 9 P 0 0 ;0=3,1=1
P 2.4291925 2.621063 9 P 0 0 ;0=3,1=1
P 2.4348425 3.546063 9 P 0 0 ;0=3,1=1
P 2.4468425 1.437063 9 P 0 0 ;0=3,1=1
P 2.4508425 2.282063 9 P 0 0 ;0=3,1=1
P 2.462374 3.1722441 9 P 0 0 ;0=3,1=1
P 2.4698827 0.4109883 9 P 0 0 ;0=3,1=1
P 2.4758425 2.291063 9 P 0 0 ;0=3,1=1
P 2.4788425 0.937063 9 P 0 0 ;0=3,1=1
P 2.4948425 2.661063 9 P 0 0 ;0=3,1=1
P 2.5028425 1.316063 9 P 0 0 ;0=3,1=1
P 2.511811 0.4055118 9 P 0 0 ;0=3,1=1
P 2.5258425 2.463063 9 P 0 0 ;0=3,1=1
P 2.5498425 1.755063 9 P 0 0 ;0=3,1=1
P 2.5798425 1.790063 9 P 0 0 ;0=3,1=1
P 2.5798425 2.281063 9 P 0 0 ;0=3,1=1
P 2.5798425 3.486063 9 P 0 0 ;0=3,1=1
P 2.5984252 0.7952756 9 P 0 0 ;0=3,1=1
P 2.5998425 2.436063 9 P 0 0 ;0=3,1=1
P 2.6048425 1.734063 9 P 0 0 ;0=3,1=1
P 2.6248425 2.461063 9 P 0 0 ;0=3,1=1
P 2.6259843 0.7952756 9 P 0 0 ;0=3,1=1
P 2.6268425 1.770063 9 P 0 0 ;0=3,1=1
P 2.6348425 3.406063 9 P 0 0 ;0=3,1=1
P 2.6438425 1.616063 9 P 0 0 ;0=3,1=1
P 2.6458425 2.274063 9 P 0 0 ;0=3,1=1
P 2.6653543 0.4055118 9 P 0 0 ;0=3,1=1
P 2.6658425 2.291063 9 P 0 0 ;0=3,1=1
P 2.6668425 1.640063 9 P 0 0 ;0=3,1=1
P 2.6811024 0.976378 9 P 0 0 ;0=3,1=1
P 2.6929134 2.7214567 9 P 0 0 ;0=3,1=1
P 2.6948425 1.481063 9 P 0 0 ;0=3,1=1
P 2.7028425 2.289063 9 P 0 0 ;0=3,1=1
P 2.7047244 0.4055118 9 P 0 0 ;0=3,1=1
P 2.7086614 0.976378 9 P 0 0 ;0=3,1=1
P 2.7198425 1.591063 9 P 0 0 ;0=3,1=1
P 2.7268425 2.293063 9 P 0 0 ;0=3,1=1
P 2.7322835 0.7952756 9 P 0 0 ;0=3,1=1
P 2.7598425 0.7952756 9 P 0 0 ;0=3,1=1
P 2.7992126 0.976378 9 P 0 0 ;0=3,1=1
P 2.8219832 0.4078519 9 P 0 0 ;0=3,1=1
P 2.8267717 0.976378 9 P 0 0 ;0=3,1=1
P 2.8543307 0.4055118 9 P 0 0 ;0=3,1=1
P 2.8622047 0.7952756 9 P 0 0 ;0=3,1=1
P 2.8937008 0.7952756 9 P 0 0 ;0=3,1=1
P 2.8948425 1.561063 9 P 0 0 ;0=3,1=1
P 2.8948425 2.431063 9 P 0 0 ;0=3,1=1
P 2.9198425 1.536063 9 P 0 0 ;0=3,1=1
P 2.9208425 2.428063 9 P 0 0 ;0=3,1=1
P 2.9428425 2.286063 9 P 0 0 ;0=3,1=1
P 2.980457 0.4091539 9 P 0 0 ;0=3,1=1
P 2.9858425 2.287063 9 P 0 0 ;0=3,1=1
P 2.9933858 3.751063 9 P 0 0 ;0=3,1=1
P 3.0148425 3.831063 9 P 0 0 ;0=3,1=1
P 3.019685 0.4055118 9 P 0 0 ;0=3,1=1
P 3.0568817 1.811803 9 P 0 0 ;0=3,1=1
P 3.0688976 3.3956693 9 P 0 0 ;0=3,1=1
P 3.1972633 1.714063 9 P 0 0 ;0=3,1=1
P 3.1978425 2.970063 9 P 0 0 ;0=3,1=1
P 3.2248425 1.6613472 9 P 0 0 ;0=3,1=1
P 3.2308425 3.235063 9 P 0 0 ;0=3,1=1
P 3.2528425 1.661063 9 P 0 0 ;0=3,1=1
P 3.2636972 3.3039177 9 P 0 0 ;0=3,1=1
P 3.2988425 1.971063 9 P 0 0 ;0=3,1=1
P 3.3028425 3.344063 9 P 0 0 ;0=3,1=1
P 3.3291721 1.826063 9 P 0 0 ;0=3,1=1
P 3.3428425 2.263063 9 P 0 0 ;0=3,1=1
P 3.3448425 2.996063 9 P 0 0 ;0=3,1=1
P 3.3588425 3.448063 9 P 0 0 ;0=3,1=1
P 3.3688425 3.050063 9 P 0 0 ;0=3,1=1
P 3.3748425 3.273063 9 P 0 0 ;0=3,1=1
P 3.3928425 1.871063 9 P 0 0 ;0=3,1=1
P 3.3948425 3.447063 9 P 0 0 ;0=3,1=1
P 3.4368425 3.457063 9 P 0 0 ;0=3,1=1
P 3.4392507 1.870938 9 P 0 0 ;0=3,1=1
P 3.4698425 3.456063 9 P 0 0 ;0=3,1=1
P 3.4918425 3.103063 9 P 0 0 ;0=3,1=1
P 3.4918425 3.297063 9 P 0 0 ;0=3,1=1
P 3.4988425 2.341063 9 P 0 0 ;0=3,1=1
P 3.5048425 4.086063 9 P 0 0 ;0=3,1=1
P 3.542865 3.3190405 9 P 0 0 ;0=3,1=1
P 3.5498425 1.441063 9 P 0 0 ;0=3,1=1
P 3.5898425 1.711063 9 P 0 0 ;0=3,1=1
P 3.6228425 3.486063 9 P 0 0 ;0=3,1=1
P 3.6238425 2.587063 9 P 0 0 ;0=3,1=1
P 3.6538425 3.293063 9 P 0 0 ;0=3,1=1
P 3.7248425 1.675063 9 P 0 0 ;0=3,1=1
P 3.7448425 3.261063 9 P 0 0 ;0=3,1=1
P 3.7738632 1.6661021 9 P 0 0 ;0=3,1=1
P 3.7998425 3.201063 9 P 0 0 ;0=3,1=1
P 3.8038425 1.691063 9 P 0 0 ;0=3,1=1
P 3.8068425 3.235063 9 P 0 0 ;0=3,1=1
P 3.8298425 3.176063 9 P 0 0 ;0=3,1=1
P 3.8348425 1.481063 9 P 0 0 ;0=3,1=1
P 3.8548425 3.151063 9 P 0 0 ;0=3,1=1
P 3.8648425 1.511063 9 P 0 0 ;0=3,1=1
P 3.8948425 1.566063 9 P 0 0 ;0=3,1=1
P 3.9248425 1.536063 9 P 0 0 ;0=3,1=1
P 3.9398425 3.121063 9 P 0 0 ;0=3,1=1
P 4.0398425 2.406063 9 P 0 0 ;0=3,1=1
P 5.5778425 2.214063 9 P 0 0 ;0=3,1=1
P 5.6348425 2.236063 9 P 0 0 ;0=3,1=1

### steps/pcb/layers/sgnd/features
#Layer_Physical_Order=2
#Layer_Color=36540
#
#Feature symbol names
#
$0 r3.937
$1 r1
$2 r250
$3 r75
$4 r61.0236
$5 oval177.1654x88.5827
$6 oval88.5827x177.1654
$7 r120
$8 r98.4252
$9 r200
$10 r16

#
#Feature attribute names
#
@0 .geometry
@1 .pad_usage

#
#Feature attribute text strings
#
&0 Pad_Simple_X250.0000Y250.0000H125.1969C165.1969
&1 Pad_Simple_X75.0000Y75.0000H50.0000C90.0000
&2 Pad_Simple_X61.0236Y61.0236H41.3386C81.3386
&3 Pad_Simple_X177.1654Y88.5827H39.3701C79.3701
&4 Pad_Simple_X88.5827Y177.1654H39.3701C79.3701
&5 Pad_Simple_X120.0000Y120.0000H68.0000C108.0000
&6 Pad_Simple_X98.4252Y98.4252H70.8661C110.8661
&7 VIA_RoundD200.0000H125.9843C165.9843
&8 VIA_RoundD16.0000H8.0000C48.0000

#
#Layer features
#
A 1.7712204 0.4310709 1.6275196 0.4310709 1.69937 0.4310709 0 P 0 N
L -0.0001175 0.177913 0.5908825 0.177913 1 P 0
L -0.0004331 0.1781182 0.5901181 0.1781182 0 P 0
L 0.5901181 0.1781182 0.5901181 0.5029213 0 P 0
L 0.5901181 0.5029213 1.312559 0.5029213 0 P 0
L 0.5908825 0.177913 0.5908825 0.502913 1 P 0
L 1.312559 0.313945 1.312559 0.5029213 0 P 0
L 1.312559 0.313945 1.6275197 0.313945 0 P 0
L 1.6275197 0.313945 1.6275197 0.4310709 0 P 0
P 0.0998425 0.806063 7 P 0 0 ;0=5,1=0
P 0.0998425 1.006063 7 P 0 0 ;0=5,1=0
P 0.0998425 1.331063 7 P 0 0 ;0=5,1=0
P 0.0998425 1.531063 7 P 0 0 ;0=5,1=0
P 0.0998425 1.856063 7 P 0 0 ;0=5,1=0
P 0.0998425 2.056063 7 P 0 0 ;0=5,1=0
P 0.0998425 2.381063 7 P 0 0 ;0=5,1=0
P 0.0998425 2.581063 7 P 0 0 ;0=5,1=0
P 0.285433 4.152063 2 P 0 0 ;0=0,1=0
P 0.2854331 0.3681102 2 P 0 0 ;0=0,1=0
P 0.2998425 0.806063 7 P 0 0 ;0=5,1=0
P 0.2998425 1.006063 7 P 0 0 ;0=5,1=0
P 0.2998425 1.331063 7 P 0 0 ;0=5,1=0
P 0.2998425 1.531063 7 P 0 0 ;0=5,1=0
P 0.2998425 1.856063 7 P 0 0 ;0=5,1=0
P 0.2998425 2.056063 7 P 0 0 ;0=5,1=0
P 0.2998425 2.381063 7 P 0 0 ;0=5,1=0
P 0.2998425 2.581063 7 P 0 0 ;0=5,1=0
P 3.9797272 2.4890438 3 P 0 0 ;0=1,1=0
P 5.1277559 2.3074803 4 P 0 0 ;0=2,1=0
P 5.5781524 1.6898312 3 P 0 0 ;0=1,1=0
P 5.9348031 3.9379527 6 P 0 0 ;0=4,1=0
P 6.1198425 4.056063 5 P 0 0 ;0=3,1=0
P 6.5694882 3.5895276 8 P 0 0 ;0=6,1=0
P 6.7348425 3.5895276 8 P 0 0 ;0=6,1=0
P 6.9001969 3.5895276 8 P 0 0 ;0=6,1=0
S P 0
OB 7.0787396 0.5090628 I
OS 3.1148425 0.509063
OS 3.1148425 0.2253937
OS 2.2948425 0.2253937
OS 2.2948425 0.314063
OS 2.2628425 0.346063
OS 2.2348425 0.346063
OS 2.2028425 0.314063
OS 2.2028425 0.2253937
OS 1.7818425 0.2253937
OS 1.7818425 0.3412095
OS 1.7844359 0.342556
OS 1.7868425 0.3431698
OS 1.7915996 0.3399913
OS 1.7978425 0.3387495
OS 1.8040854 0.3399913
OS 1.8093779 0.3435276
OS 1.8129142 0.3488201
OS 1.814156 0.355063
OS 1.8129142 0.3613059
OS 1.8093779 0.3665984
OS 1.8040854 0.3701347
OS 1.7978425 0.3713765
OS 1.7915996 0.3701347
OS 1.7868425 0.3669562
OS 1.7844359 0.36757
OS 1.7818425 0.3689165
OS 1.7818425 0.469063
OS 1.7358425 0.515063
OS 1.6638425 0.515063
OS 1.6188425 0.470063
OS 1.6188425 0.3129921
OS 1.3218425 0.3129921
OS 1.3218425 0.512063
OS 0.5818425 0.512063
OS 0.5818425 0.188063
OS 0.0078425 0.188063
OS 0.0078425 4.354063
OS 0.019921 4.3661415
OS 7.0787401 4.3661417
OS 7.0787396 0.5090628
OE
OB 2.5708425 4.2993765 H
OS 2.5645996 4.2981347
OS 2.5593071 4.2945984
OS 2.5557708 4.2893059
OS 2.554529 4.283063
OS 2.5557708 4.2768201
OS 2.5593071 4.2715276
OS 2.5645996 4.2679913
OS 2.5708425 4.2667495
OS 2.5770854 4.2679913
OS 2.5823779 4.2715276
OS 2.5859142 4.2768201
OS 2.587156 4.283063
OS 2.5859142 4.2893059
OS 2.5823779 4.2945984
OS 2.5770854 4.2981347
OS 2.5708425 4.2993765
OE
OB 1.2948425 4.2723765 H
OS 1.2885996 4.2711347
OS 1.2833071 4.2675984
OS 1.2797708 4.2623059
OS 1.278529 4.256063
OS 1.2797708 4.2498201
OS 1.2833071 4.2445276
OS 1.2885996 4.2409913
OS 1.2948425 4.2397495
OS 1.3010854 4.2409913
OS 1.3063779 4.2445276
OS 1.3099142 4.2498201
OS 1.311156 4.256063
OS 1.3099142 4.2623059
OS 1.3063779 4.2675984
OS 1.3010854 4.2711347
OS 1.2948425 4.2723765
OE
OB 2.0788071 4.293374 H
OS 2.0078071 4.293374
OS 2.0078071 4.222374
OS 2.0788071 4.222374
OS 2.0788071 4.293374
OE
OB 1.4931771 4.289437 H
OS 1.4221771 4.289437
OS 1.4221771 4.218437
OS 1.4931771 4.218437
OS 1.4931771 4.289437
OE
OB 1.5578425 4.2453765 H
OS 1.5515996 4.2441347
OS 1.5463071 4.2405984
OS 1.5427708 4.2353059
OS 1.541529 4.229063
OS 1.5427708 4.2228201
OS 1.5463071 4.2175276
OS 1.5515996 4.2139913
OS 1.5578425 4.2127495
OS 1.5640854 4.2139913
OS 1.5693779 4.2175276
OS 1.5729142 4.2228201
OS 1.574156 4.229063
OS 1.5729142 4.2353059
OS 1.5693779 4.2405984
OS 1.5640854 4.2441347
OS 1.5578425 4.2453765
OE
OB 1.3454724 4.1915104 H
OS 1.3392295 4.1902686
OS 1.333937 4.1867323
OS 1.3304007 4.1814398
OS 1.3291589 4.1751969
OS 1.3304007 4.168954
OS 1.333937 4.1636615
OS 1.3392295 4.1601252
OS 1.3454724 4.1588834
OS 1.3517153 4.1601252
OS 1.3570078 4.1636615
OS 1.3605441 4.168954
OS 1.3617859 4.1751969
OS 1.3605441 4.1814398
OS 1.3570078 4.1867323
OS 1.3517153 4.1902686
OS 1.3454724 4.1915104
OE
OB 1.5698819 4.1875734 H
OS 1.563639 4.1863316
OS 1.5583465 4.1827953
OS 1.5548102 4.1775028
OS 1.5535684 4.1712599
OS 1.5548102 4.165017
OS 1.5583465 4.1597245
OS 1.563639 4.1561882
OS 1.5698819 4.1549464
OS 1.5761248 4.1561882
OS 1.5814173 4.1597245
OS 1.5849536 4.165017
OS 1.5861954 4.1712599
OS 1.5849536 4.1775028
OS 1.5814173 4.1827953
OS 1.5761248 4.1863316
OS 1.5698819 4.1875734
OE
OB 1.7798425 4.1723765 H
OS 1.7735996 4.1711347
OS 1.7683071 4.1675984
OS 1.7647708 4.1623059
OS 1.763529 4.156063
OS 1.7647708 4.1498201
OS 1.7683071 4.1445276
OS 1.7735996 4.1409913
OS 1.7798425 4.1397495
OS 1.7860854 4.1409913
OS 1.7913779 4.1445276
OS 1.7949142 4.1498201
OS 1.796156 4.156063
OS 1.7949142 4.1623059
OS 1.7913779 4.1675984
OS 1.7860854 4.1711347
OS 1.7798425 4.1723765
OE
OB 2.0433071 4.1936803 H
OS 2.0340397 4.1924602
OS 2.0254039 4.1888832
OS 2.0179882 4.1831929
OS 2.0122979 4.1757772
OS 2.0087209 4.1671414
OS 2.0075008 4.157874
OS 2.0087209 4.1486066
OS 2.0122979 4.1399708
OS 2.0179882 4.1325551
OS 2.0254039 4.1268648
OS 2.0340397 4.1232878
OS 2.0433071 4.1220677
OS 2.0525745 4.1232878
OS 2.0612103 4.1268648
OS 2.068626 4.1325551
OS 2.0743163 4.1399708
OS 2.0778933 4.1486066
OS 2.0791134 4.157874
OS 2.0778933 4.1671414
OS 2.0743163 4.1757772
OS 2.068626 4.1831929
OS 2.0612103 4.1888832
OS 2.0525745 4.1924602
OS 2.0433071 4.1936803
OE
OB 1.4576771 4.1897433 H
OS 1.4484097 4.1885232
OS 1.4397739 4.1849462
OS 1.4323582 4.1792559
OS 1.4266679 4.1718402
OS 1.4230909 4.1632044
OS 1.4218708 4.153937
OS 1.4230909 4.1446696
OS 1.4266679 4.1360338
OS 1.4323582 4.1286181
OS 1.4397739 4.1229278
OS 1.4484097 4.1193508
OS 1.4576771 4.1181307
OS 1.4669445 4.1193508
OS 1.4755803 4.1229278
OS 1.482996 4.1286181
OS 1.4886863 4.1360338
OS 1.4922633 4.1446696
OS 1.4934834 4.153937
OS 1.4922633 4.1632044
OS 1.4886863 4.1718402
OS 1.482996 4.1792559
OS 1.4755803 4.1849462
OS 1.4669445 4.1885232
OS 1.4576771 4.1897433
OE
OB 3.9580709 4.1520014 H
OS 3.9513575 4.1511176
OS 3.9451017 4.1485263
OS 3.9397297 4.1444042
OS 3.9356076 4.1390322
OS 3.9330163 4.1327764
OS 3.9321325 4.126063
OS 3.9330163 4.1193496
OS 3.9356076 4.1130938
OS 3.9397297 4.1077218
OS 3.9451017 4.1035997
OS 3.9513575 4.1010084
OS 3.9580709 4.1001246
OS 3.9647843 4.1010084
OS 3.9710401 4.1035997
OS 3.9764121 4.1077218
OS 3.9805342 4.1130938
OS 3.9831255 4.1193496
OS 3.9840093 4.126063
OS 3.9831255 4.1327764
OS 3.9805342 4.1390322
OS 3.9764121 4.1444042
OS 3.9710401 4.1485263
OS 3.9647843 4.1511176
OS 3.9580709 4.1520014
OE
OB 3.7848425 4.1520014 H
OS 3.7781291 4.1511176
OS 3.7718733 4.1485263
OS 3.7665013 4.1444042
OS 3.7623792 4.1390322
OS 3.7597879 4.1327764
OS 3.7589041 4.126063
OS 3.7597879 4.1193496
OS 3.7623792 4.1130938
OS 3.7665013 4.1077218
OS 3.7718733 4.1035997
OS 3.7781291 4.1010084
OS 3.7848425 4.1001246
OS 3.7915559 4.1010084
OS 3.7978117 4.1035997
OS 3.8031837 4.1077218
OS 3.8073058 4.1130938
OS 3.8098971 4.1193496
OS 3.8107809 4.126063
OS 3.8098971 4.1327764
OS 3.8073058 4.1390322
OS 3.8031837 4.1444042
OS 3.7978117 4.1485263
OS 3.7915559 4.1511176
OS 3.7848425 4.1520014
OE
OB 4.7547119 4.1322459 H
OS 4.748469 4.1310041
OS 4.7431765 4.1274678
OS 4.7396402 4.1221753
OS 4.7383984 4.1159324
OS 4.7396402 4.1096895
OS 4.7431765 4.104397
OS 4.748469 4.1008607
OS 4.7547119 4.0996189
OS 4.7609548 4.1008607
OS 4.7662473 4.104397
OS 4.7697836 4.1096895
OS 4.7710254 4.1159324
OS 4.7697836 4.1221753
OS 4.7662473 4.1274678
OS 4.7609548 4.1310041
OS 4.7547119 4.1322459
OE
OB 2.1460663 4.1201044 H
OS 2.1398234 4.1188626
OS 2.1345309 4.1153263
OS 2.1309946 4.1100338
OS 2.1297528 4.1037909
OS 2.1309946 4.097548
OS 2.1345309 4.0922555
OS 2.1398234 4.0887192
OS 2.1460663 4.0874774
OS 2.1523092 4.0887192
OS 2.1576017 4.0922555
OS 2.161138 4.097548
OS 2.1623798 4.1037909
OS 2.161138 4.1100338
OS 2.1576017 4.1153263
OS 2.1523092 4.1188626
OS 2.1460663 4.1201044
OE
OB 0.285433 4.223003 H
OS 0.2715933 4.2216399
OS 0.2582854 4.217603
OS 0.2460208 4.2110475
OS 0.2352708 4.2022252
OS 0.2264485 4.1914752
OS 0.219893 4.1792106
OS 0.2158561 4.1659027
OS 0.214493 4.152063
OS 0.2158561 4.1382233
OS 0.219893 4.1249154
OS 0.2264485 4.1126508
OS 0.2352708 4.1019008
OS 0.2460208 4.0930785
OS 0.2582854 4.086523
OS 0.2715933 4.0824861
OS 0.285433 4.081123
OS 0.2992727 4.0824861
OS 0.3125806 4.086523
OS 0.3248452 4.0930785
OS 0.3355952 4.1019008
OS 0.3444175 4.1126508
OS 0.350973 4.1249154
OS 0.3550099 4.1382233
OS 0.356373 4.152063
OS 0.3550099 4.1659027
OS 0.350973 4.1792106
OS 0.3444175 4.1914752
OS 0.3355952 4.2022252
OS 0.3248452 4.2110475
OS 0.3125806 4.217603
OS 0.2992727 4.2216399
OS 0.285433 4.223003
OE
OB 5.2670079 4.1052111 H
OS 5.260765 4.1039693
OS 5.2554725 4.100433
OS 5.2519362 4.0951405
OS 5.2506944 4.0888976
OS 5.2519362 4.0826547
OS 5.2554725 4.0773622
OS 5.260765 4.0738259
OS 5.2670079 4.0725841
OS 5.2732508 4.0738259
OS 5.2785433 4.0773622
OS 5.2820796 4.0826547
OS 5.2833214 4.0888976
OS 5.2820796 4.0951405
OS 5.2785433 4.100433
OS 5.2732508 4.1039693
OS 5.2670079 4.1052111
OE
OB 2.253937 4.1029277 H
OS 2.2476941 4.1016859
OS 2.2424016 4.0981496
OS 2.2388653 4.0928571
OS 2.2376235 4.0866142
OS 2.2388653 4.0803713
OS 2.2424016 4.0750788
OS 2.2476941 4.0715425
OS 2.253937 4.0703007
OS 2.2601799 4.0715425
OS 2.2654724 4.0750788
OS 2.2690087 4.0803713
OS 2.2702505 4.0866142
OS 2.2690087 4.0928571
OS 2.2654724 4.0981496
OS 2.2601799 4.1016859
OS 2.253937 4.1029277
OE
OB 3.5048425 4.1023765 H
OS 3.4985996 4.1011347
OS 3.4933071 4.0975984
OS 3.4897708 4.0923059
OS 3.488529 4.086063
OS 3.4897708 4.0798201
OS 3.4933071 4.0745276
OS 3.4985996 4.0709913
OS 3.5048425 4.0697495
OS 3.5110854 4.0709913
OS 3.5163779 4.0745276
OS 3.5199142 4.0798201
OS 3.521156 4.086063
OS 3.5199142 4.0923059
OS 3.5163779 4.0975984
OS 3.5110854 4.1011347
OS 3.5048425 4.1023765
OE
OB 3.2948425 4.1274482 H
OS 3.2841414 4.1260394
OS 3.2741696 4.1219089
OS 3.2656066 4.1153383
OS 3.259036 4.1067753
OS 3.2549055 4.0968035
OS 3.2534967 4.0861024
OS 3.2549055 4.0754013
OS 3.259036 4.0654295
OS 3.2656066 4.0568665
OS 3.2741696 4.0502959
OS 3.2841414 4.0461654
OS 3.2948425 4.0447566
OS 3.3055436 4.0461654
OS 3.3155154 4.0502959
OS 3.3240784 4.0568665
OS 3.330649 4.0654295
OS 3.3347795 4.0754013
OS 3.3361883 4.0861024
OS 3.3347795 4.0968035
OS 3.330649 4.1067753
OS 3.3240784 4.1153383
OS 3.3155154 4.1219089
OS 3.3055436 4.1260394
OS 3.2948425 4.1274482
OE
OB 2.9948425 4.1274482 H
OS 2.9841414 4.1260394
OS 2.9741696 4.1219089
OS 2.9656066 4.1153383
OS 2.959036 4.1067753
OS 2.9549055 4.0968035
OS 2.9534967 4.0861024
OS 2.9549055 4.0754013
OS 2.959036 4.0654295
OS 2.9656066 4.0568665
OS 2.9741696 4.0502959
OS 2.9841414 4.0461654
OS 2.9948425 4.0447566
OS 3.0055436 4.0461654
OS 3.0155154 4.0502959
OS 3.0240784 4.0568665
OS 3.030649 4.0654295
OS 3.0347795 4.0754013
OS 3.0361883 4.0861024
OS 3.0347795 4.0968035
OS 3.030649 4.1067753
OS 3.0240784 4.1153383
OS 3.0155154 4.1219089
OS 3.0055436 4.1260394
OS 2.9948425 4.1274482
OE
OB 6.9001969 4.1608442 H
OS 6.8870518 4.1595495
OS 6.8744118 4.1557152
OS 6.8627628 4.1494887
OS 6.8525523 4.1411092
OS 6.8441728 4.1308987
OS 6.8379463 4.1192497
OS 6.834112 4.1066097
OS 6.8328173 4.0934646
OS 6.834112 4.0803195
OS 6.8379463 4.0676795
OS 6.8441728 4.0560305
OS 6.8525523 4.04582
OS 6.8627628 4.0374405
OS 6.8744118 4.031214
OS 6.8870518 4.0273797
OS 6.9001969 4.026085
OS 6.913342 4.0273797
OS 6.925982 4.031214
OS 6.937631 4.0374405
OS 6.9478415 4.04582
OS 6.956221 4.0560305
OS 6.9624475 4.0676795
OS 6.9662818 4.0803195
OS 6.9675765 4.0934646
OS 6.9662818 4.1066097
OS 6.9624475 4.1192497
OS 6.956221 4.1308987
OS 6.9478415 4.1411092
OS 6.937631 4.1494887
OS 6.925982 4.1557152
OS 6.913342 4.1595495
OS 6.9001969 4.1608442
OE
OB 6.5694882 4.1608442 H
OS 6.5563431 4.1595495
OS 6.5437031 4.1557152
OS 6.5320541 4.1494887
OS 6.5218436 4.1411092
OS 6.5134641 4.1308987
OS 6.5072376 4.1192497
OS 6.5034033 4.1066097
OS 6.5021086 4.0934646
OS 6.5034033 4.0803195
OS 6.5072376 4.0676795
OS 6.5134641 4.0560305
OS 6.5218436 4.04582
OS 6.5320541 4.0374405
OS 6.5437031 4.031214
OS 6.5563431 4.0273797
OS 6.5694882 4.026085
OS 6.5826333 4.0273797
OS 6.5952733 4.031214
OS 6.6069223 4.0374405
OS 6.6171328 4.04582
OS 6.6255123 4.0560305
OS 6.6317388 4.0676795
OS 6.6355731 4.0803195
OS 6.6368678 4.0934646
OS 6.6355731 4.1066097
OS 6.6317388 4.1192497
OS 6.6255123 4.1308987
OS 6.6171328 4.1411092
OS 6.6069223 4.1494887
OS 6.5952733 4.1557152
OS 6.5826333 4.1595495
OS 6.5694882 4.1608442
OE
OB 2.0433071 4.0936803 H
OS 2.0340397 4.0924602
OS 2.0254039 4.0888832
OS 2.0179882 4.0831929
OS 2.0122979 4.0757772
OS 2.0087209 4.0671414
OS 2.0075008 4.057874
OS 2.0087209 4.0486066
OS 2.0122979 4.0399708
OS 2.0179882 4.0325551
OS 2.0254039 4.0268648
OS 2.0340397 4.0232878
OS 2.0433071 4.0220677
OS 2.0525745 4.0232878
OS 2.0612103 4.0268648
OS 2.068626 4.0325551
OS 2.0743163 4.0399708
OS 2.0778933 4.0486066
OS 2.0791134 4.057874
OS 2.0778933 4.0671414
OS 2.0743163 4.0757772
OS 2.068626 4.0831929
OS 2.0612103 4.0888832
OS 2.0525745 4.0924602
OS 2.0433071 4.0936803
OE
OB 1.4576771 4.0897433 H
OS 1.4484097 4.0885232
OS 1.4397739 4.0849462
OS 1.4323582 4.0792559
OS 1.4266679 4.0718402
OS 1.4230909 4.0632044
OS 1.4218708 4.053937
OS 1.4230909 4.0446696
OS 1.4266679 4.0360338
OS 1.4323582 4.0286181
OS 1.4397739 4.0229278
OS 1.4484097 4.0193508
OS 1.4576771 4.0181307
OS 1.4669445 4.0193508
OS 1.4755803 4.0229278
OS 1.482996 4.0286181
OS 1.4886863 4.0360338
OS 1.4922633 4.0446696
OS 1.4934834 4.053937
OS 1.4922633 4.0632044
OS 1.4886863 4.0718402
OS 1.482996 4.0792559
OS 1.4755803 4.0849462
OS 1.4669445 4.0885232
OS 1.4576771 4.0897433
OE
OB 1.9038425 4.0343765 H
OS 1.8975996 4.0331347
OS 1.8923071 4.0295984
OS 1.8887708 4.0243059
OS 1.887529 4.018063
OS 1.8887708 4.0118201
OS 1.8923071 4.0065276
OS 1.8975996 4.0029913
OS 1.9038425 4.0017495
OS 1.9100854 4.0029913
OS 1.9153779 4.0065276
OS 1.9189142 4.0118201
OS 1.920156 4.018063
OS 1.9189142 4.0243059
OS 1.9153779 4.0295984
OS 1.9100854 4.0331347
OS 1.9038425 4.0343765
OE
OB 2.3533464 4.03403 H
OS 2.3471035 4.0327882
OS 2.341811 4.0292519
OS 2.3382747 4.0239594
OS 2.3370329 4.0177165
OS 2.3382747 4.0114736
OS 2.341811 4.0061811
OS 2.3471035 4.0026448
OS 2.3533464 4.001403
OS 2.3595893 4.0026448
OS 2.3648818 4.0061811
OS 2.3684181 4.0114736
OS 2.3696599 4.0177165
OS 2.3684181 4.0239594
OS 2.3648818 4.0292519
OS 2.3595893 4.0327882
OS 2.3533464 4.03403
OE
OB 5.7234252 4.0832969 H
OS 5.7084897 4.0813306
OS 5.6945721 4.0755657
OS 5.6826207 4.0663951
OS 5.6734501 4.0544438
OS 5.6676852 4.0405261
OS 5.6657189 4.0255906
OS 5.6676852 4.0106551
OS 5.6734501 3.9967374
OS 5.6826207 3.9847861
OS 5.6945721 3.9756155
OS 5.7084897 3.9698506
OS 5.7234252 3.9678843
OS 5.7383607 3.9698506
OS 5.7522783 3.9756155
OS 5.7642297 3.9847861
OS 5.7734003 3.9967374
OS 5.7791652 4.0106551
OS 5.7811315 4.0255906
OS 5.7791652 4.0405261
OS 5.7734003 4.0544438
OS 5.7642297 4.0663951
OS 5.7522783 4.0755657
OS 5.7383607 4.0813306
OS 5.7234252 4.0832969
OE
OB 1.4084645 3.9966285 H
OS 1.4022216 3.9953867
OS 1.3969291 3.9918504
OS 1.3933928 3.9865579
OS 1.392151 3.980315
OS 1.3933928 3.9740721
OS 1.3969291 3.9687796
OS 1.4022216 3.9652433
OS 1.4084645 3.9640015
OS 1.4147074 3.9652433
OS 1.4199999 3.9687796
OS 1.4235362 3.9740721
OS 1.424778 3.980315
OS 1.4235362 3.9865579
OS 1.4199999 3.9918504
OS 1.4147074 3.9953867
OS 1.4084645 3.9966285
OE
OB 2.0848425 3.9123765 H
OS 2.0785996 3.9111347
OS 2.0733071 3.9075984
OS 2.0697708 3.9023059
OS 2.068529 3.896063
OS 2.0697708 3.8898201
OS 2.0699331 3.8895773
OS 2.0663282 3.8859724
OS 2.0660854 3.8861347
OS 2.0598425 3.8873765
OS 2.0535996 3.8861347
OS 2.0483071 3.8825984
OS 2.0447708 3.8773059
OS 2.043529 3.871063
OS 2.0447708 3.8648201
OS 2.0483071 3.8595276
OS 2.0535996 3.8559913
OS 2.0598425 3.8547495
OS 2.0660854 3.8559913
OS 2.0713779 3.8595276
OS 2.0749142 3.8648201
OS 2.076156 3.871063
OS 2.0749142 3.8773059
OS 2.0747519 3.8775487
OS 2.0783568 3.8811536
OS 2.0785996 3.8809913
OS 2.0848425 3.8797495
OS 2.0910854 3.8809913
OS 2.0963779 3.8845276
OS 2.0999142 3.8898201
OS 2.101156 3.896063
OS 2.0999142 3.9023059
OS 2.0963779 3.9075984
OS 2.0910854 3.9111347
OS 2.0848425 3.9123765
OE
OB 2.0298425 3.8523765 H
OS 2.0235996 3.8511347
OS 2.0183071 3.8475984
OS 2.0147708 3.8423059
OS 2.013529 3.836063
OS 2.0136749 3.8353296
OS 2.0130932 3.8343873
OS 2.0093423 3.8314814
OS 2.0048425 3.8323765
OS 1.9985996 3.8311347
OS 1.9933071 3.8275984
OS 1.9897708 3.8223059
OS 1.988529 3.816063
OS 1.9897708 3.8098201
OS 1.9933071 3.8045276
OS 1.9985996 3.8009913
OS 2.0048425 3.7997495
OS 2.0110854 3.8009913
OS 2.0163779 3.8045276
OS 2.0199142 3.8098201
OS 2.021156 3.816063
OS 2.0210101 3.8167964
OS 2.0215918 3.8177387
OS 2.0253427 3.8206446
OS 2.0298425 3.8197495
OS 2.0360854 3.8209913
OS 2.0413779 3.8245276
OS 2.0449142 3.8298201
OS 2.046156 3.836063
OS 2.0449142 3.8423059
OS 2.0413779 3.8475984
OS 2.0360854 3.8511347
OS 2.0298425 3.8523765
OE
OB 3.6998425 3.8523765 H
OS 3.6935996 3.8511347
OS 3.6883071 3.8475984
OS 3.6847708 3.8423059
OS 3.683529 3.836063
OS 3.6847708 3.8298201
OS 3.6883071 3.8245276
OS 3.6935996 3.8209913
OS 3.6998425 3.8197495
OS 3.7060854 3.8209913
OS 3.7113779 3.8245276
OS 3.7149142 3.8298201
OS 3.716156 3.836063
OS 3.7149142 3.8423059
OS 3.7113779 3.8475984
OS 3.7060854 3.8511347
OS 3.6998425 3.8523765
OE
OB 3.0148425 3.8473765 H
OS 3.0085996 3.8461347
OS 3.0033071 3.8425984
OS 2.9997708 3.8373059
OS 2.998529 3.831063
OS 2.9997708 3.8248201
OS 3.0033071 3.8195276
OS 3.0085996 3.8159913
OS 3.0148425 3.8147495
OS 3.0210854 3.8159913
OS 3.0263779 3.8195276
OS 3.0299142 3.8248201
OS 3.031156 3.831063
OS 3.0299142 3.8373059
OS 3.0263779 3.8425984
OS 3.0210854 3.8461347
OS 3.0148425 3.8473765
OE
OB 3.8298425 3.8223765 H
OS 3.8235996 3.8211347
OS 3.8183071 3.8175984
OS 3.8147708 3.8123059
OS 3.813529 3.806063
OS 3.8147708 3.7998201
OS 3.8183071 3.7945276
OS 3.8235996 3.7909913
OS 3.8298425 3.7897495
OS 3.8360854 3.7909913
OS 3.8413779 3.7945276
OS 3.8449142 3.7998201
OS 3.846156 3.806063
OS 3.8449142 3.8123059
OS 3.8413779 3.8175984
OS 3.8360854 3.8211347
OS 3.8298425 3.8223765
OE
OB 3.5398425 3.8223765 H
OS 3.5335996 3.8211347
OS 3.5283071 3.8175984
OS 3.5247708 3.8123059
OS 3.523529 3.806063
OS 3.5247708 3.7998201
OS 3.5283071 3.7945276
OS 3.5335996 3.7909913
OS 3.5398425 3.7897495
OS 3.5460854 3.7909913
OS 3.5513779 3.7945276
OS 3.5549142 3.7998201
OS 3.556156 3.806063
OS 3.5549142 3.8123059
OS 3.5513779 3.8175984
OS 3.5460854 3.8211347
OS 3.5398425 3.8223765
OE
OB 3.2198425 3.8223765 H
OS 3.2135996 3.8211347
OS 3.2083071 3.8175984
OS 3.2047708 3.8123059
OS 3.203529 3.806063
OS 3.2047708 3.7998201
OS 3.2083071 3.7945276
OS 3.2135996 3.7909913
OS 3.2198425 3.7897495
OS 3.2260854 3.7909913
OS 3.2313779 3.7945276
OS 3.2349142 3.7998201
OS 3.236156 3.806063
OS 3.2349142 3.8123059
OS 3.2313779 3.8175984
OS 3.2260854 3.8211347
OS 3.2198425 3.8223765
OE
OB 5.7234252 3.9021945 H
OS 5.7084897 3.9002282
OS 5.6945721 3.8944633
OS 5.6826207 3.8852927
OS 5.6734501 3.8733414
OS 5.6676852 3.8594237
OS 5.6657189 3.8444882
OS 5.6676852 3.8295527
OS 5.6734501 3.815635
OS 5.6826207 3.8036837
OS 5.6945721 3.7945131
OS 5.7084897 3.7887482
OS 5.7234252 3.7867819
OS 5.7383607 3.7887482
OS 5.7522783 3.7945131
OS 5.7642297 3.8036837
OS 5.7734003 3.815635
OS 5.7791652 3.8295527
OS 5.7811315 3.8444882
OS 5.7791652 3.8594237
OS 5.7734003 3.8733414
OS 5.7642297 3.8852927
OS 5.7522783 3.8944633
OS 5.7383607 3.9002282
OS 5.7234252 3.9021945
OE
OB 2.7224094 3.8023844 H
OS 2.7161665 3.8011426
OS 2.710874 3.7976063
OS 2.7073377 3.7923138
OS 2.7060959 3.7860709
OS 2.7073377 3.779828
OS 2.710874 3.7745355
OS 2.7161665 3.7709992
OS 2.7224094 3.7697574
OS 2.7286523 3.7709992
OS 2.7339448 3.7745355
OS 2.7374811 3.779828
OS 2.7387229 3.7860709
OS 2.7374811 3.7923138
OS 2.7339448 3.7976063
OS 2.7286523 3.8011426
OS 2.7224094 3.8023844
OE
OB 6.1690551 3.8775488 H
OS 6.0706299 3.8775488
OS 6.0556944 3.8755825
OS 6.0417767 3.8698176
OS 6.0298254 3.860647
OS 6.0206548 3.8486956
OS 6.0148899 3.834778
OS 6.0129236 3.8198425
OS 6.0148899 3.804907
OS 6.0206548 3.7909894
OS 6.0298254 3.779038
OS 6.0417767 3.7698674
OS 6.0556944 3.7641025
OS 6.0706299 3.7621362
OS 6.1690551 3.7621362
OS 6.1839906 3.7641025
OS 6.1979083 3.7698674
OS 6.2098596 3.779038
OS 6.2190302 3.7909894
OS 6.2247951 3.804907
OS 6.2267614 3.8198425
OS 6.2247951 3.834778
OS 6.2190302 3.8486956
OS 6.2098596 3.860647
OS 6.1979083 3.8698176
OS 6.1839906 3.8755825
OS 6.1690551 3.8775488
OE
OB 4.2548425 3.7923765 H
OS 4.2485996 3.7911347
OS 4.2433071 3.7875984
OS 4.2397708 3.7823059
OS 4.238529 3.776063
OS 4.2397708 3.7698201
OS 4.2433071 3.7645276
OS 4.2485996 3.7609913
OS 4.2548425 3.7597495
OS 4.2610854 3.7609913
OS 4.2663779 3.7645276
OS 4.2699142 3.7698201
OS 4.271156 3.776063
OS 4.2699142 3.7823059
OS 4.2663779 3.7875984
OS 4.2610854 3.7911347
OS 4.2548425 3.7923765
OE
OB 6.9001969 3.8637693 H
OS 6.8852614 3.861803
OS 6.8713437 3.8560381
OS 6.8593924 3.8468675
OS 6.8502218 3.8349162
OS 6.8444569 3.8209985
OS 6.8424906 3.806063
OS 6.8444569 3.7911275
OS 6.8502218 3.7772098
OS 6.8593924 3.7652585
OS 6.8713437 3.7560879
OS 6.8852614 3.750323
OS 6.9001969 3.7483567
OS 6.9151324 3.750323
OS 6.9290501 3.7560879
OS 6.9410014 3.7652585
OS 6.950172 3.7772098
OS 6.9559369 3.7911275
OS 6.9579032 3.806063
OS 6.9559369 3.8209985
OS 6.950172 3.8349162
OS 6.9410014 3.8468675
OS 6.9290501 3.8560381
OS 6.9151324 3.861803
OS 6.9001969 3.8637693
OE
OB 6.7348425 3.8637693 H
OS 6.719907 3.861803
OS 6.7059893 3.8560381
OS 6.694038 3.8468675
OS 6.6848674 3.8349162
OS 6.6791025 3.8209985
OS 6.6771362 3.806063
OS 6.6791025 3.7911275
OS 6.6848674 3.7772098
OS 6.694038 3.7652585
OS 6.7059893 3.7560879
OS 6.719907 3.750323
OS 6.7348425 3.7483567
OS 6.749778 3.750323
OS 6.7636957 3.7560879
OS 6.775647 3.7652585
OS 6.7848176 3.7772098
OS 6.7905825 3.7911275
OS 6.7925488 3.806063
OS 6.7905825 3.8209985
OS 6.7848176 3.8349162
OS 6.775647 3.8468675
OS 6.7636957 3.8560381
OS 6.749778 3.861803
OS 6.7348425 3.8637693
OE
OB 6.5694882 3.8637693 H
OS 6.5545527 3.861803
OS 6.540635 3.8560381
OS 6.5286837 3.8468675
OS 6.5195131 3.8349161
OS 6.5137482 3.8209985
OS 6.5117819 3.806063
OS 6.5137482 3.7911275
OS 6.5195131 3.7772099
OS 6.5286837 3.7652585
OS 6.540635 3.7560879
OS 6.5545527 3.750323
OS 6.5694882 3.7483567
OS 6.5844237 3.750323
OS 6.5983414 3.7560879
OS 6.6102927 3.7652585
OS 6.6194633 3.7772099
OS 6.6252282 3.7911275
OS 6.6271945 3.806063
OS 6.6252282 3.8209985
OS 6.6194633 3.8349161
OS 6.6102927 3.8468675
OS 6.5983414 3.8560381
OS 6.5844237 3.861803
OS 6.5694882 3.8637693
OE
OB 3.6998425 3.7673765 H
OS 3.6935996 3.7661347
OS 3.6883071 3.7625984
OS 3.6847708 3.7573059
OS 3.683529 3.751063
OS 3.6847708 3.7448201
OS 3.6883071 3.7395276
OS 3.6935996 3.7359913
OS 3.6998425 3.7347495
OS 3.7060854 3.7359913
OS 3.7113779 3.7395276
OS 3.7149142 3.7448201
OS 3.716156 3.751063
OS 3.7149142 3.7573059
OS 3.7113779 3.7625984
OS 3.7060854 3.7661347
OS 3.6998425 3.7673765
OE
OB 2.9933858 3.7673765 H
OS 2.9871429 3.7661347
OS 2.9818504 3.7625984
OS 2.9783141 3.7573059
OS 2.9770723 3.751063
OS 2.9783141 3.7448201
OS 2.9818504 3.7395276
OS 2.9871429 3.7359913
OS 2.9933858 3.7347495
OS 2.9996287 3.7359913
OS 3.0049212 3.7395276
OS 3.0084575 3.7448201
OS 3.0096993 3.751063
OS 3.0084575 3.7573059
OS 3.0049212 3.7625984
OS 2.9996287 3.7661347
OS 2.9933858 3.7673765
OE
OB 6.2948425 3.7173765 H
OS 6.2885996 3.7161347
OS 6.2833071 3.7125984
OS 6.2797708 3.7073059
OS 6.278529 3.701063
OS 6.2797708 3.6948201
OS 6.2833071 3.6895276
OS 6.2885996 3.6859913
OS 6.2948425 3.6847495
OS 6.3010854 3.6859913
OS 6.3063779 3.6895276
OS 6.3099142 3.6948201
OS 6.311156 3.701063
OS 6.3099142 3.7073059
OS 6.3063779 3.7125984
OS 6.3010854 3.7161347
OS 6.2948425 3.7173765
OE
OB 1.8498425 3.7173765 H
OS 1.8435996 3.7161347
OS 1.8383071 3.7125984
OS 1.8347708 3.7073059
OS 1.833529 3.701063
OS 1.8347708 3.6948201
OS 1.8383071 3.6895276
OS 1.8435996 3.6859913
OS 1.8498425 3.6847495
OS 1.8560854 3.6859913
OS 1.8613779 3.6895276
OS 1.8649142 3.6948201
OS 1.866156 3.701063
OS 1.8649142 3.7073059
OS 1.8613779 3.7125984
OS 1.8560854 3.7161347
OS 1.8498425 3.7173765
OE
OB 4.0498425 3.6813765 H
OS 4.0435996 3.6801347
OS 4.0383071 3.6765984
OS 4.0347708 3.6713059
OS 4.033529 3.665063
OS 4.0347708 3.6588201
OS 4.0383071 3.6535276
OS 4.0435996 3.6499913
OS 4.0498425 3.6487495
OS 4.0560854 3.6499913
OS 4.0613779 3.6535276
OS 4.0649142 3.6588201
OS 4.066156 3.665063
OS 4.0649142 3.6713059
OS 4.0613779 3.6765984
OS 4.0560854 3.6801347
OS 4.0498425 3.6813765
OE
OB 2.6798425 3.6773765 H
OS 2.6735996 3.6761347
OS 2.6683071 3.6725984
OS 2.6647708 3.6673059
OS 2.663529 3.661063
OS 2.6647708 3.6548201
OS 2.6683071 3.6495276
OS 2.6735996 3.6459913
OS 2.6798425 3.6447495
OS 2.6860854 3.6459913
OS 2.6913779 3.6495276
OS 2.6949142 3.6548201
OS 2.696156 3.661063
OS 2.6949142 3.6673059
OS 2.6913779 3.6725984
OS 2.6860854 3.6761347
OS 2.6798425 3.6773765
OE
OB 1.7548425 3.6773765 H
OS 1.7485996 3.6761347
OS 1.7433071 3.6725984
OS 1.7397708 3.6673059
OS 1.738529 3.661063
OS 1.7397708 3.6548201
OS 1.7433071 3.6495276
OS 1.7485996 3.6459913
OS 1.7548425 3.6447495
OS 1.7610854 3.6459913
OS 1.7663779 3.6495276
OS 1.7699142 3.6548201
OS 1.771156 3.661063
OS 1.7699142 3.6673059
OS 1.7663779 3.6725984
OS 1.7610854 3.6761347
OS 1.7548425 3.6773765
OE
OB 3.4248425 3.6523765 H
OS 3.4185996 3.6511347
OS 3.4133071 3.6475984
OS 3.4097708 3.6423059
OS 3.408529 3.636063
OS 3.4097708 3.6298201
OS 3.4133071 3.6245276
OS 3.4185996 3.6209913
OS 3.4248425 3.6197495
OS 3.4310854 3.6209913
OS 3.4363779 3.6245276
OS 3.4399142 3.6298201
OS 3.441156 3.636063
OS 3.4399142 3.6423059
OS 3.4363779 3.6475984
OS 3.4310854 3.6511347
OS 3.4248425 3.6523765
OE
OB 2.7998425 3.6323765 H
OS 2.7935996 3.6311347
OS 2.7883071 3.6275984
OS 2.7847708 3.6223059
OS 2.783529 3.616063
OS 2.7847708 3.6098201
OS 2.7883071 3.6045276
OS 2.7935996 3.6009913
OS 2.7998425 3.5997495
OS 2.8060854 3.6009913
OS 2.8113779 3.6045276
OS 2.8149142 3.6098201
OS 2.816156 3.616063
OS 2.8149142 3.6223059
OS 2.8113779 3.6275984
OS 2.8060854 3.6311347
OS 2.7998425 3.6323765
OE
OB 2.1398425 3.6273765 H
OS 2.1335996 3.6261347
OS 2.1283071 3.6225984
OS 2.1247708 3.6173059
OS 2.123529 3.611063
OS 2.1247708 3.6048201
OS 2.1283071 3.5995276
OS 2.1335996 3.5959913
OS 2.1398425 3.5947495
OS 2.1460854 3.5959913
OS 2.1513779 3.5995276
OS 2.1549142 3.6048201
OS 2.156156 3.611063
OS 2.1549142 3.6173059
OS 2.1513779 3.6225984
OS 2.1460854 3.6261347
OS 2.1398425 3.6273765
OE
OB 1.8848425 3.6173765 H
OS 1.8785996 3.6161347
OS 1.8733071 3.6125984
OS 1.8697708 3.6073059
OS 1.868529 3.601063
OS 1.8697708 3.5948201
OS 1.8733071 3.5895276
OS 1.8785996 3.5859913
OS 1.8848425 3.5847495
OS 1.8910854 3.5859913
OS 1.8963779 3.5895276
OS 1.8999142 3.5948201
OS 1.901156 3.601063
OS 1.8999142 3.6073059
OS 1.8963779 3.6125984
OS 1.8910854 3.6161347
OS 1.8848425 3.6173765
OE
OB 3.2398425 3.6123765 H
OS 3.2335996 3.6111347
OS 3.2283071 3.6075984
OS 3.2247708 3.6023059
OS 3.223529 3.596063
OS 3.2247708 3.5898201
OS 3.2283071 3.5845276
OS 3.2335996 3.5809913
OS 3.2398425 3.5797495
OS 3.2460854 3.5809913
OS 3.2513779 3.5845276
OS 3.2549142 3.5898201
OS 3.256156 3.596063
OS 3.2549142 3.6023059
OS 3.2513779 3.6075984
OS 3.2460854 3.6111347
OS 3.2398425 3.6123765
OE
OB 1.5498425 3.6373765 H
OS 1.5435996 3.6361347
OS 1.5383071 3.6325984
OS 1.5347708 3.6273059
OS 1.533529 3.621063
OS 1.5347708 3.6148201
OS 1.5383071 3.6095276
OS 1.5435996 3.6059913
OS 1.5498425 3.6047495
OS 1.5560854 3.6059913
OS 1.5563282 3.6061536
OS 1.5599331 3.6025487
OS 1.5597708 3.6023059
OS 1.558529 3.596063
OS 1.5597708 3.5898201
OS 1.5633071 3.5845276
OS 1.5685996 3.5809913
OS 1.5748425 3.5797495
OS 1.5810854 3.5809913
OS 1.5863779 3.5845276
OS 1.5899142 3.5898201
OS 1.591156 3.596063
OS 1.5899142 3.6023059
OS 1.5863779 3.6075984
OS 1.5810854 3.6111347
OS 1.5748425 3.6123765
OS 1.5685996 3.6111347
OS 1.5683568 3.6109724
OS 1.5647519 3.6145773
OS 1.5649142 3.6148201
OS 1.566156 3.621063
OS 1.5649142 3.6273059
OS 1.5613779 3.6325984
OS 1.5560854 3.6361347
OS 1.5498425 3.6373765
OE
OB 2.4223425 3.6247884 H
OS 2.4133837 3.6230064
OS 2.4057888 3.6179317
OS 2.4007141 3.6103368
OS 2.3989321 3.601378
OS 2.4007141 3.5924192
OS 2.4057888 3.5848243
OS 2.4133837 3.5797496
OS 2.4223425 3.5779676
OS 2.4313013 3.5797496
OS 2.4388962 3.5848243
OS 2.4439709 3.5924192
OS 2.4457529 3.601378
OS 2.4439709 3.6103368
OS 2.4388962 3.6179317
OS 2.4313013 3.6230064
OS 2.4223425 3.6247884
OE
OB 2.7748425 3.5823765 H
OS 2.7685996 3.5811347
OS 2.7633071 3.5775984
OS 2.7597708 3.5723059
OS 2.758529 3.566063
OS 2.7597708 3.5598201
OS 2.7633071 3.5545276
OS 2.7685996 3.5509913
OS 2.7748425 3.5497495
OS 2.7810854 3.5509913
OS 2.7863779 3.5545276
OS 2.7899142 3.5598201
OS 2.791156 3.566063
OS 2.7899142 3.5723059
OS 2.7863779 3.5775984
OS 2.7810854 3.5811347
OS 2.7748425 3.5823765
OE
OB 1.4408425 3.5733765 H
OS 1.4345996 3.5721347
OS 1.4293071 3.5685984
OS 1.4257708 3.5633059
OS 1.424529 3.557063
OS 1.4257708 3.5508201
OS 1.4293071 3.5455276
OS 1.4345996 3.5419913
OS 1.4408425 3.5407495
OS 1.4470854 3.5419913
OS 1.4523779 3.5455276
OS 1.4559142 3.5508201
OS 1.457156 3.557063
OS 1.4559142 3.5633059
OS 1.4523779 3.5685984
OS 1.4470854 3.5721347
OS 1.4408425 3.5733765
OE
OB 5.9948425 3.5683765 H
OS 5.9885996 3.5671347
OS 5.9833071 3.5635984
OS 5.9797708 3.5583059
OS 5.978529 3.552063
OS 5.9797708 3.5458201
OS 5.9833071 3.5405276
OS 5.9885996 3.5369913
OS 5.9948425 3.5357495
OS 6.0010854 3.5369913
OS 6.0063779 3.5405276
OS 6.0099142 3.5458201
OS 6.011156 3.552063
OS 6.0099142 3.5583059
OS 6.0063779 3.5635984
OS 6.0010854 3.5671347
OS 5.9948425 3.5683765
OE
OB 2.4348425 3.5623765 H
OS 2.4285996 3.5611347
OS 2.4233071 3.5575984
OS 2.4197708 3.5523059
OS 2.418529 3.546063
OS 2.4197708 3.5398201
OS 2.4233071 3.5345276
OS 2.4285996 3.5309913
OS 2.4348425 3.5297495
OS 2.4410854 3.5309913
OS 2.4463779 3.5345276
OS 2.4499142 3.5398201
OS 2.451156 3.546063
OS 2.4499142 3.5523059
OS 2.4463779 3.5575984
OS 2.4410854 3.5611347
OS 2.4348425 3.5623765
OE
OB 2.2548425 3.5523765 H
OS 2.2485996 3.5511347
OS 2.2433071 3.5475984
OS 2.2397708 3.5423059
OS 2.238529 3.536063
OS 2.2397708 3.5298201
OS 2.2424883 3.5257531
OS 2.2396399 3.5214222
OS 2.2348425 3.5223765
OS 2.2285996 3.5211347
OS 2.2233071 3.5175984
OS 2.2197708 3.5123059
OS 2.218529 3.506063
OS 2.2197708 3.4998201
OS 2.2233071 3.4945276
OS 2.2285996 3.4909913
OS 2.2348425 3.4897495
OS 2.2410854 3.4909913
OS 2.2463779 3.4945276
OS 2.2499142 3.4998201
OS 2.251156 3.506063
OS 2.2499142 3.5123059
OS 2.2471967 3.5163729
OS 2.2500451 3.5207038
OS 2.2548425 3.5197495
OS 2.2610854 3.5209913
OS 2.2663779 3.5245276
OS 2.2699142 3.5298201
OS 2.271156 3.536063
OS 2.2699142 3.5423059
OS 2.2663779 3.5475984
OS 2.2610854 3.5511347
OS 2.2548425 3.5523765
OE
OB 5.2748425 3.5273765 H
OS 5.2685996 3.5261347
OS 5.2633071 3.5225984
OS 5.2597708 3.5173059
OS 5.258529 3.511063
OS 5.2597708 3.5048201
OS 5.2633071 3.4995276
OS 5.2685996 3.4959913
OS 5.2748425 3.4947495
OS 5.2810854 3.4959913
OS 5.2863779 3.4995276
OS 5.2899142 3.5048201
OS 5.291156 3.511063
OS 5.2899142 3.5173059
OS 5.2863779 3.5225984
OS 5.2810854 3.5261347
OS 5.2748425 3.5273765
OE
OB 3.6228425 3.5023765 H
OS 3.6165996 3.5011347
OS 3.6113071 3.4975984
OS 3.6077708 3.4923059
OS 3.606529 3.486063
OS 3.6077708 3.4798201
OS 3.6113071 3.4745276
OS 3.6165996 3.4709913
OS 3.6228425 3.4697495
OS 3.6290854 3.4709913
OS 3.6343779 3.4745276
OS 3.6379142 3.4798201
OS 3.639156 3.486063
OS 3.6379142 3.4923059
OS 3.6343779 3.4975984
OS 3.6290854 3.5011347
OS 3.6228425 3.5023765
OE
OB 2.5798425 3.5023765 H
OS 2.5735996 3.5011347
OS 2.5683071 3.4975984
OS 2.5647708 3.4923059
OS 2.563529 3.486063
OS 2.5647708 3.4798201
OS 2.5683071 3.4745276
OS 2.5735996 3.4709913
OS 2.5798425 3.4697495
OS 2.5860854 3.4709913
OS 2.5913779 3.4745276
OS 2.5949142 3.4798201
OS 2.596156 3.486063
OS 2.5949142 3.4923059
OS 2.5913779 3.4975984
OS 2.5860854 3.5011347
OS 2.5798425 3.5023765
OE
OB 3.5298425 3.4973765 H
OS 3.5235996 3.4961347
OS 3.5183071 3.4925984
OS 3.5147708 3.4873059
OS 3.513529 3.481063
OS 3.5147708 3.4748201
OS 3.5183071 3.4695276
OS 3.5235996 3.4659913
OS 3.5298425 3.4647495
OS 3.5360854 3.4659913
OS 3.5413779 3.4695276
OS 3.5449142 3.4748201
OS 3.546156 3.481063
OS 3.5449142 3.4873059
OS 3.5413779 3.4925984
OS 3.5360854 3.4961347
OS 3.5298425 3.4973765
OE
OB 2.3898425 3.4973765 H
OS 2.3835996 3.4961347
OS 2.3783071 3.4925984
OS 2.3747708 3.4873059
OS 2.373529 3.481063
OS 2.3747708 3.4748201
OS 2.3783071 3.4695276
OS 2.3835996 3.4659913
OS 2.3898425 3.4647495
OS 2.3960854 3.4659913
OS 2.4013779 3.4695276
OS 2.4049142 3.4748201
OS 2.406156 3.481063
OS 2.4049142 3.4873059
OS 2.4013779 3.4925984
OS 2.3960854 3.4961347
OS 2.3898425 3.4973765
OE
OB 6.5098425 3.4723765 H
OS 6.5035996 3.4711347
OS 6.4983071 3.4675984
OS 6.4947708 3.4623059
OS 6.493529 3.456063
OS 6.4947708 3.4498201
OS 6.4983071 3.4445276
OS 6.5035996 3.4409913
OS 6.5098425 3.4397495
OS 6.5160854 3.4409913
OS 6.5213779 3.4445276
OS 6.5249142 3.4498201
OS 6.526156 3.456063
OS 6.5249142 3.4623059
OS 6.5213779 3.4675984
OS 6.5160854 3.4711347
OS 6.5098425 3.4723765
OE
OB 3.4368425 3.4733765 H
OS 3.4305996 3.4721347
OS 3.4253071 3.4685984
OS 3.4217708 3.4633059
OS 3.420529 3.457063
OS 3.4217708 3.4508201
OS 3.4253071 3.4455276
OS 3.4305996 3.4419913
OS 3.4368425 3.4407495
OS 3.4430854 3.4419913
OS 3.4483779 3.4455276
OS 3.4502305 3.4483003
OS 3.4506142 3.4484287
OS 3.4560152 3.4479578
OS 3.4583071 3.4445276
OS 3.4635996 3.4409913
OS 3.4698425 3.4397495
OS 3.4760854 3.4409913
OS 3.4813779 3.4445276
OS 3.4849142 3.4498201
OS 3.486156 3.456063
OS 3.4849142 3.4623059
OS 3.4813779 3.4675984
OS 3.4760854 3.4711347
OS 3.4698425 3.4723765
OS 3.4635996 3.4711347
OS 3.4583071 3.4675984
OS 3.4564545 3.4648257
OS 3.4560708 3.4646973
OS 3.4506698 3.4651682
OS 3.4483779 3.4685984
OS 3.4430854 3.4721347
OS 3.4368425 3.4733765
OE
OB 3.3588425 3.4643765 H
OS 3.3525996 3.4631347
OS 3.3473071 3.4595984
OS 3.3437708 3.4543059
OS 3.342529 3.448063
OS 3.3437708 3.4418201
OS 3.3473071 3.4365276
OS 3.3525996 3.4329913
OS 3.3588425 3.4317495
OS 3.3650854 3.4329913
OS 3.3703779 3.4365276
OS 3.3739142 3.4418201
OS 3.3741941 3.443227
OS 3.379292 3.443227
OS 3.3797708 3.4408201
OS 3.3833071 3.4355276
OS 3.3885996 3.4319913
OS 3.3948425 3.4307495
OS 3.4010854 3.4319913
OS 3.4063779 3.4355276
OS 3.4099142 3.4408201
OS 3.411156 3.447063
OS 3.4099142 3.4533059
OS 3.4063779 3.4585984
OS 3.4010854 3.4621347
OS 3.3948425 3.4633765
OS 3.3885996 3.4621347
OS 3.3833071 3.4585984
OS 3.3797708 3.4533059
OS 3.3794909 3.451899
OS 3.374393 3.451899
OS 3.3739142 3.4543059
OS 3.3703779 3.4595984
OS 3.3650854 3.4631347
OS 3.3588425 3.4643765
OE
OB 2.4223425 3.4673081 H
OS 2.4133837 3.4655261
OS 2.4057888 3.4604514
OS 2.4007141 3.4528565
OS 2.3989321 3.4438977
OS 2.4007141 3.4349389
OS 2.4057888 3.427344
OS 2.4133837 3.4222693
OS 2.4223425 3.4204873
OS 2.4313013 3.4222693
OS 2.4388962 3.427344
OS 2.4439709 3.4349389
OS 2.4457529 3.4438977
OS 2.4439709 3.4528565
OS 2.4388962 3.4604514
OS 2.4313013 3.4655261
OS 2.4223425 3.4673081
OE
OB 6.4798425 3.4423765 H
OS 6.4735996 3.4411347
OS 6.4683071 3.4375984
OS 6.4647708 3.4323059
OS 6.463529 3.426063
OS 6.4647708 3.4198201
OS 6.4683071 3.4145276
OS 6.4735996 3.4109913
OS 6.4798425 3.4097495
OS 6.4860854 3.4109913
OS 6.4913779 3.4145276
OS 6.4949142 3.4198201
OS 6.496156 3.426063
OS 6.4949142 3.4323059
OS 6.4913779 3.4375984
OS 6.4860854 3.4411347
OS 6.4798425 3.4423765
OE
OB 2.6348425 3.4223765 H
OS 2.6285996 3.4211347
OS 2.6233071 3.4175984
OS 2.6197708 3.4123059
OS 2.618529 3.406063
OS 2.6197708 3.3998201
OS 2.6233071 3.3945276
OS 2.6285996 3.3909913
OS 2.6348425 3.3897495
OS 2.6410854 3.3909913
OS 2.6463779 3.3945276
OS 2.6499142 3.3998201
OS 2.651156 3.406063
OS 2.6499142 3.4123059
OS 2.6463779 3.4175984
OS 2.6410854 3.4211347
OS 2.6348425 3.4223765
OE
OB 6.4475772 3.4123765 H
OS 6.4413343 3.4111347
OS 6.4360418 3.4075984
OS 6.4325055 3.4023059
OS 6.4312637 3.396063
OS 6.4325055 3.3898201
OS 6.4360418 3.3845276
OS 6.4413343 3.3809913
OS 6.4475772 3.3797495
OS 6.4538201 3.3809913
OS 6.4591126 3.3845276
OS 6.4626489 3.3898201
OS 6.4638907 3.396063
OS 6.4626489 3.4023059
OS 6.4591126 3.4075984
OS 6.4538201 3.4111347
OS 6.4475772 3.4123765
OE
OB 3.0688976 3.4119828 H
OS 3.0626547 3.410741
OS 3.0573622 3.4072047
OS 3.0538259 3.4019122
OS 3.0525841 3.3956693
OS 3.0538259 3.3894264
OS 3.0573622 3.3841339
OS 3.0626547 3.3805976
OS 3.0688976 3.3793558
OS 3.0751405 3.3805976
OS 3.080433 3.3841339
OS 3.0839693 3.3894264
OS 3.0852111 3.3956693
OS 3.0839693 3.4019122
OS 3.080433 3.4072047
OS 3.0751405 3.410741
OS 3.0688976 3.4119828
OE
OB 6.4098425 3.3873765 H
OS 6.4035996 3.3861347
OS 6.3983071 3.3825984
OS 6.3947708 3.3773059
OS 6.393529 3.371063
OS 6.3947708 3.3648201
OS 6.3983071 3.3595276
OS 6.4035996 3.3559913
OS 6.4098425 3.3547495
OS 6.4160854 3.3559913
OS 6.4213779 3.3595276
OS 6.4249142 3.3648201
OS 6.426156 3.371063
OS 6.4249142 3.3773059
OS 6.4213779 3.3825984
OS 6.4160854 3.3861347
OS 6.4098425 3.3873765
OE
OB 3.3028425 3.3603765 H
OS 3.2965996 3.3591347
OS 3.2913071 3.3555984
OS 3.2877708 3.3503059
OS 3.286529 3.344063
OS 3.2877708 3.3378201
OS 3.2913071 3.3325276
OS 3.2965996 3.3289913
OS 3.3028425 3.3277495
OS 3.3090854 3.3289913
OS 3.3143779 3.3325276
OS 3.3179142 3.3378201
OS 3.319156 3.344063
OS 3.3179142 3.3503059
OS 3.3143779 3.3555984
OS 3.3090854 3.3591347
OS 3.3028425 3.3603765
OE
OB 6.3547483 3.3474519 H
OS 6.3485054 3.3462101
OS 6.3432129 3.3426738
OS 6.3396766 3.3373813
OS 6.3384348 3.3311384
OS 6.3396766 3.3248955
OS 6.3432129 3.319603
OS 6.3485054 3.3160667
OS 6.3547483 3.3148249
OS 6.3609912 3.3160667
OS 6.3662837 3.319603
OS 6.36982 3.3248955
OS 6.3710618 3.3311384
OS 6.36982 3.3373813
OS 6.3662837 3.3426738
OS 6.3609912 3.3462101
OS 6.3547483 3.3474519
OE
OB 3.542865 3.335354 H
OS 3.5366221 3.3341122
OS 3.5313296 3.3305759
OS 3.5277933 3.3252834
OS 3.5265515 3.3190405
OS 3.5277933 3.3127976
OS 3.5313296 3.3075051
OS 3.5366221 3.3039688
OS 3.542865 3.302727
OS 3.5491079 3.3039688
OS 3.5544004 3.3075051
OS 3.5579367 3.3127976
OS 3.5591785 3.3190405
OS 3.5579367 3.3252834
OS 3.5544004 3.3305759
OS 3.5491079 3.3341122
OS 3.542865 3.335354
OE
OB 3.2636972 3.3202312 H
OS 3.2574543 3.3189894
OS 3.2521618 3.3154531
OS 3.2486255 3.3101606
OS 3.2473837 3.3039177
OS 3.2486255 3.2976748
OS 3.2521618 3.2923823
OS 3.2574543 3.288846
OS 3.2636972 3.2876042
OS 3.2699401 3.288846
OS 3.2752326 3.2923823
OS 3.2787689 3.2976748
OS 3.2800107 3.3039177
OS 3.2787689 3.3101606
OS 3.2752326 3.3154531
OS 3.2699401 3.3189894
OS 3.2636972 3.3202312
OE
OB 3.4918425 3.3133765 H
OS 3.4855996 3.3121347
OS 3.4803071 3.3085984
OS 3.4767708 3.3033059
OS 3.475529 3.297063
OS 3.4767708 3.2908201
OS 3.4803071 3.2855276
OS 3.4855996 3.2819913
OS 3.4918425 3.2807495
OS 3.4980854 3.2819913
OS 3.5033779 3.2855276
OS 3.5069142 3.2908201
OS 3.508156 3.297063
OS 3.5069142 3.3033059
OS 3.5033779 3.3085984
OS 3.4980854 3.3121347
OS 3.4918425 3.3133765
OE
OB 3.6538425 3.3093765 H
OS 3.6475996 3.3081347
OS 3.6423071 3.3045984
OS 3.6387708 3.2993059
OS 3.637529 3.293063
OS 3.6387708 3.2868201
OS 3.6423071 3.2815276
OS 3.6475996 3.2779913
OS 3.6538425 3.2767495
OS 3.6600854 3.2779913
OS 3.6653779 3.2815276
OS 3.6689142 3.2868201
OS 3.670156 3.293063
OS 3.6689142 3.2993059
OS 3.6653779 3.3045984
OS 3.6600854 3.3081347
OS 3.6538425 3.3093765
OE
OB 6.4448425 3.3073765 H
OS 6.4385996 3.3061347
OS 6.4333071 3.3025984
OS 6.4297708 3.2973059
OS 6.428529 3.291063
OS 6.4297708 3.2848201
OS 6.4333071 3.2795276
OS 6.4385996 3.2759913
OS 6.4448425 3.2747495
OS 6.4510854 3.2759913
OS 6.4563779 3.2795276
OS 6.4599142 3.2848201
OS 6.461156 3.291063
OS 6.4599142 3.2973059
OS 6.4563779 3.3025984
OS 6.4510854 3.3061347
OS 6.4448425 3.3073765
OE
OB 2.5908425 3.3043765 H
OS 2.5845996 3.3031347
OS 2.5793071 3.2995984
OS 2.5757708 3.2943059
OS 2.574529 3.288063
OS 2.5757708 3.2818201
OS 2.5793071 3.2765276
OS 2.5845996 3.2729913
OS 2.5908425 3.2717495
OS 2.5970854 3.2729913
OS 2.6023779 3.2765276
OS 2.6059142 3.2818201
OS 2.607156 3.288063
OS 2.6059142 3.2943059
OS 2.6023779 3.2995984
OS 2.5970854 3.3031347
OS 2.5908425 3.3043765
OE
OB 3.3748425 3.2893765 H
OS 3.3685996 3.2881347
OS 3.3633071 3.2845984
OS 3.3597708 3.2793059
OS 3.358529 3.273063
OS 3.3597708 3.2668201
OS 3.3633071 3.2615276
OS 3.3685996 3.2579913
OS 3.3748425 3.2567495
OS 3.3810854 3.2579913
OS 3.3863779 3.2615276
OS 3.3899142 3.2668201
OS 3.391156 3.273063
OS 3.3899142 3.2793059
OS 3.3863779 3.2845984
OS 3.3810854 3.2881347
OS 3.3748425 3.2893765
OE
OB 6.3348425 3.2823765 H
OS 6.3285996 3.2811347
OS 6.3233071 3.2775984
OS 6.3197708 3.2723059
OS 6.318529 3.266063
OS 6.3197708 3.2598201
OS 6.3233071 3.2545276
OS 6.3285996 3.2509913
OS 6.3348425 3.2497495
OS 6.3410854 3.2509913
OS 6.3463779 3.2545276
OS 6.3499142 3.2598201
OS 6.351156 3.266063
OS 6.3499142 3.2723059
OS 6.3463779 3.2775984
OS 6.3410854 3.2811347
OS 6.3348425 3.2823765
OE
OB 3.7448425 3.2773765 H
OS 3.7385996 3.2761347
OS 3.7333071 3.2725984
OS 3.7297708 3.2673059
OS 3.728529 3.261063
OS 3.7297708 3.2548201
OS 3.7333071 3.2495276
OS 3.7385996 3.2459913
OS 3.7448425 3.2447495
OS 3.7510854 3.2459913
OS 3.7563779 3.2495276
OS 3.7599142 3.2548201
OS 3.761156 3.261063
OS 3.7599142 3.2673059
OS 3.7563779 3.2725984
OS 3.7510854 3.2761347
OS 3.7448425 3.2773765
OE
OB 2.2598425 3.2773765 H
OS 2.2535996 3.2761347
OS 2.2483071 3.2725984
OS 2.2447708 3.2673059
OS 2.243529 3.261063
OS 2.2447708 3.2548201
OS 2.2483071 3.2495276
OS 2.2535996 3.2459913
OS 2.2598425 3.2447495
OS 2.2660854 3.2459913
OS 2.2713779 3.2495276
OS 2.2749142 3.2548201
OS 2.276156 3.261063
OS 2.2749142 3.2673059
OS 2.2713779 3.2725984
OS 2.2660854 3.2761347
OS 2.2598425 3.2773765
OE
OB 3.2308425 3.2513765 H
OS 3.2245996 3.2501347
OS 3.2193071 3.2465984
OS 3.2157708 3.2413059
OS 3.214529 3.235063
OS 3.2157708 3.2288201
OS 3.2193071 3.2235276
OS 3.2245996 3.2199913
OS 3.2308425 3.2187495
OS 3.2370854 3.2199913
OS 3.2423779 3.2235276
OS 3.2459142 3.2288201
OS 3.247156 3.235063
OS 3.2459142 3.2413059
OS 3.2423779 3.2465984
OS 3.2370854 3.2501347
OS 3.2308425 3.2513765
OE
OB 6.2824161 3.2423765 H
OS 6.2761732 3.2411347
OS 6.2708807 3.2375984
OS 6.2673444 3.2323059
OS 6.2661026 3.226063
OS 6.2673444 3.2198201
OS 6.2708807 3.2145276
OS 6.2761732 3.2109913
OS 6.2824161 3.2097495
OS 6.288659 3.2109913
OS 6.2939515 3.2145276
OS 6.2974878 3.2198201
OS 6.2987296 3.226063
OS 6.2974878 3.2323059
OS 6.2939515 3.2375984
OS 6.288659 3.2411347
OS 6.2824161 3.2423765
OE
OB 3.8068425 3.2513765 H
OS 3.8005996 3.2501347
OS 3.7953071 3.2465984
OS 3.7917708 3.2413059
OS 3.790529 3.235063
OS 3.7917708 3.2288201
OS 3.7953071 3.2235276
OS 3.7975621 3.2220209
OS 3.7965063 3.2167129
OS 3.7935996 3.2161347
OS 3.7883071 3.2125984
OS 3.7847708 3.2073059
OS 3.783529 3.201063
OS 3.7847708 3.1948201
OS 3.7883071 3.1895276
OS 3.7935996 3.1859913
OS 3.7998425 3.1847495
OS 3.8060854 3.1859913
OS 3.8113779 3.1895276
OS 3.8149142 3.1948201
OS 3.816156 3.201063
OS 3.8149142 3.2073059
OS 3.8113779 3.2125984
OS 3.8091229 3.2141051
OS 3.8101787 3.2194131
OS 3.8130854 3.2199913
OS 3.8183779 3.2235276
OS 3.8219142 3.2288201
OS 3.823156 3.235063
OS 3.8219142 3.2413059
OS 3.8183779 3.2465984
OS 3.8130854 3.2501347
OS 3.8068425 3.2513765
OE
OB 2.2058425 3.2163765 H
OS 2.1995996 3.2151347
OS 2.1943071 3.2115984
OS 2.1907708 3.2063059
OS 2.189529 3.200063
OS 2.1907708 3.1938201
OS 2.1943071 3.1885276
OS 2.1995996 3.1849913
OS 2.2058425 3.1837495
OS 2.2120854 3.1849913
OS 2.2173779 3.1885276
OS 2.2209142 3.1938201
OS 2.222156 3.200063
OS 2.2209142 3.2063059
OS 2.2173779 3.2115984
OS 2.2120854 3.2151347
OS 2.2058425 3.2163765
OE
OB 2.4223425 3.2631033 H
OS 2.4133837 3.2613213
OS 2.4057888 3.2562466
OS 2.4007141 3.2486517
OS 2.3989321 3.2396929
OS 2.4007141 3.2307341
OS 2.4057888 3.2231392
OS 2.4098502 3.2204255
OS 2.4087944 3.2151175
OS 2.4078122 3.2149221
OS 2.4025197 3.2113858
OS 2.3989834 3.2060933
OS 2.3977416 3.1998504
OS 2.3989834 3.1936075
OS 2.4025197 3.188315
OS 2.4078122 3.1847787
OS 2.4140551 3.1835369
OS 2.420298 3.1847787
OS 2.4255905 3.188315
OS 2.4291268 3.1936075
OS 2.4303686 3.1998504
OS 2.4291268 3.2060933
OS 2.4255905 3.2113858
OS 2.4250776 3.2117285
OS 2.4261334 3.2170365
OS 2.4313013 3.2180645
OS 2.4388962 3.2231392
OS 2.4439709 3.2307341
OS 2.4457529 3.2396929
OS 2.4439709 3.2486517
OS 2.4388962 3.2562466
OS 2.4313013 3.2613213
OS 2.4223425 3.2631033
OE
OB 6.3094161 3.2153765 H
OS 6.3031732 3.2141347
OS 6.2978807 3.2105984
OS 6.2943444 3.2053059
OS 6.2931026 3.199063
OS 6.2943444 3.1928201
OS 6.2978807 3.1875276
OS 6.3031732 3.1839913
OS 6.3094161 3.1827495
OS 6.315659 3.1839913
OS 6.3209515 3.1875276
OS 6.3244878 3.1928201
OS 6.3257296 3.199063
OS 6.3244878 3.2053059
OS 6.3209515 3.2105984
OS 6.315659 3.2141347
OS 6.3094161 3.2153765
OE
OB 6.4398425 3.2073765 H
OS 6.4335996 3.2061347
OS 6.4283071 3.2025984
OS 6.4247708 3.1973059
OS 6.423529 3.191063
OS 6.4247708 3.1848201
OS 6.4283071 3.1795276
OS 6.4335996 3.1759913
OS 6.4398425 3.1747495
OS 6.4460854 3.1759913
OS 6.4513779 3.1795276
OS 6.4549142 3.1848201
OS 6.456156 3.191063
OS 6.4549142 3.1973059
OS 6.4513779 3.2025984
OS 6.4460854 3.2061347
OS 6.4398425 3.2073765
OE
OB 3.1889764 3.2033214 H
OS 3.1827335 3.2020796
OS 3.177441 3.1985433
OS 3.1739047 3.1932508
OS 3.1726629 3.1870079
OS 3.1739047 3.180765
OS 3.177441 3.1754725
OS 3.1827335 3.1719362
OS 3.1889764 3.1706944
OS 3.1952193 3.1719362
OS 3.2005118 3.1754725
OS 3.2040481 3.180765
OS 3.2052899 3.1870079
OS 3.2040481 3.1932508
OS 3.2005118 3.1985433
OS 3.1952193 3.2020796
OS 3.1889764 3.2033214
OE
OB 2.5918425 3.202534 H
OS 2.5855996 3.2012922
OS 2.5803071 3.1977559
OS 2.5767708 3.1924634
OS 2.575529 3.1862205
OS 2.5767708 3.1799776
OS 2.5803071 3.1746851
OS 2.5855996 3.1711488
OS 2.5918425 3.169907
OS 2.5980854 3.1711488
OS 2.6033779 3.1746851
OS 2.6069142 3.1799776
OS 2.608156 3.1862205
OS 2.6069142 3.1924634
OS 2.6033779 3.1977559
OS 2.5980854 3.2012922
OS 2.5918425 3.202534
OE
OB 2.462374 3.1885576 H
OS 2.4561311 3.1873158
OS 2.4508386 3.1837795
OS 2.4473023 3.178487
OS 2.4460605 3.1722441
OS 2.4473023 3.1660012
OS 2.4508386 3.1607087
OS 2.4561311 3.1571724
OS 2.462374 3.1559306
OS 2.4686169 3.1571724
OS 2.4739094 3.1607087
OS 2.4774457 3.1660012
OS 2.4786875 3.1722441
OS 2.4774457 3.178487
OS 2.4739094 3.1837795
OS 2.4686169 3.1873158
OS 2.462374 3.1885576
OE
OB 6.3398425 3.1673765 H
OS 6.3335996 3.1661347
OS 6.3283071 3.1625984
OS 6.3247708 3.1573059
OS 6.323529 3.151063
OS 6.3247708 3.1448201
OS 6.3283071 3.1395276
OS 6.3335996 3.1359913
OS 6.3398425 3.1347495
OS 6.3460854 3.1359913
OS 6.3513779 3.1395276
OS 6.3549142 3.1448201
OS 6.356156 3.151063
OS 6.3549142 3.1573059
OS 6.3513779 3.1625984
OS 6.3460854 3.1661347
OS 6.3398425 3.1673765
OE
OB 3.8298425 3.1923765 H
OS 3.8235996 3.1911347
OS 3.8183071 3.1875984
OS 3.8147708 3.1823059
OS 3.813529 3.176063
OS 3.8147708 3.1698201
OS 3.8183071 3.1645276
OS 3.8235996 3.1609913
OS 3.8298425 3.1597495
OS 3.8360854 3.1609913
OS 3.8363282 3.1611536
OS 3.8399331 3.1575487
OS 3.8397708 3.1573059
OS 3.838529 3.151063
OS 3.8397708 3.1448201
OS 3.8433071 3.1395276
OS 3.8485996 3.1359913
OS 3.8548425 3.1347495
OS 3.8610854 3.1359913
OS 3.8663779 3.1395276
OS 3.8699142 3.1448201
OS 3.871156 3.151063
OS 3.8699142 3.1573059
OS 3.8663779 3.1625984
OS 3.8610854 3.1661347
OS 3.8548425 3.1673765
OS 3.8485996 3.1661347
OS 3.8483568 3.1659724
OS 3.8447519 3.1695773
OS 3.8449142 3.1698201
OS 3.846156 3.176063
OS 3.8449142 3.1823059
OS 3.8413779 3.1875984
OS 3.8360854 3.1911347
OS 3.8298425 3.1923765
OE
OB 1.4598425 3.1633765 H
OS 1.4535996 3.1621347
OS 1.4483071 3.1585984
OS 1.4447708 3.1533059
OS 1.443529 3.147063
OS 1.4447708 3.1408201
OS 1.4483071 3.1355276
OS 1.4535996 3.1319913
OS 1.4598425 3.1307495
OS 1.4660854 3.1319913
OS 1.4713779 3.1355276
OS 1.4749142 3.1408201
OS 1.476156 3.147063
OS 1.4749142 3.1533059
OS 1.4713779 3.1585984
OS 1.4660854 3.1621347
OS 1.4598425 3.1633765
OE
OB 3.2755905 3.1580458 H
OS 3.2693476 3.156804
OS 3.2640551 3.1532677
OS 3.2605188 3.1479752
OS 3.259277 3.1417323
OS 3.2605188 3.1354894
OS 3.2640551 3.1301969
OS 3.2693476 3.1266606
OS 3.2755905 3.1254188
OS 3.2818334 3.1266606
OS 3.2871259 3.1301969
OS 3.2906622 3.1354894
OS 3.291904 3.1417323
OS 3.2906622 3.1479752
OS 3.2871259 3.1532677
OS 3.2818334 3.156804
OS 3.2755905 3.1580458
OE
OB 6.3048425 3.1373765 H
OS 6.2985996 3.1361347
OS 6.2933071 3.1325984
OS 6.2897708 3.1273059
OS 6.288529 3.121063
OS 6.2897708 3.1148201
OS 6.2933071 3.1095276
OS 6.2985996 3.1059913
OS 6.3048425 3.1047495
OS 6.3110854 3.1059913
OS 6.3163779 3.1095276
OS 6.3199142 3.1148201
OS 6.321156 3.121063
OS 6.3199142 3.1273059
OS 6.3163779 3.1325984
OS 6.3110854 3.1361347
OS 6.3048425 3.1373765
OE
OB 3.9398425 3.1373765 H
OS 3.9335996 3.1361347
OS 3.9283071 3.1325984
OS 3.9247708 3.1273059
OS 3.923529 3.121063
OS 3.9247708 3.1148201
OS 3.9283071 3.1095276
OS 3.9335996 3.1059913
OS 3.9398425 3.1047495
OS 3.9460854 3.1059913
OS 3.9513779 3.1095276
OS 3.9549142 3.1148201
OS 3.956156 3.121063
OS 3.9549142 3.1273059
OS 3.9513779 3.1325984
OS 3.9460854 3.1361347
OS 3.9398425 3.1373765
OE
OB 3.4918425 3.1193765 H
OS 3.4855996 3.1181347
OS 3.4803071 3.1145984
OS 3.4767708 3.1093059
OS 3.475529 3.103063
OS 3.4767708 3.0968201
OS 3.4803071 3.0915276
OS 3.4855996 3.0879913
OS 3.4918425 3.0867495
OS 3.4980854 3.0879913
OS 3.5033779 3.0915276
OS 3.5069142 3.0968201
OS 3.508156 3.103063
OS 3.5069142 3.1093059
OS 3.5033779 3.1145984
OS 3.4980854 3.1181347
OS 3.4918425 3.1193765
OE
OB 2.4187174 3.1348201 H
OS 2.4124745 3.1335783
OS 2.407182 3.130042
OS 2.4036457 3.1247495
OS 2.4024039 3.1185066
OS 2.4036457 3.1122637
OS 2.407182 3.1069712
OS 2.4081253 3.1063409
OS 2.4081253 3.1003275
OS 2.4057888 3.0987663
OS 2.4007141 3.0911714
OS 2.3989321 3.0822126
OS 2.4007141 3.0732538
OS 2.4057888 3.0656589
OS 2.4133837 3.0605842
OS 2.4223425 3.0588022
OS 2.4313013 3.0605842
OS 2.4388962 3.0656589
OS 2.4439709 3.0732538
OS 2.4457529 3.0822126
OS 2.4439709 3.0911714
OS 2.4388962 3.0987663
OS 2.4329346 3.1027496
OS 2.4313655 3.1052197
OS 2.4315364 3.1088922
OS 2.4337891 3.1122637
OS 2.4350309 3.1185066
OS 2.4337891 3.1247495
OS 2.4302528 3.130042
OS 2.4249603 3.1335783
OS 2.4187174 3.1348201
OE
OB 3.3688425 3.0663765 H
OS 3.3625996 3.0651347
OS 3.3573071 3.0615984
OS 3.3537708 3.0563059
OS 3.352529 3.050063
OS 3.3537708 3.0438201
OS 3.3573071 3.0385276
OS 3.3625996 3.0349913
OS 3.3688425 3.0337495
OS 3.3750854 3.0349913
OS 3.3803779 3.0385276
OS 3.3839142 3.0438201
OS 3.385156 3.050063
OS 3.3839142 3.0563059
OS 3.3803779 3.0615984
OS 3.3750854 3.0651347
OS 3.3688425 3.0663765
OE
OB 3.3448425 3.0123765 H
OS 3.3385996 3.0111347
OS 3.3333071 3.0075984
OS 3.3297708 3.0023059
OS 3.328529 2.996063
OS 3.3297708 2.9898201
OS 3.3333071 2.9845276
OS 3.3385996 2.9809913
OS 3.3448425 2.9797495
OS 3.3510854 2.9809913
OS 3.3563779 2.9845276
OS 3.3599142 2.9898201
OS 3.361156 2.996063
OS 3.3599142 3.0023059
OS 3.3563779 3.0075984
OS 3.3510854 3.0111347
OS 3.3448425 3.0123765
OE
OB 3.1978425 2.9863765 H
OS 3.1915996 2.9851347
OS 3.1863071 2.9815984
OS 3.1827708 2.9763059
OS 3.181529 2.970063
OS 3.1827708 2.9638201
OS 3.1863071 2.9585276
OS 3.1915996 2.9549913
OS 3.1978425 2.9537495
OS 3.2040854 2.9549913
OS 3.2093779 2.9585276
OS 3.2129142 2.9638201
OS 3.214156 2.970063
OS 3.2129142 2.9763059
OS 3.2093779 2.9815984
OS 3.2040854 2.9851347
OS 3.1978425 2.9863765
OE
OB 4.7942913 2.8243844 H
OS 4.7880484 2.8231426
OS 4.7827559 2.8196063
OS 4.7792196 2.8143138
OS 4.7779778 2.8080709
OS 4.7792196 2.801828
OS 4.7827559 2.7965355
OS 4.7880484 2.7929992
OS 4.7942913 2.7917574
OS 4.8005342 2.7929992
OS 4.8058267 2.7965355
OS 4.809363 2.801828
OS 4.8106048 2.8080709
OS 4.809363 2.8143138
OS 4.8058267 2.8196063
OS 4.8005342 2.8231426
OS 4.7942913 2.8243844
OE
OB 4.5036614 2.8061954 H
OS 4.4974185 2.8049536
OS 4.492126 2.8014173
OS 4.4885897 2.7961248
OS 4.4873479 2.7898819
OS 4.4885897 2.783639
OS 4.492126 2.7783465
OS 4.4974185 2.7748102
OS 4.5036614 2.7735684
OS 4.5099043 2.7748102
OS 4.5151968 2.7783465
OS 4.5187331 2.783639
OS 4.5199749 2.7898819
OS 4.5187331 2.7961248
OS 4.5151968 2.8014173
OS 4.5099043 2.8049536
OS 4.5036614 2.8061954
OE
OB 2.1468425 2.7693765 H
OS 2.1405996 2.7681347
OS 2.1353071 2.7645984
OS 2.1317708 2.7593059
OS 2.130529 2.753063
OS 2.1317708 2.7468201
OS 2.1353071 2.7415276
OS 2.1405996 2.7379913
OS 2.1468425 2.7367495
OS 2.1530854 2.7379913
OS 2.1583779 2.7415276
OS 2.1619142 2.7468201
OS 2.163156 2.753063
OS 2.1619142 2.7593059
OS 2.1583779 2.7645984
OS 2.1530854 2.7681347
OS 2.1468425 2.7693765
OE
OB 2.6929134 2.7377702 H
OS 2.6866705 2.7365284
OS 2.681378 2.7329921
OS 2.6778417 2.7276996
OS 2.6765999 2.7214567
OS 2.6778417 2.7152138
OS 2.681378 2.7099213
OS 2.6866705 2.706385
OS 2.6929134 2.7051432
OS 2.6991563 2.706385
OS 2.7044488 2.7099213
OS 2.7079851 2.7152138
OS 2.7092269 2.7214567
OS 2.7079851 2.7276996
OS 2.7044488 2.7329921
OS 2.6991563 2.7365284
OS 2.6929134 2.7377702
OE
OB 2.394685 2.7367859 H
OS 2.3884421 2.7355441
OS 2.3831496 2.7320078
OS 2.3796133 2.7267153
OS 2.3783715 2.7204724
OS 2.3796133 2.7142295
OS 2.3831496 2.708937
OS 2.3884421 2.7054007
OS 2.394685 2.7041589
OS 2.4009279 2.7054007
OS 2.4062204 2.708937
OS 2.4097567 2.7142295
OS 2.4109985 2.7204724
OS 2.4097567 2.7267153
OS 2.4062204 2.7320078
OS 2.4009279 2.7355441
OS 2.394685 2.7367859
OE
OB 2.4948425 2.7123765 H
OS 2.4885996 2.7111347
OS 2.4833071 2.7075984
OS 2.4797708 2.7023059
OS 2.478529 2.696063
OS 2.4797708 2.6898201
OS 2.4833071 2.6845276
OS 2.4883212 2.6811773
OS 2.4885995 2.6790399
OS 2.4885995 2.6780861
OS 2.4883212 2.6759487
OS 2.4833071 2.6725984
OS 2.4797708 2.6673059
OS 2.478529 2.661063
OS 2.4797708 2.6548201
OS 2.4833071 2.6495276
OS 2.4885996 2.6459913
OS 2.4948425 2.6447495
OS 2.5010854 2.6459913
OS 2.5063779 2.6495276
OS 2.5099142 2.6548201
OS 2.511156 2.661063
OS 2.5099142 2.6673059
OS 2.5063779 2.6725984
OS 2.5013638 2.6759487
OS 2.5010855 2.6780861
OS 2.5010855 2.6790399
OS 2.5013638 2.6811773
OS 2.5063779 2.6845276
OS 2.5099142 2.6898201
OS 2.511156 2.696063
OS 2.5099142 2.7023059
OS 2.5063779 2.7075984
OS 2.5010854 2.7111347
OS 2.4948425 2.7123765
OE
OB 2.9588425 2.6373765 H
OS 2.9525996 2.6361347
OS 2.9473071 2.6325984
OS 2.9437708 2.6273059
OS 2.942529 2.621063
OS 2.9437708 2.6148201
OS 2.9473071 2.6095276
OS 2.9525996 2.6059913
OS 2.9588425 2.6047495
OS 2.9650854 2.6059913
OS 2.9703779 2.6095276
OS 2.9739142 2.6148201
OS 2.975156 2.621063
OS 2.9739142 2.6273059
OS 2.9703779 2.6325984
OS 2.9650854 2.6361347
OS 2.9588425 2.6373765
OE
OB 2.4291925 2.6373765 H
OS 2.4229496 2.6361347
OS 2.4176571 2.6325984
OS 2.4141208 2.6273059
OS 2.412879 2.621063
OS 2.4141208 2.6148201
OS 2.4176571 2.6095276
OS 2.4229496 2.6059913
OS 2.4291925 2.6047495
OS 2.4354354 2.6059913
OS 2.4407279 2.6095276
OS 2.4442642 2.6148201
OS 2.445506 2.621063
OS 2.4442642 2.6273059
OS 2.4407279 2.6325984
OS 2.4354354 2.6361347
OS 2.4291925 2.6373765
OE
OB 2.2523425 2.6298765 H
OS 2.2460996 2.6286347
OS 2.2408071 2.6250984
OS 2.2372708 2.6198059
OS 2.236029 2.613563
OS 2.2372708 2.6073201
OS 2.239748 2.6036127
OS 2.2364566 2.5995388
OS 2.2317425 2.6004765
OS 2.2254996 2.5992347
OS 2.2202071 2.5956984
OS 2.2166708 2.5904059
OS 2.215429 2.584163
OS 2.2166708 2.5779201
OS 2.2202071 2.5726276
OS 2.2254996 2.5690913
OS 2.2317425 2.5678495
OS 2.2379854 2.5690913
OS 2.2432779 2.5726276
OS 2.2468142 2.5779201
OS 2.248056 2.584163
OS 2.2468142 2.5904059
OS 2.244337 2.5941133
OS 2.2476284 2.5981872
OS 2.2523425 2.5972495
OS 2.2585854 2.5984913
OS 2.2638779 2.6020276
OS 2.2674142 2.6073201
OS 2.268656 2.613563
OS 2.2674142 2.6198059
OS 2.2638779 2.6250984
OS 2.2585854 2.6286347
OS 2.2523425 2.6298765
OE
OB 2.8218425 2.6173765 H
OS 2.8155996 2.6161347
OS 2.8103071 2.6125984
OS 2.8067708 2.6073059
OS 2.805529 2.601063
OS 2.8067708 2.5948201
OS 2.8103071 2.5895276
OS 2.8155996 2.5859913
OS 2.8218425 2.5847495
OS 2.8280854 2.5859913
OS 2.8333779 2.5895276
OS 2.8369142 2.5948201
OS 2.838156 2.601063
OS 2.8369142 2.6073059
OS 2.8333779 2.6125984
OS 2.8280854 2.6161347
OS 2.8218425 2.6173765
OE
OB 3.6238425 2.6033765 H
OS 3.6175996 2.6021347
OS 3.6123071 2.5985984
OS 3.6087708 2.5933059
OS 3.607529 2.587063
OS 3.6087708 2.5808201
OS 3.6123071 2.5755276
OS 3.6175996 2.5719913
OS 3.6238425 2.5707495
OS 3.6300854 2.5719913
OS 3.6353779 2.5755276
OS 3.6389142 2.5808201
OS 3.640156 2.587063
OS 3.6389142 2.5933059
OS 3.6353779 2.5985984
OS 3.6300854 2.6021347
OS 3.6238425 2.6033765
OE
OB 4.2986248 2.6412356 H
OS 4.2867469 2.6396718
OS 4.2756785 2.6350872
OS 4.2661738 2.627794
OS 4.2588806 2.6182893
OS 4.254296 2.6072209
OS 4.2527322 2.595343
OS 4.254296 2.5834651
OS 4.2588806 2.5723967
OS 4.2661738 2.562892
OS 4.2756785 2.5555988
OS 4.2867469 2.5510142
OS 4.2986248 2.5494504
OS 4.3105027 2.5510142
OS 4.3215711 2.5555988
OS 4.3310758 2.562892
OS 4.338369 2.5723967
OS 4.3429536 2.5834651
OS 4.3445174 2.595343
OS 4.3429536 2.6072209
OS 4.338369 2.6182893
OS 4.3310758 2.627794
OS 4.3215711 2.6350872
OS 4.3105027 2.6396718
OS 4.2986248 2.6412356
OE
OB 4.1805146 2.6412356 H
OS 4.1686367 2.6396718
OS 4.1575683 2.6350872
OS 4.1480636 2.627794
OS 4.1407704 2.6182893
OS 4.1361858 2.6072209
OS 4.134622 2.595343
OS 4.1361858 2.5834651
OS 4.1407704 2.5723967
OS 4.1480636 2.562892
OS 4.1575683 2.5555988
OS 4.1686367 2.5510142
OS 4.1805146 2.5494504
OS 4.1923925 2.5510142
OS 4.2034609 2.5555988
OS 4.2129656 2.562892
OS 4.2202588 2.5723967
OS 4.2248434 2.5834651
OS 4.2264072 2.595343
OS 4.2248434 2.6072209
OS 4.2202588 2.6182893
OS 4.2129656 2.627794
OS 4.2034609 2.6350872
OS 4.1923925 2.6396718
OS 4.1805146 2.6412356
OE
OB 4.0624044 2.6412356 H
OS 4.0505265 2.6396718
OS 4.0394581 2.6350872
OS 4.0299534 2.627794
OS 4.0226602 2.6182893
OS 4.0180756 2.6072209
OS 4.0165118 2.595343
OS 4.0180756 2.5834651
OS 4.0226602 2.5723967
OS 4.0299534 2.562892
OS 4.0394581 2.5555988
OS 4.0505265 2.5510142
OS 4.0624044 2.5494504
OS 4.0742823 2.5510142
OS 4.0853507 2.5555988
OS 4.0948554 2.562892
OS 4.1021486 2.5723967
OS 4.1067332 2.5834651
OS 4.108297 2.595343
OS 4.1067332 2.6072209
OS 4.1021486 2.6182893
OS 4.0948554 2.627794
OS 4.0853507 2.6350872
OS 4.0742823 2.6396718
OS 4.0624044 2.6412356
OE
OB 6.2848425 2.5173765 H
OS 6.2785996 2.5161347
OS 6.2733071 2.5125984
OS 6.2697708 2.5073059
OS 6.268529 2.501063
OS 6.2697708 2.4948201
OS 6.2733071 2.4895276
OS 6.2785996 2.4859913
OS 6.2848425 2.4847495
OS 6.2910854 2.4859913
OS 6.2963779 2.4895276
OS 6.2999142 2.4948201
OS 6.301156 2.501063
OS 6.2999142 2.5073059
OS 6.2963779 2.5125984
OS 6.2910854 2.5161347
OS 6.2848425 2.5173765
OE
OB 1.0208425 2.4973765 H
OS 1.0145996 2.4961347
OS 1.0093071 2.4925984
OS 1.0057708 2.4873059
OS 1.004529 2.481063
OS 1.0057708 2.4748201
OS 1.0093071 2.4695276
OS 1.0145996 2.4659913
OS 1.0208425 2.4647495
OS 1.0270854 2.4659913
OS 1.0323779 2.4695276
OS 1.0359142 2.4748201
OS 1.037156 2.481063
OS 1.0359142 2.4873059
OS 1.0323779 2.4925984
OS 1.0270854 2.4961347
OS 1.0208425 2.4973765
OE
OB 2.6248425 2.4773765 H
OS 2.6185996 2.4761347
OS 2.6133071 2.4725984
OS 2.6097708 2.4673059
OS 2.608529 2.461063
OS 2.6097708 2.4548201
OS 2.6099331 2.4545773
OS 2.6063282 2.4509724
OS 2.6060854 2.4511347
OS 2.5998425 2.4523765
OS 2.5935996 2.4511347
OS 2.5883071 2.4475984
OS 2.5847708 2.4423059
OS 2.583529 2.436063
OS 2.5844621 2.4313719
OS 2.583986 2.4305231
OS 2.5813824 2.4279195
OS 2.5805336 2.4274434
OS 2.5758425 2.4283765
OS 2.5695996 2.4271347
OS 2.5643071 2.4235984
OS 2.5607708 2.4183059
OS 2.559529 2.412063
OS 2.5607708 2.4058201
OS 2.5643071 2.4005276
OS 2.5695996 2.3969913
OS 2.5758425 2.3957495
OS 2.5820854 2.3969913
OS 2.5873779 2.4005276
OS 2.5909142 2.4058201
OS 2.592156 2.412063
OS 2.5912229 2.4167541
OS 2.591699 2.4176029
OS 2.5943026 2.4202065
OS 2.5951514 2.4206826
OS 2.5998425 2.4197495
OS 2.6060854 2.4209913
OS 2.6113779 2.4245276
OS 2.6149142 2.4298201
OS 2.616156 2.436063
OS 2.6149142 2.4423059
OS 2.6147519 2.4425487
OS 2.6183568 2.4461536
OS 2.6185996 2.4459913
OS 2.6248425 2.4447495
OS 2.6310854 2.4459913
OS 2.6363779 2.4495276
OS 2.6399142 2.4548201
OS 2.641156 2.461063
OS 2.6399142 2.4673059
OS 2.6363779 2.4725984
OS 2.6310854 2.4761347
OS 2.6248425 2.4773765
OE
OB 2.2720325 2.4801865 H
OS 2.2657896 2.4789447
OS 2.2604971 2.4754084
OS 2.2569608 2.4701159
OS 2.255719 2.463873
OS 2.2569608 2.4576301
OS 2.2604971 2.4523376
OS 2.2657896 2.4488013
OS 2.2720325 2.4475595
OS 2.2782754 2.4488013
OS 2.2835679 2.4523376
OS 2.2871042 2.4576301
OS 2.288346 2.463873
OS 2.2871042 2.4701159
OS 2.2835679 2.4754084
OS 2.2782754 2.4789447
OS 2.2720325 2.4801865
OE
OB 2.5258425 2.4793765 H
OS 2.5195996 2.4781347
OS 2.5143071 2.4745984
OS 2.5107708 2.4693059
OS 2.509529 2.463063
OS 2.5107708 2.4568201
OS 2.5143071 2.4515276
OS 2.5195996 2.4479913
OS 2.5258425 2.4467495
OS 2.5320854 2.4479913
OS 2.5373779 2.4515276
OS 2.5409142 2.4568201
OS 2.542156 2.463063
OS 2.5409142 2.4693059
OS 2.5373779 2.4745984
OS 2.5320854 2.4781347
OS 2.5258425 2.4793765
OE
OB 5.5781524 2.5349364 H
OS 5.5662745 2.5333726
OS 5.5552061 2.528788
OS 5.5457014 2.5214948
OS 5.5384082 2.5119901
OS 5.5338236 2.5009217
OS 5.5322598 2.4890438
OS 5.5338236 2.4771659
OS 5.5384082 2.4660975
OS 5.5457014 2.4565928
OS 5.5552061 2.4492996
OS 5.5662745 2.444715
OS 5.5781524 2.4431512
OS 5.5900303 2.444715
OS 5.6010987 2.4492996
OS 5.6106034 2.4565928
OS 5.6178966 2.4660975
OS 5.6224812 2.4771659
OS 5.624045 2.4890438
OS 5.6224812 2.5009217
OS 5.6178966 2.5119901
OS 5.6106034 2.5214948
OS 5.6010987 2.528788
OS 5.5900303 2.5333726
OS 5.5781524 2.5349364
OE
OB 2.9488425 2.4723765 H
OS 2.9425996 2.4711347
OS 2.9373071 2.4675984
OS 2.9337708 2.4623059
OS 2.932529 2.456063
OS 2.9337708 2.4498201
OS 2.9373071 2.4445276
OS 2.9425996 2.4409913
OS 2.9488425 2.4397495
OS 2.9550854 2.4409913
OS 2.9603779 2.4445276
OS 2.9639142 2.4498201
OS 2.965156 2.456063
OS 2.9639142 2.4623059
OS 2.9603779 2.4675984
OS 2.9550854 2.4711347
OS 2.9488425 2.4723765
OE
OB 2.9905325 2.4577319 H
OS 2.9831854 2.4562705
OS 2.9769568 2.4521087
OS 2.972795 2.4458801
OS 2.9713336 2.438533
OS 2.972795 2.4311859
OS 2.9769568 2.4249573
OS 2.9831854 2.4207955
OS 2.9905325 2.4193341
OS 2.9978796 2.4207955
OS 3.0041082 2.4249573
OS 3.00827 2.4311859
OS 3.0097314 2.438533
OS 3.00827 2.4458801
OS 3.0041082 2.4521087
OS 2.9978796 2.4562705
OS 2.9905325 2.4577319
OE
OB 2.2031325 2.4577319 H
OS 2.1957854 2.4562705
OS 2.1895568 2.4521087
OS 2.185395 2.4458801
OS 2.1839336 2.438533
OS 2.185395 2.4311859
OS 2.1895568 2.4249573
OS 2.1957854 2.4207955
OS 2.2031325 2.4193341
OS 2.2104796 2.4207955
OS 2.2167082 2.4249573
OS 2.22087 2.4311859
OS 2.2223314 2.438533
OS 2.22087 2.4458801
OS 2.2167082 2.4521087
OS 2.2104796 2.4562705
OS 2.2031325 2.4577319
OE
OB 3.6179425 2.5536725 H
OS 3.6047974 2.5523778
OS 3.5921575 2.5485435
OS 3.5805085 2.542317
OS 3.570298 2.5339375
OS 3.5619185 2.523727
OS 3.555692 2.512078
OS 3.5518577 2.4994381
OS 3.550563 2.486293
OS 3.5518577 2.4731479
OS 3.555692 2.460508
OS 3.5619185 2.448859
OS 3.570298 2.4386485
OS 3.5805085 2.430269
OS 3.5921575 2.4240425
OS 3.6047974 2.4202082
OS 3.6179425 2.4189135
OS 3.6310876 2.4202082
OS 3.6437275 2.4240425
OS 3.6553765 2.430269
OS 3.665587 2.4386485
OS 3.6739665 2.448859
OS 3.680193 2.460508
OS 3.6840273 2.4731479
OS 3.685322 2.486293
OS 3.6840273 2.4994381
OS 3.680193 2.512078
OS 3.6739665 2.523727
OS 3.665587 2.5339375
OS 3.6553765 2.542317
OS 3.6437275 2.5485435
OS 3.6310876 2.5523778
OS 3.6179425 2.5536725
OE
OB 1.6519425 2.5536725 H
OS 1.6387974 2.5523778
OS 1.6261575 2.5485435
OS 1.6145085 2.542317
OS 1.604298 2.5339375
OS 1.5959185 2.523727
OS 1.589692 2.512078
OS 1.5858577 2.4994381
OS 1.584563 2.486293
OS 1.5858577 2.4731479
OS 1.589692 2.460508
OS 1.5959185 2.448859
OS 1.604298 2.4386485
OS 1.6145085 2.430269
OS 1.6261575 2.4240425
OS 1.6387974 2.4202082
OS 1.6519425 2.4189135
OS 1.6650876 2.4202082
OS 1.6777275 2.4240425
OS 1.6893765 2.430269
OS 1.699587 2.4386485
OS 1.7079665 2.448859
OS 1.714193 2.460508
OS 1.7180273 2.4731479
OS 1.719322 2.486293
OS 1.7180273 2.4994381
OS 1.714193 2.512078
OS 1.7079665 2.523727
OS 1.699587 2.5339375
OS 1.6893765 2.542317
OS 1.6777275 2.5485435
OS 1.6650876 2.5523778
OS 1.6519425 2.5536725
OE
OB 0.1998425 2.5453727 H
OS 0.1872963 2.544137
OS 0.1752322 2.5404774
OS 0.1641139 2.5345346
OS 0.1543687 2.5265368
OS 0.1463709 2.5167916
OS 0.1404281 2.5056733
OS 0.1367685 2.4936092
OS 0.1355328 2.481063
OS 0.1367685 2.4685168
OS 0.1404281 2.4564527
OS 0.1463709 2.4453344
OS 0.1543687 2.4355892
OS 0.1641139 2.4275914
OS 0.1752322 2.4216486
OS 0.1872963 2.417989
OS 0.1998425 2.4167533
OS 0.2123887 2.417989
OS 0.2244528 2.4216486
OS 0.2355711 2.4275914
OS 0.2453163 2.4355892
OS 0.2533141 2.4453344
OS 0.2592569 2.4564527
OS 0.2629165 2.4685168
OS 0.2641522 2.481063
OS 0.2629165 2.4936092
OS 0.2592569 2.5056733
OS 0.2533141 2.5167916
OS 0.2453163 2.5265368
OS 0.2355711 2.5345346
OS 0.2244528 2.5404774
OS 0.2123887 2.544137
OS 0.1998425 2.5453727
OE
OB 2.8948425 2.4473765 H
OS 2.8885996 2.4461347
OS 2.8833071 2.4425984
OS 2.8797708 2.4373059
OS 2.878529 2.431063
OS 2.8797708 2.4248201
OS 2.8833071 2.4195276
OS 2.8885996 2.4159913
OS 2.8948425 2.4147495
OS 2.9010854 2.4159913
OS 2.9063778 2.4195276
OS 2.9073026 2.4195276
OS 2.9093071 2.4165276
OS 2.9145996 2.4129913
OS 2.9208425 2.4117495
OS 2.9270854 2.4129913
OS 2.9323779 2.4165276
OS 2.9359142 2.4218201
OS 2.937156 2.428063
OS 2.9359142 2.4343059
OS 2.9323779 2.4395984
OS 2.9270854 2.4431347
OS 2.9208425 2.4443765
OS 2.9145996 2.4431347
OS 2.9093072 2.4395984
OS 2.9083824 2.4395984
OS 2.9063779 2.4425984
OS 2.9010854 2.4461347
OS 2.8948425 2.4473765
OE
OB 4.0398425 2.4223765 H
OS 4.0335996 2.4211347
OS 4.0283071 2.4175984
OS 4.0247708 2.4123059
OS 4.023529 2.406063
OS 4.0247708 2.3998201
OS 4.0283071 2.3945276
OS 4.0335996 2.3909913
OS 4.0398425 2.3897495
OS 4.0460854 2.3909913
OS 4.0513779 2.3945276
OS 4.0549142 2.3998201
OS 4.056156 2.406063
OS 4.0549142 2.4123059
OS 4.0513779 2.4175984
OS 4.0460854 2.4211347
OS 4.0398425 2.4223765
OE
OB 3.4988425 2.3573765 H
OS 3.4925996 2.3561347
OS 3.4873071 2.3525984
OS 3.4837708 2.3473059
OS 3.482529 2.341063
OS 3.4837708 2.3348201
OS 3.4873071 2.3295276
OS 3.4925996 2.3259913
OS 3.4988425 2.3247495
OS 3.5050854 2.3259913
OS 3.5103779 2.3295276
OS 3.5139142 2.3348201
OS 3.515156 2.341063
OS 3.5139142 2.3473059
OS 3.5103779 2.3525984
OS 3.5050854 2.3561347
OS 3.4988425 2.3573765
OE
OB 2.7268425 2.3093765 H
OS 2.7205996 2.3081347
OS 2.7153071 2.3045984
OS 2.7131725 2.3014038
OS 2.7090854 2.3041347
OS 2.7028425 2.3053765
OS 2.6965996 2.3041347
OS 2.6913071 2.3005984
OS 2.6877708 2.2953059
OS 2.6868962 2.2909101
OS 2.6821561 2.2910632
OS 2.6809142 2.2973059
OS 2.6773779 2.3025984
OS 2.6720854 2.3061347
OS 2.6658425 2.3073765
OS 2.6595996 2.3061347
OS 2.6543071 2.3025984
OS 2.6507708 2.2973059
OS 2.649529 2.2910631
OS 2.6483447 2.2898788
OS 2.6458425 2.2903765
OS 2.6395996 2.2891347
OS 2.6343071 2.2855984
OS 2.6307708 2.2803059
OS 2.629529 2.274063
OS 2.6307708 2.2678201
OS 2.6343071 2.2625276
OS 2.6395996 2.2589913
OS 2.6458425 2.2577495
OS 2.6520854 2.2589913
OS 2.6573779 2.2625276
OS 2.6609142 2.2678201
OS 2.662156 2.2740629
OS 2.6633403 2.2752472
OS 2.6658425 2.2747495
OS 2.6720854 2.2759913
OS 2.6773779 2.2795276
OS 2.6809142 2.2848201
OS 2.6817888 2.2892159
OS 2.6865289 2.2890628
OS 2.6877708 2.2828201
OS 2.6913071 2.2775276
OS 2.6965996 2.2739913
OS 2.7028425 2.2727495
OS 2.7090854 2.2739913
OS 2.7143779 2.2775276
OS 2.7165125 2.2807222
OS 2.7205996 2.2779913
OS 2.7268425 2.2767495
OS 2.7330854 2.2779913
OS 2.7383779 2.2815276
OS 2.7419142 2.2868201
OS 2.743156 2.293063
OS 2.7419142 2.2993059
OS 2.7383779 2.3045984
OS 2.7330854 2.3081347
OS 2.7268425 2.3093765
OE
OB 2.4758425 2.3073765 H
OS 2.4695996 2.3061347
OS 2.4643071 2.3025984
OS 2.4623321 2.2996425
OS 2.4575823 2.2973722
OS 2.4556938 2.2974115
OS 2.4508425 2.2983765
OS 2.4445996 2.2971347
OS 2.4393071 2.2935984
OS 2.4357708 2.2883059
OS 2.434529 2.282063
OS 2.4357708 2.2758201
OS 2.4393071 2.2705276
OS 2.4445996 2.2669913
OS 2.4508425 2.2657495
OS 2.4570854 2.2669913
OS 2.4623779 2.2705276
OS 2.4659142 2.27582
OS 2.4709912 2.2757145
OS 2.4758425 2.2747495
OS 2.4820854 2.2759913
OS 2.4873779 2.2795276
OS 2.4909142 2.2848201
OS 2.492156 2.291063
OS 2.4909142 2.2973059
OS 2.4873779 2.3025984
OS 2.4820854 2.3061347
OS 2.4758425 2.3073765
OE
OB 2.8038425 2.3233765 H
OS 2.7975996 2.3221347
OS 2.7923071 2.3185984
OS 2.7887708 2.3133059
OS 2.787529 2.307063
OS 2.7887708 2.3008201
OS 2.7923071 2.2955276
OS 2.7975996 2.2919913
OS 2.8038425 2.2907495
OS 2.8100854 2.2919913
OS 2.8153779 2.2955276
OS 2.8189142 2.3008201
OS 2.820156 2.307063
OS 2.8189142 2.3133059
OS 2.8153779 2.3185984
OS 2.8100854 2.3221347
OS 2.8038425 2.3233765
OE
OB 2.9858425 2.3033765 H
OS 2.9795996 2.3021347
OS 2.9743071 2.2985984
OS 2.9707708 2.2933059
OS 2.969529 2.287063
OS 2.9707708 2.2808201
OS 2.9743071 2.2755276
OS 2.9795996 2.2719913
OS 2.9858425 2.2707495
OS 2.9920854 2.2719913
OS 2.9973779 2.2755276
OS 3.0009142 2.2808201
OS 3.002156 2.287063
OS 3.0009142 2.2933059
OS 2.9973779 2.2985984
OS 2.9920854 2.3021347
OS 2.9858425 2.3033765
OE
OB 2.9428425 2.3023765 H
OS 2.9365996 2.3011347
OS 2.9313071 2.2975984
OS 2.9277708 2.2923059
OS 2.926529 2.286063
OS 2.9277708 2.2798201
OS 2.9313071 2.2745276
OS 2.9365996 2.2709913
OS 2.9428425 2.2697495
OS 2.9490854 2.2709913
OS 2.9543779 2.2745276
OS 2.9579142 2.2798201
OS 2.959156 2.286063
OS 2.9579142 2.2923059
OS 2.9543779 2.2975984
OS 2.9490854 2.3011347
OS 2.9428425 2.3023765
OE
OB 5.3277559 2.3463244 H
OS 5.3177023 2.3450008
OS 5.3083338 2.3411203
OS 5.300289 2.3349472
OS 5.2941159 2.3269023
OS 5.2902354 2.3175339
OS 5.2889118 2.3074803
OS 5.2902354 2.2974267
OS 5.2941159 2.2880583
OS 5.300289 2.2800134
OS 5.3083338 2.2738403
OS 5.3177023 2.2699598
OS 5.3277559 2.2686362
OS 5.3378095 2.2699598
OS 5.347178 2.2738403
OS 5.3552228 2.2800134
OS 5.3613959 2.2880583
OS 5.3652764 2.2974267
OS 5.3666 2.3074803
OS 5.3652764 2.3175339
OS 5.3613959 2.3269023
OS 5.3552228 2.3349472
OS 5.347178 2.3411203
OS 5.3378095 2.3450008
OS 5.3277559 2.3463244
OE
OB 4.9277559 2.3463244 H
OS 4.9177023 2.3450008
OS 4.9083338 2.3411203
OS 4.900289 2.3349472
OS 4.8941159 2.3269023
OS 4.8902354 2.3175339
OS 4.8889118 2.3074803
OS 4.8902354 2.2974267
OS 4.8941159 2.2880583
OS 4.900289 2.2800134
OS 4.9083338 2.2738403
OS 4.9177023 2.2699598
OS 4.9277559 2.2686362
OS 4.9378095 2.2699598
OS 4.947178 2.2738403
OS 4.9552228 2.2800134
OS 4.9613959 2.2880583
OS 4.9652764 2.2974267
OS 4.9666 2.3074803
OS 4.9652764 2.3175339
OS 4.9613959 2.3269023
OS 4.9552228 2.3349472
OS 4.947178 2.3411203
OS 4.9378095 2.3450008
OS 4.9277559 2.3463244
OE
OB 4.7277559 2.3463244 H
OS 4.7177023 2.3450008
OS 4.7083338 2.3411203
OS 4.700289 2.3349472
OS 4.6941159 2.3269023
OS 4.6902354 2.3175339
OS 4.6889118 2.3074803
OS 4.6902354 2.2974267
OS 4.6941159 2.2880583
OS 4.700289 2.2800134
OS 4.7083338 2.2738403
OS 4.7177023 2.2699598
OS 4.7277559 2.2686362
OS 4.7378095 2.2699598
OS 4.747178 2.2738403
OS 4.7552228 2.2800134
OS 4.7613959 2.2880583
OS 4.7652764 2.2974267
OS 4.7666 2.3074803
OS 4.7652764 2.3175339
OS 4.7613959 2.3269023
OS 4.7552228 2.3349472
OS 4.747178 2.3411203
OS 4.7378095 2.3450008
OS 4.7277559 2.3463244
OE
OB 4.3277559 2.3463244 H
OS 4.3177023 2.3450008
OS 4.3083338 2.3411203
OS 4.300289 2.3349472
OS 4.2941159 2.3269023
OS 4.2902354 2.3175339
OS 4.2889118 2.3074803
OS 4.2902354 2.2974267
OS 4.2941159 2.2880583
OS 4.300289 2.2800134
OS 4.3083338 2.2738403
OS 4.3177023 2.2699598
OS 4.3277559 2.2686362
OS 4.3378095 2.2699598
OS 4.347178 2.2738403
OS 4.3552228 2.2800134
OS 4.3613959 2.2880583
OS 4.3652764 2.2974267
OS 4.3666 2.3074803
OS 4.3652764 2.3175339
OS 4.3613959 2.3269023
OS 4.3552228 2.3349472
OS 4.347178 2.3411203
OS 4.3378095 2.3450008
OS 4.3277559 2.3463244
OE
OB 2.4098425 2.3303765 H
OS 2.4035996 2.3291347
OS 2.3983071 2.3255984
OS 2.3947708 2.3203059
OS 2.393529 2.314063
OS 2.3947708 2.3078201
OS 2.3983071 2.3025276
OS 2.3997406 2.3015697
OS 2.3997406 2.2955563
OS 2.3983071 2.2945984
OS 2.3947708 2.2893059
OS 2.393529 2.283063
OS 2.3947708 2.2768201
OS 2.3983071 2.2715276
OS 2.4035996 2.2679913
OS 2.4098425 2.2667495
OS 2.4160854 2.2679913
OS 2.4213779 2.2715276
OS 2.4249142 2.2768201
OS 2.426156 2.283063
OS 2.4249142 2.2893059
OS 2.4213779 2.2945984
OS 2.4199444 2.2955563
OS 2.4199444 2.3015697
OS 2.4213779 2.3025276
OS 2.4249142 2.3078201
OS 2.426156 2.314063
OS 2.4249142 2.3203059
OS 2.4213779 2.3255984
OS 2.4160854 2.3291347
OS 2.4098425 2.3303765
OE
OB 2.5798425 2.2973765 H
OS 2.5735996 2.2961347
OS 2.5683071 2.2925984
OS 2.5647708 2.2873059
OS 2.563529 2.281063
OS 2.5647708 2.2748201
OS 2.5683071 2.2695276
OS 2.5735996 2.2659913
OS 2.5798425 2.2647495
OS 2.5860854 2.2659913
OS 2.5913779 2.2695276
OS 2.5949142 2.2748201
OS 2.596156 2.281063
OS 2.5949142 2.2873059
OS 2.5913779 2.2925984
OS 2.5860854 2.2961347
OS 2.5798425 2.2973765
OE
OB 3.3428425 2.2793765 H
OS 3.3365996 2.2781347
OS 3.3313071 2.2745984
OS 3.3277708 2.2693059
OS 3.326529 2.263063
OS 3.3277708 2.2568201
OS 3.3313071 2.2515276
OS 3.3365996 2.2479913
OS 3.3428425 2.2467495
OS 3.3490854 2.2479913
OS 3.3543779 2.2515276
OS 3.3579142 2.2568201
OS 3.359156 2.263063
OS 3.3579142 2.2693059
OS 3.3543779 2.2745984
OS 3.3490854 2.2781347
OS 3.3428425 2.2793765
OE
OB 2.8418425 2.2793765 H
OS 2.8355996 2.2781347
OS 2.8303071 2.2745984
OS 2.8267708 2.2693059
OS 2.825529 2.263063
OS 2.8267708 2.2568201
OS 2.8303071 2.2515276
OS 2.8355996 2.2479913
OS 2.8418425 2.2467495
OS 2.8480854 2.2479913
OS 2.8533779 2.2515276
OS 2.8569142 2.2568201
OS 2.858156 2.263063
OS 2.8569142 2.2693059
OS 2.8533779 2.2745984
OS 2.8480854 2.2781347
OS 2.8418425 2.2793765
OE
OB 0.9968357 2.2723495 H
OS 0.9905928 2.2711077
OS 0.9853003 2.2675714
OS 0.981764 2.2622789
OS 0.9805222 2.256036
OS 0.981764 2.2497931
OS 0.9853003 2.2445006
OS 0.9905928 2.2409643
OS 0.9968357 2.2397225
OS 1.0030786 2.2409643
OS 1.0083711 2.2445006
OS 1.0119074 2.2497931
OS 1.0131492 2.256036
OS 1.0119074 2.2622789
OS 1.0083711 2.2675714
OS 1.0030786 2.2711077
OS 0.9968357 2.2723495
OE
OB 5.6348425 2.2523765 H
OS 5.6285996 2.2511347
OS 5.6233071 2.2475984
OS 5.6197708 2.2423059
OS 5.618529 2.236063
OS 5.6197708 2.2298201
OS 5.6233071 2.2245276
OS 5.6285996 2.2209913
OS 5.6348425 2.2197495
OS 5.6410854 2.2209913
OS 5.6463779 2.2245276
OS 5.6499142 2.2298201
OS 5.651156 2.236063
OS 5.6499142 2.2423059
OS 5.6463779 2.2475984
OS 5.6410854 2.2511347
OS 5.6348425 2.2523765
OE
OB 2.4998425 2.2523765 H
OS 2.4935996 2.2511347
OS 2.4883071 2.2475984
OS 2.4847708 2.2423059
OS 2.483529 2.236063
OS 2.4847708 2.2298201
OS 2.4883071 2.2245276
OS 2.4935996 2.2209913
OS 2.4998425 2.2197495
OS 2.5060854 2.2209913
OS 2.5113779 2.2245276
OS 2.5149142 2.2298201
OS 2.516156 2.236063
OS 2.5149142 2.2423059
OS 2.5113779 2.2475984
OS 2.5060854 2.2511347
OS 2.4998425 2.2523765
OE
OB 2.3308425 2.2313765 H
OS 2.3245996 2.2301347
OS 2.3193071 2.2265984
OS 2.3157708 2.2213059
OS 2.314529 2.215063
OS 2.3157708 2.2088201
OS 2.3193071 2.2035276
OS 2.3245996 2.1999913
OS 2.3308425 2.1987495
OS 2.3370854 2.1999913
OS 2.3423779 2.2035276
OS 2.3459142 2.2088201
OS 2.347156 2.215063
OS 2.3459142 2.2213059
OS 2.3423779 2.2265984
OS 2.3370854 2.2301347
OS 2.3308425 2.2313765
OE
OB 5.5778425 2.2303765 H
OS 5.5715996 2.2291347
OS 5.5663071 2.2255984
OS 5.5627708 2.2203059
OS 5.561529 2.214063
OS 5.5627708 2.2078201
OS 5.5663071 2.2025276
OS 5.5715996 2.1989913
OS 5.5778425 2.1977495
OS 5.5840854 2.1989913
OS 5.5893779 2.2025276
OS 5.5929142 2.2078201
OS 5.594156 2.214063
OS 5.5929142 2.2203059
OS 5.5893779 2.2255984
OS 5.5840854 2.2291347
OS 5.5778425 2.2303765
OE
OB 6.4248425 2.1973765 H
OS 6.4185996 2.1961347
OS 6.4133071 2.1925984
OS 6.4097708 2.1873059
OS 6.408529 2.181063
OS 6.4097708 2.1748201
OS 6.4133071 2.1695276
OS 6.4185996 2.1659913
OS 6.4248425 2.1647495
OS 6.4310854 2.1659913
OS 6.4363779 2.1695276
OS 6.4399142 2.1748201
OS 6.441156 2.181063
OS 6.4399142 2.1873059
OS 6.4363779 2.1925984
OS 6.4310854 2.1961347
OS 6.4248425 2.1973765
OE
OB 1.7548425 2.1423765 H
OS 1.7485996 2.1411347
OS 1.7433071 2.1375984
OS 1.7397708 2.1323059
OS 1.738529 2.126063
OS 1.7397708 2.1198201
OS 1.7433071 2.1145276
OS 1.7485996 2.1109913
OS 1.7548425 2.1097495
OS 1.7610854 2.1109913
OS 1.7663779 2.1145276
OS 1.7699142 2.1198201
OS 1.771156 2.126063
OS 1.7699142 2.1323059
OS 1.7663779 2.1375984
OS 1.7610854 2.1411347
OS 1.7548425 2.1423765
OE
OB 1.6198425 2.1373765 H
OS 1.6135996 2.1361347
OS 1.6083071 2.1325984
OS 1.6047708 2.1273059
OS 1.603529 2.121063
OS 1.6047708 2.1148201
OS 1.6083071 2.1095276
OS 1.6135996 2.1059913
OS 1.6198425 2.1047495
OS 1.6260854 2.1059913
OS 1.6313779 2.1095276
OS 1.6349142 2.1148201
OS 1.636156 2.121063
OS 1.6349142 2.1273059
OS 1.6313779 2.1325984
OS 1.6260854 2.1361347
OS 1.6198425 2.1373765
OE
OB 1.6968325 2.1164319 H
OS 1.6894854 2.1149705
OS 1.6832568 2.1108087
OS 1.679095 2.1045801
OS 1.6776336 2.097233
OS 1.679095 2.0898859
OS 1.6832568 2.0836573
OS 1.6894854 2.0794955
OS 1.6968325 2.0780341
OS 1.7041796 2.0794955
OS 1.7104082 2.0836573
OS 1.71457 2.0898859
OS 1.7160314 2.097233
OS 1.71457 2.1045801
OS 1.7104082 2.1108087
OS 1.7041796 2.1149705
OS 1.6968325 2.1164319
OE
OB 1.8848425 2.0873765 H
OS 1.8785996 2.0861347
OS 1.8733071 2.0825984
OS 1.8697708 2.0773059
OS 1.868529 2.071063
OS 1.8697708 2.0648201
OS 1.8733071 2.0595276
OS 1.8785996 2.0559913
OS 1.8848425 2.0547495
OS 1.8910854 2.0559913
OS 1.8963779 2.0595276
OS 1.8999142 2.0648201
OS 1.901156 2.071063
OS 1.8999142 2.0773059
OS 1.8963779 2.0825984
OS 1.8910854 2.0861347
OS 1.8848425 2.0873765
OE
OB 1.5682025 2.0840165 H
OS 1.5619596 2.0827747
OS 1.5566671 2.0792384
OS 1.5531308 2.0739459
OS 1.551889 2.067703
OS 1.5531308 2.0614601
OS 1.5566671 2.0561676
OS 1.5619596 2.0526313
OS 1.5682025 2.0513895
OS 1.5744454 2.0526313
OS 1.5797379 2.0561676
OS 1.5832742 2.0614601
OS 1.584516 2.067703
OS 1.5832742 2.0739459
OS 1.5797379 2.0792384
OS 1.5744454 2.0827747
OS 1.5682025 2.0840165
OE
OB 3.5717425 2.1163919 H
OS 3.5643954 2.1149305
OS 3.5581668 2.1107687
OS 3.554005 2.1045401
OS 3.5525436 2.097193
OS 3.554005 2.0898459
OS 3.5581668 2.0836173
OS 3.5643954 2.0794555
OS 3.5680713 2.0787243
OS 3.5680713 2.0736264
OS 3.5655996 2.0731347
OS 3.5603071 2.0695984
OS 3.5567708 2.0643059
OS 3.555529 2.058063
OS 3.5567708 2.0518201
OS 3.5584204 2.0493513
OS 3.5599241 2.045563
OS 3.5584204 2.0417747
OS 3.5567708 2.0393059
OS 3.555529 2.033063
OS 3.5567708 2.0268201
OS 3.5603071 2.0215276
OS 3.5655996 2.0179913
OS 3.5718425 2.0167495
OS 3.5780854 2.0179913
OS 3.5833779 2.0215276
OS 3.5869142 2.0268201
OS 3.588156 2.033063
OS 3.5869142 2.0393059
OS 3.5852646 2.0417747
OS 3.5837609 2.045563
OS 3.5852646 2.0493513
OS 3.5869142 2.0518201
OS 3.588156 2.058063
OS 3.5869142 2.0643059
OS 3.5833779 2.0695984
OS 3.5780854 2.0731347
OS 3.5755137 2.0736462
OS 3.5755137 2.0787442
OS 3.5790896 2.0794555
OS 3.5853182 2.0836173
OS 3.58948 2.0898459
OS 3.5909414 2.097193
OS 3.58948 2.1045401
OS 3.5853182 2.1107687
OS 3.5790896 2.1149305
OS 3.5717425 2.1163919
OE
OB 2.4098425 1.9833765 H
OS 2.4035996 1.9821347
OS 2.3983071 1.9785984
OS 2.3947708 1.9733059
OS 2.393529 1.967063
OS 2.3947708 1.9608201
OS 2.3961401 1.9587707
OS 2.3925353 1.9551659
OS 2.3910854 1.9561347
OS 2.3848425 1.9573765
OS 2.3785996 1.9561347
OS 2.3733071 1.9525984
OS 2.3697708 1.9473059
OS 2.368529 1.941063
OS 2.3697708 1.9348201
OS 2.3733071 1.9295276
OS 2.3785996 1.9259913
OS 2.3848425 1.9247495
OS 2.3910854 1.9259913
OS 2.3963779 1.9295276
OS 2.3999142 1.9348201
OS 2.401156 1.941063
OS 2.3999142 1.9473059
OS 2.3985449 1.9493553
OS 2.4021497 1.9529601
OS 2.4035996 1.9519913
OS 2.4098425 1.9507495
OS 2.4160854 1.9519913
OS 2.4213779 1.9555276
OS 2.4249142 1.9608201
OS 2.426156 1.967063
OS 2.4249142 1.9733059
OS 2.4213779 1.9785984
OS 2.4160854 1.9821347
OS 2.4098425 1.9833765
OE
OB 3.2988425 1.9873765 H
OS 3.2925996 1.9861347
OS 3.2873071 1.9825984
OS 3.2837708 1.9773059
OS 3.282529 1.971063
OS 3.2837708 1.9648201
OS 3.2873071 1.9595276
OS 3.2925996 1.9559913
OS 3.2988425 1.9547495
OS 3.3050854 1.9559913
OS 3.3103779 1.9595276
OS 3.3139142 1.9648201
OS 3.315156 1.971063
OS 3.3139142 1.9773059
OS 3.3103779 1.9825984
OS 3.3050854 1.9861347
OS 3.2988425 1.9873765
OE
OB 1.0098425 1.9723765 H
OS 1.0035996 1.9711347
OS 0.9983071 1.9675984
OS 0.9947708 1.9623059
OS 0.993529 1.956063
OS 0.9947708 1.9498201
OS 0.9983071 1.9445276
OS 1.0035996 1.9409913
OS 1.0098425 1.9397495
OS 1.0160854 1.9409913
OS 1.0213779 1.9445276
OS 1.0249142 1.9498201
OS 1.026156 1.956063
OS 1.0249142 1.9623059
OS 1.0213779 1.9675984
OS 1.0160854 1.9711347
OS 1.0098425 1.9723765
OE
OB 2.2998425 1.9323765 H
OS 2.2935996 1.9311347
OS 2.2883071 1.9275984
OS 2.2847708 1.9223059
OS 2.283529 1.916063
OS 2.2847708 1.9098201
OS 2.2883071 1.9045276
OS 2.2935996 1.9009913
OS 2.2998425 1.8997495
OS 2.3060854 1.9009913
OS 2.3113779 1.9045276
OS 2.3149142 1.9098201
OS 2.316156 1.916063
OS 2.3149142 1.9223059
OS 2.3113779 1.9275984
OS 2.3060854 1.9311347
OS 2.2998425 1.9323765
OE
OB 0.1998425 2.0203727 H
OS 0.1872963 2.019137
OS 0.1752322 2.0154774
OS 0.1641139 2.0095346
OS 0.1543687 2.0015368
OS 0.1463709 1.9917916
OS 0.1404281 1.9806733
OS 0.1367685 1.9686092
OS 0.1355328 1.956063
OS 0.1367685 1.9435168
OS 0.1404281 1.9314527
OS 0.1463709 1.9203344
OS 0.1543687 1.9105892
OS 0.1641139 1.9025914
OS 0.1752322 1.8966486
OS 0.1872963 1.892989
OS 0.1998425 1.8917533
OS 0.2123887 1.892989
OS 0.2244528 1.8966486
OS 0.2355711 1.9025914
OS 0.2453163 1.9105892
OS 0.2533141 1.9203344
OS 0.2592569 1.9314527
OS 0.2629165 1.9435168
OS 0.2641522 1.956063
OS 0.2629165 1.9686092
OS 0.2592569 1.9806733
OS 0.2533141 1.9917916
OS 0.2453163 2.0015368
OS 0.2355711 2.0095346
OS 0.2244528 2.0154774
OS 0.2123887 2.019137
OS 0.1998425 2.0203727
OE
OB 3.5548425 1.9073765 H
OS 3.5485996 1.9061347
OS 3.5433071 1.9025984
OS 3.5397708 1.8973059
OS 3.538529 1.891063
OS 3.5397708 1.8848201
OS 3.5433071 1.8795276
OS 3.5485996 1.8759913
OS 3.5548425 1.8747495
OS 3.5610854 1.8759913
OS 3.5663779 1.8795276
OS 3.5699142 1.8848201
OS 3.571156 1.891063
OS 3.5699142 1.8973059
OS 3.5663779 1.9025984
OS 3.5610854 1.9061347
OS 3.5548425 1.9073765
OE
OB 3.3928425 1.8873765 H
OS 3.3865996 1.8861347
OS 3.3813071 1.8825984
OS 3.3777708 1.8773059
OS 3.376529 1.871063
OS 3.3777708 1.8648201
OS 3.3813071 1.8595276
OS 3.3865996 1.8559913
OS 3.3928425 1.8547495
OS 3.3990854 1.8559913
OS 3.4043779 1.8595276
OS 3.4079142 1.8648201
OS 3.409156 1.871063
OS 3.4079142 1.8773059
OS 3.4043779 1.8825984
OS 3.3990854 1.8861347
OS 3.3928425 1.8873765
OE
OB 3.4392507 1.8872515 H
OS 3.4330078 1.8860097
OS 3.4277153 1.8824734
OS 3.424179 1.8771809
OS 3.4229372 1.870938
OS 3.424179 1.8646951
OS 3.4277153 1.8594026
OS 3.4330078 1.8558663
OS 3.4392507 1.8546245
OS 3.4454936 1.8558663
OS 3.4507861 1.8594026
OS 3.4543224 1.8646951
OS 3.4555642 1.870938
OS 3.4543224 1.8771809
OS 3.4507861 1.8824734
OS 3.4454936 1.8860097
OS 3.4392507 1.8872515
OE
OB 3.8048425 1.8563765 H
OS 3.7985996 1.8551347
OS 3.7933071 1.8515984
OS 3.7897708 1.8463059
OS 3.788529 1.840063
OS 3.7897708 1.8338201
OS 3.7933071 1.8285276
OS 3.7985996 1.8249913
OS 3.8048425 1.8237495
OS 3.8110854 1.8249913
OS 3.8163779 1.8285276
OS 3.8199142 1.8338201
OS 3.821156 1.840063
OS 3.8199142 1.8463059
OS 3.8163779 1.8515984
OS 3.8110854 1.8551347
OS 3.8048425 1.8563765
OE
OB 3.3291721 1.8423765 H
OS 3.3229292 1.8411347
OS 3.3176367 1.8375984
OS 3.3141004 1.8323059
OS 3.3128586 1.826063
OS 3.3141004 1.8198201
OS 3.3176367 1.8145276
OS 3.3229292 1.8109913
OS 3.3291721 1.8097495
OS 3.335415 1.8109913
OS 3.3407075 1.8145276
OS 3.3442438 1.8198201
OS 3.3454856 1.826063
OS 3.3442438 1.8323059
OS 3.3407075 1.8375984
OS 3.335415 1.8411347
OS 3.3291721 1.8423765
OE
OB 1.3937008 1.8332426 H
OS 1.3874579 1.8320008
OS 1.3821654 1.8284645
OS 1.3786291 1.823172
OS 1.3773873 1.8169291
OS 1.3786291 1.8106862
OS 1.3821654 1.8053937
OS 1.3874579 1.8018574
OS 1.3937008 1.8006156
OS 1.3999437 1.8018574
OS 1.4052362 1.8053937
OS 1.4087725 1.8106862
OS 1.4100143 1.8169291
OS 1.4087725 1.823172
OS 1.4052362 1.8284645
OS 1.3999437 1.8320008
OS 1.3937008 1.8332426
OE
OB 3.9448425 1.8323765 H
OS 3.9385996 1.8311347
OS 3.9333071 1.8275984
OS 3.9297708 1.8223059
OS 3.928529 1.816063
OS 3.9297708 1.8098201
OS 3.9333071 1.8045276
OS 3.9385996 1.8009913
OS 3.9448425 1.7997495
OS 3.9510854 1.8009913
OS 3.9563779 1.8045276
OS 3.9599142 1.8098201
OS 3.961156 1.816063
OS 3.9599142 1.8223059
OS 3.9563779 1.8275984
OS 3.9510854 1.8311347
OS 3.9448425 1.8323765
OE
OB 3.0568817 1.8281165 H
OS 3.0506388 1.8268747
OS 3.0453463 1.8233384
OS 3.04181 1.8180459
OS 3.0405682 1.811803
OS 3.04181 1.8055601
OS 3.0453463 1.8002676
OS 3.0506388 1.7967313
OS 3.0568817 1.7954895
OS 3.0631246 1.7967313
OS 3.0684171 1.8002676
OS 3.0719534 1.8055601
OS 3.0731952 1.811803
OS 3.0719534 1.8180459
OS 3.0684171 1.8233384
OS 3.0631246 1.8268747
OS 3.0568817 1.8281165
OE
OB 1.8799377 1.8281165 H
OS 1.8736948 1.8268747
OS 1.8684023 1.8233384
OS 1.864866 1.8180459
OS 1.8636242 1.811803
OS 1.864866 1.8055601
OS 1.8684023 1.8002676
OS 1.8736948 1.7967313
OS 1.8799377 1.7954895
OS 1.8861806 1.7967313
OS 1.8914731 1.8002676
OS 1.8950094 1.8055601
OS 1.8962512 1.811803
OS 1.8950094 1.8180459
OS 1.8914731 1.8233384
OS 1.8861806 1.8268747
OS 1.8799377 1.8281165
OE
OB 4.0648425 1.8123765 H
OS 4.0585996 1.8111347
OS 4.0533071 1.8075984
OS 4.0497708 1.8023059
OS 4.048529 1.796063
OS 4.0497708 1.7898201
OS 4.0533071 1.7845276
OS 4.0585996 1.7809913
OS 4.0648425 1.7797495
OS 4.0710854 1.7809913
OS 4.0763779 1.7845276
OS 4.0799142 1.7898201
OS 4.081156 1.796063
OS 4.0799142 1.8023059
OS 4.0763779 1.8075984
OS 4.0710854 1.8111347
OS 4.0648425 1.8123765
OE
OB 2.5798425 1.8063765 H
OS 2.5735996 1.8051347
OS 2.5683071 1.8015984
OS 2.5647708 1.7963059
OS 2.563529 1.790063
OS 2.5647708 1.7838201
OS 2.5683071 1.7785276
OS 2.5735996 1.7749913
OS 2.5798425 1.7737495
OS 2.5860854 1.7749913
OS 2.5913779 1.7785276
OS 2.5949142 1.7838201
OS 2.596156 1.790063
OS 2.5949142 1.7963059
OS 2.5913779 1.8015984
OS 2.5860854 1.8051347
OS 2.5798425 1.8063765
OE
OB 2.6268425 1.7863765 H
OS 2.6205996 1.7851347
OS 2.6153071 1.7815984
OS 2.6117708 1.7763059
OS 2.610529 1.770063
OS 2.6117708 1.7638201
OS 2.6153071 1.7585276
OS 2.6205996 1.7549913
OS 2.6268425 1.7537495
OS 2.6330854 1.7549913
OS 2.6383779 1.7585276
OS 2.6419142 1.7638201
OS 2.643156 1.770063
OS 2.6419142 1.7763059
OS 2.6383779 1.7815984
OS 2.6330854 1.7851347
OS 2.6268425 1.7863765
OE
OB 3.7198425 1.7823765 H
OS 3.7135996 1.7811347
OS 3.7083071 1.7775984
OS 3.7047708 1.7723059
OS 3.703529 1.766063
OS 3.7047708 1.7598201
OS 3.7083071 1.7545276
OS 3.7135996 1.7509913
OS 3.7198425 1.7497495
OS 3.7260854 1.7509913
OS 3.7313779 1.7545276
OS 3.7349142 1.7598201
OS 3.736156 1.766063
OS 3.7349142 1.7723059
OS 3.7313779 1.7775984
OS 3.7260854 1.7811347
OS 3.7198425 1.7823765
OE
OB 2.5498425 1.7713765 H
OS 2.5435996 1.7701347
OS 2.5383071 1.7665984
OS 2.5347708 1.7613059
OS 2.533529 1.755063
OS 2.5347708 1.7488201
OS 2.5383071 1.7435276
OS 2.5435996 1.7399913
OS 2.5498425 1.7387495
OS 2.5560854 1.7399913
OS 2.5613779 1.7435276
OS 2.5649142 1.7488201
OS 2.566156 1.755063
OS 2.5649142 1.7613059
OS 2.5613779 1.7665984
OS 2.5560854 1.7701347
OS 2.5498425 1.7713765
OE
OB 4.1348425 1.7673765 H
OS 4.1285996 1.7661347
OS 4.1233071 1.7625984
OS 4.1197708 1.7573059
OS 4.118529 1.751063
OS 4.1197708 1.7448201
OS 4.1233071 1.7395276
OS 4.1285996 1.7359913
OS 4.1348425 1.7347495
OS 4.1410854 1.7359913
OS 4.1463779 1.7395276
OS 4.1499142 1.7448201
OS 4.151156 1.751063
OS 4.1499142 1.7573059
OS 4.1463779 1.7625984
OS 4.1410854 1.7661347
OS 4.1348425 1.7673765
OE
OB 2.6048425 1.7503765 H
OS 2.5985996 1.7491347
OS 2.5933071 1.7455984
OS 2.5897708 1.7403059
OS 2.588529 1.734063
OS 2.5897708 1.7278201
OS 2.5933071 1.7225276
OS 2.5985996 1.7189913
OS 2.6048425 1.7177495
OS 2.6110854 1.7189913
OS 2.6163779 1.7225276
OS 2.6199142 1.7278201
OS 2.621156 1.734063
OS 2.6199142 1.7403059
OS 2.6163779 1.7455984
OS 2.6110854 1.7491347
OS 2.6048425 1.7503765
OE
OB 0.988189 1.7338332 H
OS 0.9819461 1.7325914
OS 0.9766536 1.7290551
OS 0.9731173 1.7237626
OS 0.9718755 1.7175197
OS 0.9731173 1.7112768
OS 0.9766536 1.7059843
OS 0.9819461 1.702448
OS 0.988189 1.7012062
OS 0.9944319 1.702448
OS 0.9997244 1.7059843
OS 1.0032607 1.7112768
OS 1.0045025 1.7175197
OS 1.0032607 1.7237626
OS 0.9997244 1.7290551
OS 0.9944319 1.7325914
OS 0.988189 1.7338332
OE
OB 3.1972633 1.7303765 H
OS 3.1910204 1.7291347
OS 3.1857279 1.7255984
OS 3.1821916 1.7203059
OS 3.1809498 1.714063
OS 3.1821916 1.7078201
OS 3.1857279 1.7025276
OS 3.1910204 1.6989913
OS 3.1972633 1.6977495
OS 3.2035062 1.6989913
OS 3.2087987 1.7025276
OS 3.212335 1.7078201
OS 3.2135768 1.714063
OS 3.212335 1.7203059
OS 3.2087987 1.7255984
OS 3.2035062 1.7291347
OS 3.1972633 1.7303765
OE
OB 3.5898425 1.7273765 H
OS 3.5835996 1.7261347
OS 3.5783071 1.7225984
OS 3.5747708 1.7173059
OS 3.573529 1.711063
OS 3.5747708 1.7048201
OS 3.5783071 1.6995276
OS 3.5835996 1.6959913
OS 3.5898425 1.6947495
OS 3.5960854 1.6959913
OS 3.6013779 1.6995276
OS 3.6049142 1.7048201
OS 3.606156 1.711063
OS 3.6049142 1.7173059
OS 3.6013779 1.7225984
OS 3.5960854 1.7261347
OS 3.5898425 1.7273765
OE
OB 1.8938425 1.7093765 H
OS 1.8875996 1.7081347
OS 1.8823071 1.7045984
OS 1.8787708 1.6993059
OS 1.877529 1.693063
OS 1.8787708 1.6868201
OS 1.8823071 1.6815276
OS 1.8875996 1.6779913
OS 1.8938425 1.6767495
OS 1.9000854 1.6779913
OS 1.9053779 1.6815276
OS 1.9089142 1.6868201
OS 1.910156 1.693063
OS 1.9089142 1.6993059
OS 1.9053779 1.7045984
OS 1.9000854 1.7081347
OS 1.8938425 1.7093765
OE
OB 3.8038425 1.7073765 H
OS 3.7975996 1.7061347
OS 3.7923071 1.7025984
OS 3.7887708 1.6973059
OS 3.787529 1.691063
OS 3.7887708 1.6848201
OS 3.7923071 1.6795276
OS 3.7975996 1.6759913
OS 3.8038425 1.6747495
OS 3.8100854 1.6759913
OS 3.8153779 1.6795276
OS 3.8189142 1.6848201
OS 3.820156 1.691063
OS 3.8189142 1.6973059
OS 3.8153779 1.7025984
OS 3.8100854 1.7061347
OS 3.8038425 1.7073765
OE
OB 3.7248425 1.6913765 H
OS 3.7185996 1.6901347
OS 3.7133071 1.6865984
OS 3.7097708 1.6813059
OS 3.708529 1.675063
OS 3.7097708 1.6688201
OS 3.7133071 1.6635276
OS 3.7185996 1.6599913
OS 3.7248425 1.6587495
OS 3.7310854 1.6599913
OS 3.7363779 1.6635276
OS 3.7399142 1.6688201
OS 3.741156 1.675063
OS 3.7399142 1.6813059
OS 3.7363779 1.6865984
OS 3.7310854 1.6901347
OS 3.7248425 1.6913765
OE
OB 1.8227825 1.6903165 H
OS 1.8165396 1.6890747
OS 1.8112471 1.6855384
OS 1.8077108 1.6802459
OS 1.806469 1.674003
OS 1.8077108 1.6677601
OS 1.8112471 1.6624676
OS 1.8165396 1.6589313
OS 1.8227825 1.6576895
OS 1.8290254 1.6589313
OS 1.8343179 1.6624676
OS 1.8378542 1.6677601
OS 1.839096 1.674003
OS 1.8378542 1.6802459
OS 1.8343179 1.6855384
OS 1.8290254 1.6890747
OS 1.8227825 1.6903165
OE
OB 3.7738632 1.6824156 H
OS 3.7676203 1.6811738
OS 3.7623278 1.6776375
OS 3.7587915 1.672345
OS 3.7575497 1.6661021
OS 3.7587915 1.6598592
OS 3.7623278 1.6545667
OS 3.7676203 1.6510304
OS 3.7738632 1.6497886
OS 3.7801061 1.6510304
OS 3.7853986 1.6545667
OS 3.7889349 1.6598592
OS 3.7901767 1.6661021
OS 3.7889349 1.672345
OS 3.7853986 1.6776375
OS 3.7801061 1.6811738
OS 3.7738632 1.6824156
OE
OB 6.8448425 1.6773765 H
OS 6.8385996 1.6761347
OS 6.8333071 1.6725984
OS 6.8297708 1.6673059
OS 6.828529 1.661063
OS 6.8297708 1.6548201
OS 6.8333071 1.6495276
OS 6.8385996 1.6459913
OS 6.8448425 1.6447495
OS 6.8510854 1.6459913
OS 6.8563779 1.6495276
OS 6.8599142 1.6548201
OS 6.861156 1.661063
OS 6.8599142 1.6673059
OS 6.8563779 1.6725984
OS 6.8510854 1.6761347
OS 6.8448425 1.6773765
OE
OB 3.2248425 1.6776607 H
OS 3.2185996 1.6764189
OS 3.2133071 1.6728826
OS 3.2097708 1.6675901
OS 3.208529 1.6613472
OS 3.2097708 1.6551043
OS 3.2133071 1.6498118
OS 3.2185996 1.6462755
OS 3.2248425 1.6450337
OS 3.2310854 1.6462755
OS 3.235497 1.6492232
OS 3.2395781 1.6496996
OS 3.2419254 1.6491144
OS 3.2465996 1.6459913
OS 3.2528425 1.6447495
OS 3.2590854 1.6459913
OS 3.2643779 1.6495276
OS 3.2679142 1.6548201
OS 3.269156 1.661063
OS 3.2679142 1.6673059
OS 3.2643779 1.6725984
OS 3.2590854 1.6761347
OS 3.2528425 1.6773765
OS 3.2465996 1.6761347
OS 3.242188 1.673187
OS 3.2381069 1.6727106
OS 3.2357596 1.6732958
OS 3.2310854 1.6764189
OS 3.2248425 1.6776607
OE
OB 2.6668425 1.6563765 H
OS 2.6605996 1.6551347
OS 2.6553071 1.6515984
OS 2.6517708 1.6463059
OS 2.650529 1.640063
OS 2.6513707 1.6358317
OS 2.6479104 1.6318625
OS 2.6474924 1.6316505
OS 2.6438425 1.6323765
OS 2.6375996 1.6311347
OS 2.6323071 1.6275984
OS 2.6287708 1.6223059
OS 2.627529 1.616063
OS 2.6287708 1.6098201
OS 2.6323071 1.6045276
OS 2.6375996 1.6009913
OS 2.6438425 1.5997495
OS 2.6500854 1.6009913
OS 2.6553779 1.6045276
OS 2.6589142 1.6098201
OS 2.660156 1.616063
OS 2.6593143 1.6202943
OS 2.6627746 1.6242635
OS 2.6631926 1.6244755
OS 2.6668425 1.6237495
OS 2.6730854 1.6249913
OS 2.6783779 1.6285276
OS 2.6819142 1.6338201
OS 2.683156 1.640063
OS 2.6819142 1.6463059
OS 2.6783779 1.6515984
OS 2.6730854 1.6551347
OS 2.6668425 1.6563765
OE
OB 4.1348425 1.6673765 H
OS 4.1285996 1.6661347
OS 4.1233071 1.6625984
OS 4.1197708 1.6573059
OS 4.118529 1.651063
OS 4.1197708 1.6448201
OS 4.1233071 1.6395276
OS 4.1285996 1.6359913
OS 4.1336434 1.634988
OS 4.1357664 1.6316625
OS 4.1362826 1.629938
OS 4.1362346 1.6298661
OS 4.1349928 1.6236232
OS 4.1362346 1.6173803
OS 4.1397709 1.6120878
OS 4.1450634 1.6085515
OS 4.1513063 1.6073097
OS 4.1575492 1.6085515
OS 4.1612353 1.6110144
OS 4.1648401 1.6074096
OS 4.1647708 1.6073059
OS 4.163529 1.601063
OS 4.1647708 1.5948201
OS 4.1683071 1.5895276
OS 4.1735996 1.5859913
OS 4.1798425 1.5847495
OS 4.1860854 1.5859913
OS 4.1913779 1.5895276
OS 4.1949142 1.5948201
OS 4.196156 1.601063
OS 4.1949142 1.6073059
OS 4.1913779 1.6125984
OS 4.1860854 1.6161347
OS 4.1798425 1.6173765
OS 4.1735996 1.6161347
OS 4.1699135 1.6136718
OS 4.1663087 1.6172766
OS 4.166378 1.6173803
OS 4.1676198 1.6236232
OS 4.166378 1.6298661
OS 4.1628417 1.6351586
OS 4.1575492 1.6386949
OS 4.1525054 1.6396982
OS 4.1503824 1.6430237
OS 4.1498662 1.6447482
OS 4.1499142 1.6448201
OS 4.151156 1.651063
OS 4.1499142 1.6573059
OS 4.1463779 1.6625984
OS 4.1410854 1.6661347
OS 4.1348425 1.6673765
OE
OB 2.7198425 1.6073765 H
OS 2.7135996 1.6061347
OS 2.7083071 1.6025984
OS 2.7047708 1.5973059
OS 2.703529 1.591063
OS 2.7047708 1.5848201
OS 2.7083071 1.5795276
OS 2.7135996 1.5759913
OS 2.7198425 1.5747495
OS 2.7260854 1.5759913
OS 2.7313779 1.5795276
OS 2.7349142 1.5848201
OS 2.736156 1.591063
OS 2.7349142 1.5973059
OS 2.7313779 1.6025984
OS 2.7260854 1.6061347
OS 2.7198425 1.6073765
OE
OB 3.8948425 1.5823765 H
OS 3.8885996 1.5811347
OS 3.8833071 1.5775984
OS 3.8797708 1.5723059
OS 3.878529 1.566063
OS 3.8797708 1.5598201
OS 3.8833071 1.5545276
OS 3.8885996 1.5509913
OS 3.8948425 1.5497495
OS 3.9010854 1.5509913
OS 3.9063779 1.5545276
OS 3.9099142 1.5598201
OS 3.911156 1.566063
OS 3.9099142 1.5723059
OS 3.9063779 1.5775984
OS 3.9010854 1.5811347
OS 3.8948425 1.5823765
OE
OB 3.9698425 1.5683765 H
OS 3.9635996 1.5671347
OS 3.9583071 1.5635984
OS 3.9547708 1.5583059
OS 3.953529 1.552063
OS 3.9547708 1.5458201
OS 3.9583071 1.5405276
OS 3.9635996 1.5369913
OS 3.9698425 1.5357495
OS 3.9760854 1.5369913
OS 3.9780923 1.5383323
OS 3.9831154 1.5394836
OS 3.9856688 1.5379496
OS 3.9885996 1.5359913
OS 3.9948425 1.5347495
OS 4.0010854 1.5359913
OS 4.0063779 1.5395276
OS 4.0099142 1.5448201
OS 4.011156 1.551063
OS 4.0099142 1.5573059
OS 4.0063779 1.5625984
OS 4.0010854 1.5661347
OS 3.9948425 1.5673765
OS 3.9885996 1.5661347
OS 3.9833072 1.5625984
OS 3.982046 1.5625984
OS 3.9813779 1.5635984
OS 3.9760854 1.5671347
OS 3.9698425 1.5683765
OE
OB 4.0348425 1.5623765 H
OS 4.0285996 1.5611347
OS 4.0233071 1.5575984
OS 4.0197708 1.5523059
OS 4.018529 1.546063
OS 4.0197708 1.5398201
OS 4.0233071 1.5345276
OS 4.0285996 1.5309913
OS 4.0348425 1.5297495
OS 4.0410854 1.5309913
OS 4.0463779 1.5345276
OS 4.0499142 1.5398201
OS 4.051156 1.546063
OS 4.0499142 1.5523059
OS 4.0463779 1.5575984
OS 4.0410854 1.5611347
OS 4.0348425 1.5623765
OE
OB 3.9248425 1.5523765 H
OS 3.9185996 1.5511347
OS 3.9133071 1.5475984
OS 3.9097708 1.5423059
OS 3.908529 1.536063
OS 3.9097708 1.5298201
OS 3.9133071 1.5245276
OS 3.9185996 1.5209913
OS 3.9248425 1.5197495
OS 3.9310854 1.5209913
OS 3.9363779 1.5245276
OS 3.9399142 1.5298201
OS 3.941156 1.536063
OS 3.9399142 1.5423059
OS 3.9363779 1.5475984
OS 3.9310854 1.5511347
OS 3.9248425 1.5523765
OE
OB 2.8948425 1.5773765 H
OS 2.8885996 1.5761347
OS 2.8833071 1.5725984
OS 2.8797708 1.5673059
OS 2.878529 1.561063
OS 2.8797708 1.5548201
OS 2.8833071 1.5495276
OS 2.8885996 1.5459913
OS 2.8948425 1.5447495
OS 2.9010854 1.5459913
OS 2.9013282 1.5461536
OS 2.9049331 1.5425487
OS 2.9047708 1.5423059
OS 2.903529 1.536063
OS 2.9047708 1.5298201
OS 2.9083071 1.5245276
OS 2.9135996 1.5209913
OS 2.9198425 1.5197495
OS 2.9260854 1.5209913
OS 2.9313779 1.5245276
OS 2.9349142 1.5298201
OS 2.936156 1.536063
OS 2.9349142 1.5423059
OS 2.9313779 1.5475984
OS 2.9260854 1.5511347
OS 2.9198425 1.5523765
OS 2.9135996 1.5511347
OS 2.9133568 1.5509724
OS 2.9097519 1.5545773
OS 2.9099142 1.5548201
OS 2.911156 1.561063
OS 2.9099142 1.5673059
OS 2.9063779 1.5725984
OS 2.9010854 1.5761347
OS 2.8948425 1.5773765
OE
OB 1.7198425 1.5523765 H
OS 1.7135996 1.5511347
OS 1.7083071 1.5475984
OS 1.7047708 1.5423059
OS 1.703529 1.536063
OS 1.7047708 1.5298201
OS 1.7083071 1.5245276
OS 1.7135996 1.5209913
OS 1.7198425 1.5197495
OS 1.7260854 1.5209913
OS 1.7313779 1.5245276
OS 1.7349142 1.5298201
OS 1.736156 1.536063
OS 1.7349142 1.5423059
OS 1.7313779 1.5475984
OS 1.7260854 1.5511347
OS 1.7198425 1.5523765
OE
OB 1.8973025 1.5328365 H
OS 1.8910596 1.5315947
OS 1.8857671 1.5280584
OS 1.8822308 1.5227659
OS 1.880989 1.516523
OS 1.8822308 1.5102801
OS 1.8857671 1.5049876
OS 1.8910596 1.5014513
OS 1.8973025 1.5002095
OS 1.9035454 1.5014513
OS 1.9088379 1.5049876
OS 1.9123742 1.5102801
OS 1.913616 1.516523
OS 1.9123742 1.5227659
OS 1.9088379 1.5280584
OS 1.9035454 1.5315947
OS 1.8973025 1.5328365
OE
OB 4.0648425 1.5273765 H
OS 4.0585996 1.5261347
OS 4.0533071 1.5225984
OS 4.0497708 1.5173059
OS 4.048529 1.511063
OS 4.0497708 1.5048201
OS 4.0533071 1.4995276
OS 4.0585996 1.4959913
OS 4.0648425 1.4947495
OS 4.0710854 1.4959913
OS 4.0763779 1.4995276
OS 4.0799142 1.5048201
OS 4.081156 1.511063
OS 4.0799142 1.5173059
OS 4.0763779 1.5225984
OS 4.0710854 1.5261347
OS 4.0648425 1.5273765
OE
OB 3.8648425 1.5273765 H
OS 3.8585996 1.5261347
OS 3.8533071 1.5225984
OS 3.8497708 1.5173059
OS 3.848529 1.511063
OS 3.8497708 1.5048201
OS 3.8533071 1.4995276
OS 3.8585996 1.4959913
OS 3.8648425 1.4947495
OS 3.8710854 1.4959913
OS 3.8763779 1.4995276
OS 3.8799142 1.5048201
OS 3.881156 1.511063
OS 3.8799142 1.5173059
OS 3.8763779 1.5225984
OS 3.8710854 1.5261347
OS 3.8648425 1.5273765
OE
OB 2.2748425 1.5223765 H
OS 2.2685996 1.5211347
OS 2.2633071 1.5175984
OS 2.2597708 1.5123059
OS 2.258529 1.506063
OS 2.2597708 1.4998201
OS 2.2633071 1.4945276
OS 2.2685996 1.4909913
OS 2.2748425 1.4897495
OS 2.2810854 1.4909913
OS 2.2863779 1.4945276
OS 2.2899142 1.4998201
OS 2.291156 1.506063
OS 2.2899142 1.5123059
OS 2.2863779 1.5175984
OS 2.2810854 1.5211347
OS 2.2748425 1.5223765
OE
OB 3.8348425 1.4973765 H
OS 3.8285996 1.4961347
OS 3.8233071 1.4925984
OS 3.8197708 1.4873059
OS 3.818529 1.481063
OS 3.8197708 1.4748201
OS 3.8233071 1.4695276
OS 3.8285996 1.4659913
OS 3.8348425 1.4647495
OS 3.8410854 1.4659913
OS 3.8463779 1.4695276
OS 3.8499142 1.4748201
OS 3.851156 1.481063
OS 3.8499142 1.4873059
OS 3.8463779 1.4925984
OS 3.8410854 1.4961347
OS 3.8348425 1.4973765
OE
OB 2.6948425 1.4973765 H
OS 2.6885996 1.4961347
OS 2.6833071 1.4925984
OS 2.6797708 1.4873059
OS 2.678529 1.481063
OS 2.6797708 1.4748201
OS 2.6833071 1.4695276
OS 2.6885996 1.4659913
OS 2.6948425 1.4647495
OS 2.7010854 1.4659913
OS 2.7063779 1.4695276
OS 2.7099142 1.4748201
OS 2.711156 1.481063
OS 2.7099142 1.4873059
OS 2.7063779 1.4925984
OS 2.7010854 1.4961347
OS 2.6948425 1.4973765
OE
OB 3.5498425 1.4573765 H
OS 3.5435996 1.4561347
OS 3.5383071 1.4525984
OS 3.5347708 1.4473059
OS 3.533529 1.441063
OS 3.5347708 1.4348201
OS 3.5383071 1.4295276
OS 3.5435996 1.4259913
OS 3.5498425 1.4247495
OS 3.5560854 1.4259913
OS 3.5613779 1.4295276
OS 3.5649142 1.4348201
OS 3.566156 1.441063
OS 3.5649142 1.4473059
OS 3.5613779 1.4525984
OS 3.5560854 1.4561347
OS 3.5498425 1.4573765
OE
OB 2.4468425 1.4533765 H
OS 2.4405996 1.4521347
OS 2.4353071 1.4485984
OS 2.4317708 1.4433059
OS 2.430529 1.437063
OS 2.4317708 1.4308201
OS 2.4353071 1.4255276
OS 2.4405996 1.4219913
OS 2.4468425 1.4207495
OS 2.4530854 1.4219913
OS 2.4583779 1.4255276
OS 2.4619142 1.4308201
OS 2.463156 1.437063
OS 2.4619142 1.4433059
OS 2.4583779 1.4485984
OS 2.4530854 1.4521347
OS 2.4468425 1.4533765
OE
OB 1.0088425 1.4463765 H
OS 1.0025996 1.4451347
OS 0.9973071 1.4415984
OS 0.9937708 1.4363059
OS 0.992529 1.430063
OS 0.9937708 1.4238201
OS 0.9973071 1.4185276
OS 1.0025996 1.4149913
OS 1.0088425 1.4137495
OS 1.0150854 1.4149913
OS 1.0203779 1.4185276
OS 1.0239142 1.4238201
OS 1.025156 1.430063
OS 1.0239142 1.4363059
OS 1.0203779 1.4415984
OS 1.0150854 1.4451347
OS 1.0088425 1.4463765
OE
OB 2.0838425 1.4279765 H
OS 2.0775996 1.4267347
OS 2.0723071 1.4231984
OS 2.0687708 1.4179059
OS 2.067529 1.411663
OS 2.0687708 1.4054201
OS 2.0688553 1.4052937
OS 2.0669242 1.4023943
OS 2.0655495 1.4012413
OS 2.0598425 1.4023765
OS 2.0535996 1.4011347
OS 2.0483071 1.3975984
OS 2.0447708 1.3923059
OS 2.043529 1.386063
OS 2.0447708 1.3798201
OS 2.0483071 1.3745276
OS 2.0535996 1.3709913
OS 2.0598425 1.3697495
OS 2.0660854 1.3709913
OS 2.0713779 1.3745276
OS 2.0749142 1.3798201
OS 2.076156 1.386063
OS 2.0749142 1.3923059
OS 2.0748297 1.3924323
OS 2.0767608 1.3953317
OS 2.0781355 1.3964847
OS 2.0838425 1.3953495
OS 2.0900854 1.3965913
OS 2.0953779 1.4001276
OS 2.0989142 1.4054201
OS 2.100156 1.411663
OS 2.0989142 1.4179059
OS 2.0953779 1.4231984
OS 2.0900854 1.4267347
OS 2.0838425 1.4279765
OE
OB 3.4072822 1.4276365 H
OS 3.4010393 1.4263947
OS 3.3957468 1.4228584
OS 3.3922105 1.4175659
OS 3.3909687 1.411323
OS 3.3922105 1.4050801
OS 3.3952066 1.4005957
OS 3.3913778 1.3975986
OS 3.3860854 1.4011347
OS 3.3798425 1.4023765
OS 3.3735996 1.4011347
OS 3.3683071 1.3975984
OS 3.3647708 1.3923059
OS 3.363529 1.386063
OS 3.3647708 1.3798201
OS 3.3683071 1.3745276
OS 3.3735996 1.3709913
OS 3.3798425 1.3697495
OS 3.3850268 1.3707807
OS 3.3880585 1.3685992
OS 3.3892832 1.3671145
OS 3.388529 1.363323
OS 3.3897708 1.3570801
OS 3.3920261 1.3537048
OS 3.3926608 1.3527545
OS 3.3890562 1.3491499
OS 3.3882815 1.3496673
OS 3.3860854 1.3511347
OS 3.3798425 1.3523765
OS 3.3735996 1.3511347
OS 3.3683071 1.3475984
OS 3.3647708 1.3423059
OS 3.363529 1.336063
OS 3.3647708 1.3298201
OS 3.3683071 1.3245276
OS 3.3735996 1.3209913
OS 3.3798425 1.3197495
OS 3.3860854 1.3209913
OS 3.3913779 1.3245276
OS 3.3949142 1.3298201
OS 3.396156 1.336063
OS 3.3949142 1.3423059
OS 3.3926589 1.3456812
OS 3.3920242 1.3466315
OS 3.3956288 1.3502361
OS 3.3964035 1.3497187
OS 3.3985996 1.3482513
OS 3.4048425 1.3470095
OS 3.4110854 1.3482513
OS 3.4163779 1.3517876
OS 3.4199142 1.3570801
OS 3.421156 1.363323
OS 3.4199142 1.3695659
OS 3.4163779 1.3748584
OS 3.4110854 1.3783947
OS 3.4048425 1.3796365
OS 3.3996582 1.3786053
OS 3.3966265 1.3807868
OS 3.3954018 1.3822715
OS 3.396156 1.386063
OS 3.3949142 1.3923059
OS 3.3919181 1.3967903
OS 3.3957469 1.3997874
OS 3.4010393 1.3962513
OS 3.4072822 1.3950095
OS 3.4135251 1.3962513
OS 3.4188176 1.3997876
OS 3.4223539 1.4050801
OS 3.4235957 1.411323
OS 3.4223539 1.4175659
OS 3.4188176 1.4228584
OS 3.4135251 1.4263947
OS 3.4072822 1.4276365
OE
OB 0.1998425 1.4953727 H
OS 0.1872963 1.494137
OS 0.1752322 1.4904774
OS 0.1641139 1.4845346
OS 0.1543687 1.4765368
OS 0.1463709 1.4667916
OS 0.1404281 1.4556733
OS 0.1367685 1.4436092
OS 0.1355328 1.431063
OS 0.1367685 1.4185168
OS 0.1404281 1.4064527
OS 0.1463709 1.3953344
OS 0.1543687 1.3855892
OS 0.1641139 1.3775914
OS 0.1752322 1.3716486
OS 0.1872963 1.367989
OS 0.1998425 1.3667533
OS 0.2123887 1.367989
OS 0.2244528 1.3716486
OS 0.2355711 1.3775914
OS 0.2453163 1.3855892
OS 0.2533141 1.3953344
OS 0.2592569 1.4064527
OS 0.2629165 1.4185168
OS 0.2641522 1.431063
OS 0.2629165 1.4436092
OS 0.2592569 1.4556733
OS 0.2533141 1.4667916
OS 0.2453163 1.4765368
OS 0.2355711 1.4845346
OS 0.2244528 1.4904774
OS 0.2123887 1.494137
OS 0.1998425 1.4953727
OE
OB 2.0288425 1.3779765 H
OS 2.0225996 1.3767347
OS 2.0173071 1.3731984
OS 2.0137708 1.3679059
OS 2.012529 1.361663
OS 2.0137708 1.3554201
OS 2.0138553 1.3552937
OS 2.0119242 1.3523943
OS 2.0105495 1.3512413
OS 2.0048425 1.3523765
OS 1.9985996 1.3511347
OS 1.9933071 1.3475984
OS 1.9897708 1.3423059
OS 1.988529 1.336063
OS 1.9897708 1.3298201
OS 1.9933071 1.3245276
OS 1.9985996 1.3209913
OS 2.0048425 1.3197495
OS 2.0110854 1.3209913
OS 2.0163779 1.3245276
OS 2.0199142 1.3298201
OS 2.021156 1.336063
OS 2.0199142 1.3423059
OS 2.0198297 1.3424323
OS 2.0217608 1.3453317
OS 2.0231355 1.3464847
OS 2.0288425 1.3453495
OS 2.0350854 1.3465913
OS 2.0403779 1.3501276
OS 2.0439142 1.3554201
OS 2.045156 1.361663
OS 2.0439142 1.3679059
OS 2.0403779 1.3731984
OS 2.0350854 1.3767347
OS 2.0288425 1.3779765
OE
OB 2.5028425 1.3323765 H
OS 2.4965996 1.3311347
OS 2.4913071 1.3275984
OS 2.4877708 1.3223059
OS 2.486529 1.316063
OS 2.4877708 1.3098201
OS 2.4913071 1.3045276
OS 2.4965996 1.3009913
OS 2.5028425 1.2997495
OS 2.5090854 1.3009913
OS 2.5143779 1.3045276
OS 2.5179142 1.3098201
OS 2.519156 1.316063
OS 2.5179142 1.3223059
OS 2.5143779 1.3275984
OS 2.5090854 1.3311347
OS 2.5028425 1.3323765
OE
OB 1.6968325 1.3290319 H
OS 1.6894854 1.3275705
OS 1.6832568 1.3234087
OS 1.679095 1.3171801
OS 1.6776336 1.309833
OS 1.679095 1.3024859
OS 1.6832568 1.2962573
OS 1.6894854 1.2920955
OS 1.6968325 1.2906341
OS 1.7041796 1.2920955
OS 1.7104082 1.2962573
OS 1.71457 1.3024859
OS 1.7160314 1.309833
OS 1.71457 1.3171801
OS 1.7104082 1.3234087
OS 1.7041796 1.3275705
OS 1.6968325 1.3290319
OE
OB 3.5717425 1.3289919 H
OS 3.5643954 1.3275305
OS 3.5581668 1.3233687
OS 3.554005 1.3171401
OS 3.5525436 1.309793
OS 3.554005 1.3024459
OS 3.5581668 1.2962173
OS 3.5643954 1.2920555
OS 3.5717425 1.2905941
OS 3.5790896 1.2920555
OS 3.5853182 1.2962173
OS 3.58948 1.3024459
OS 3.5909414 1.309793
OS 3.58948 1.3171401
OS 3.5853182 1.3233687
OS 3.5790896 1.3275305
OS 3.5717425 1.3289919
OE
OB 1.7982283 1.3204474 H
OS 1.7919854 1.3192056
OS 1.7866929 1.3156693
OS 1.7831566 1.3103768
OS 1.7819148 1.3041339
OS 1.7831566 1.297891
OS 1.7866929 1.2925985
OS 1.7919854 1.2890622
OS 1.7982283 1.2878204
OS 1.8044712 1.2890622
OS 1.8097637 1.2925985
OS 1.8133 1.297891
OS 1.8145418 1.3041339
OS 1.8133 1.3103768
OS 1.8097637 1.3156693
OS 1.8044712 1.3192056
OS 1.7982283 1.3204474
OE
OB 2.2068425 1.3143765 H
OS 2.2005996 1.3131347
OS 2.1953071 1.3095984
OS 2.1917708 1.3043059
OS 2.190529 1.298063
OS 2.1917708 1.2918201
OS 2.1953071 1.2865276
OS 2.2005996 1.2829913
OS 2.2068425 1.2817495
OS 2.2130854 1.2829913
OS 2.2183779 1.2865276
OS 2.2219142 1.2918201
OS 2.223156 1.298063
OS 2.2219142 1.3043059
OS 2.2183779 1.3095984
OS 2.2130854 1.3131347
OS 2.2068425 1.3143765
OE
OB 1.5679134 1.3017466 H
OS 1.5616705 1.3005048
OS 1.556378 1.2969685
OS 1.5528417 1.291676
OS 1.5515999 1.2854331
OS 1.5528417 1.2791902
OS 1.556378 1.2738977
OS 1.5616705 1.2703614
OS 1.5679134 1.2691196
OS 1.5741563 1.2703614
OS 1.5794488 1.2738977
OS 1.5829851 1.2791902
OS 1.5842269 1.2854331
OS 1.5829851 1.291676
OS 1.5794488 1.2969685
OS 1.5741563 1.3005048
OS 1.5679134 1.3017466
OE
OB 0.996063 1.2033214 H
OS 0.9898201 1.2020796
OS 0.9845276 1.1985433
OS 0.9809913 1.1932508
OS 0.9797495 1.1870079
OS 0.9809913 1.180765
OS 0.9845276 1.1754725
OS 0.9898201 1.1719362
OS 0.996063 1.1706944
OS 1.0023059 1.1719362
OS 1.0075984 1.1754725
OS 1.0111347 1.180765
OS 1.0123765 1.1870079
OS 1.0111347 1.1932508
OS 1.0075984 1.1985433
OS 1.0023059 1.2020796
OS 0.996063 1.2033214
OE
OB 2.8267717 0.9926915 H
OS 2.8205288 0.9914497
OS 2.8152364 0.9879134
OS 2.8107479 0.9879134
OS 2.8054555 0.9914497
OS 2.7992126 0.9926915
OS 2.7929697 0.9914497
OS 2.7876772 0.9879134
OS 2.7864713 0.9861086
OS 2.7804578 0.9861086
OS 2.7792519 0.9879134
OS 2.7739594 0.9914497
OS 2.7677165 0.9926915
OS 2.7614736 0.9914497
OS 2.7561812 0.9879134
OS 2.7516928 0.9879134
OS 2.7464004 0.9914497
OS 2.7401575 0.9926915
OS 2.7339146 0.9914497
OS 2.7286221 0.9879134
OS 2.7274162 0.9861086
OS 2.7214027 0.9861086
OS 2.7201968 0.9879134
OS 2.7149043 0.9914497
OS 2.7086614 0.9926915
OS 2.7024185 0.9914497
OS 2.6971261 0.9879134
OS 2.6926377 0.9879134
OS 2.6873453 0.9914497
OS 2.6811024 0.9926915
OS 2.6748595 0.9914497
OS 2.669567 0.9879134
OS 2.6683611 0.9861086
OS 2.6623476 0.9861086
OS 2.6611417 0.9879134
OS 2.6558492 0.9914497
OS 2.6496063 0.9926915
OS 2.6433634 0.9914497
OS 2.638071 0.9879134
OS 2.6335825 0.9879134
OS 2.6282901 0.9914497
OS 2.6220472 0.9926915
OS 2.6158043 0.9914497
OS 2.6105118 0.9879134
OS 2.6069755 0.9826209
OS 2.6057337 0.976378
OS 2.6069755 0.9701351
OS 2.6105118 0.9648426
OS 2.6158043 0.9613063
OS 2.6220472 0.9600645
OS 2.6282901 0.9613063
OS 2.6335825 0.9648426
OS 2.638071 0.9648426
OS 2.6433634 0.9613063
OS 2.6496063 0.9600645
OS 2.6558492 0.9613063
OS 2.6611417 0.9648426
OS 2.6623476 0.9666474
OS 2.6683611 0.9666474
OS 2.669567 0.9648426
OS 2.6748595 0.9613063
OS 2.6811024 0.9600645
OS 2.6873453 0.9613063
OS 2.6926377 0.9648426
OS 2.6971261 0.9648426
OS 2.7024185 0.9613063
OS 2.7086614 0.9600645
OS 2.7149043 0.9613063
OS 2.7201968 0.9648426
OS 2.7214027 0.9666474
OS 2.7274162 0.9666474
OS 2.7286221 0.9648426
OS 2.7339146 0.9613063
OS 2.7401575 0.9600645
OS 2.7464004 0.9613063
OS 2.7516928 0.9648426
OS 2.7561812 0.9648426
OS 2.7614736 0.9613063
OS 2.7677165 0.9600645
OS 2.7739594 0.9613063
OS 2.7792519 0.9648426
OS 2.7804578 0.9666474
OS 2.7864713 0.9666474
OS 2.7876772 0.9648426
OS 2.7929697 0.9613063
OS 2.7992126 0.9600645
OS 2.8054555 0.9613063
OS 2.8107479 0.9648426
OS 2.8152364 0.9648426
OS 2.8205288 0.9613063
OS 2.8267717 0.9600645
OS 2.8330146 0.9613063
OS 2.8383071 0.9648426
OS 2.8418434 0.9701351
OS 2.8430852 0.976378
OS 2.8418434 0.9826209
OS 2.8383071 0.9879134
OS 2.8330146 0.9914497
OS 2.8267717 0.9926915
OE
OB 4.3662677 1.0459921 H
OS 4.2892441 1.0459921
OS 4.2892441 0.9689685
OS 4.3662677 0.9689685
OS 4.3662677 1.0459921
OE
OB 5.3277559 1.0463244 H
OS 5.3177023 1.0450008
OS 5.3083338 1.0411203
OS 5.300289 1.0349472
OS 5.2941159 1.0269023
OS 5.2902354 1.0175339
OS 5.2889118 1.0074803
OS 5.2902354 0.9974267
OS 5.2941159 0.9880583
OS 5.300289 0.9800134
OS 5.3083338 0.9738403
OS 5.3177023 0.9699598
OS 5.3277559 0.9686362
OS 5.3378095 0.9699598
OS 5.347178 0.9738403
OS 5.3552228 0.9800134
OS 5.3613959 0.9880583
OS 5.3652764 0.9974267
OS 5.3666 1.0074803
OS 5.3652764 1.0175339
OS 5.3613959 1.0269023
OS 5.3552228 1.0349472
OS 5.347178 1.0411203
OS 5.3378095 1.0450008
OS 5.3277559 1.0463244
OE
OB 5.1277559 1.0463244 H
OS 5.1177023 1.0450008
OS 5.1083338 1.0411203
OS 5.100289 1.0349472
OS 5.0941159 1.0269023
OS 5.0902354 1.0175339
OS 5.0889118 1.0074803
OS 5.0902354 0.9974267
OS 5.0941159 0.9880583
OS 5.100289 0.9800134
OS 5.1083338 0.9738403
OS 5.1177023 0.9699598
OS 5.1277559 0.9686362
OS 5.1378095 0.9699598
OS 5.147178 0.9738403
OS 5.1552228 0.9800134
OS 5.1613959 0.9880583
OS 5.1652764 0.9974267
OS 5.1666 1.0074803
OS 5.1652764 1.0175339
OS 5.1613959 1.0269023
OS 5.1552228 1.0349472
OS 5.147178 1.0411203
OS 5.1378095 1.0450008
OS 5.1277559 1.0463244
OE
OB 4.9277559 1.0463244 H
OS 4.9177023 1.0450008
OS 4.9083338 1.0411203
OS 4.900289 1.0349472
OS 4.8941159 1.0269023
OS 4.8902354 1.0175339
OS 4.8889118 1.0074803
OS 4.8902354 0.9974267
OS 4.8941159 0.9880583
OS 4.900289 0.9800134
OS 4.9083338 0.9738403
OS 4.9177023 0.9699598
OS 4.9277559 0.9686362
OS 4.9378095 0.9699598
OS 4.947178 0.9738403
OS 4.9552228 0.9800134
OS 4.9613959 0.9880583
OS 4.9652764 0.9974267
OS 4.9666 1.0074803
OS 4.9652764 1.0175339
OS 4.9613959 1.0269023
OS 4.9552228 1.0349472
OS 4.947178 1.0411203
OS 4.9378095 1.0450008
OS 4.9277559 1.0463244
OE
OB 2.9905425 0.9777919 H
OS 2.9831954 0.9763305
OS 2.9769668 0.9721687
OS 2.972805 0.9659401
OS 2.9713436 0.958593
OS 2.972805 0.9512459
OS 2.9769668 0.9450173
OS 2.9831954 0.9408555
OS 2.9905425 0.9393941
OS 2.9978896 0.9408555
OS 3.0041182 0.9450173
OS 3.00828 0.9512459
OS 3.0097414 0.958593
OS 3.00828 0.9659401
OS 3.0041182 0.9721687
OS 2.9978896 0.9763305
OS 2.9905425 0.9777919
OE
OB 2.2031425 0.9777919 H
OS 2.1957954 0.9763305
OS 2.1895668 0.9721687
OS 2.185405 0.9659401
OS 2.1839436 0.958593
OS 2.185405 0.9512459
OS 2.1895668 0.9450173
OS 2.1957954 0.9408555
OS 2.2031425 0.9393941
OS 2.2104896 0.9408555
OS 2.2167182 0.9450173
OS 2.22088 0.9512459
OS 2.2223414 0.958593
OS 2.22088 0.9659401
OS 2.2167182 0.9721687
OS 2.2104896 0.9763305
OS 2.2031425 0.9777919
OE
OB 2.4788425 0.9533765 H
OS 2.4725996 0.9521347
OS 2.4673071 0.9485984
OS 2.4637708 0.9433059
OS 2.462529 0.937063
OS 2.4637708 0.9308201
OS 2.4673071 0.9255276
OS 2.4725996 0.9219913
OS 2.4788425 0.9207495
OS 2.4850854 0.9219913
OS 2.4903779 0.9255276
OS 2.4939142 0.9308201
OS 2.495156 0.937063
OS 2.4939142 0.9433059
OS 2.4903779 0.9485984
OS 2.4850854 0.9521347
OS 2.4788425 0.9533765
OE
OB 1.0048425 0.9223765 H
OS 0.9985996 0.9211347
OS 0.9933071 0.9175984
OS 0.9897708 0.9123059
OS 0.988529 0.906063
OS 0.9897708 0.8998201
OS 0.9933071 0.8945276
OS 0.9985996 0.8909913
OS 1.0048425 0.8897495
OS 1.0110854 0.8909913
OS 1.0163779 0.8945276
OS 1.0199142 0.8998201
OS 1.021156 0.906063
OS 1.0199142 0.9123059
OS 1.0163779 0.9175984
OS 1.0110854 0.9211347
OS 1.0048425 0.9223765
OE
OB 3.6179425 0.9836725 H
OS 3.6047974 0.9823778
OS 3.5921575 0.9785435
OS 3.5805085 0.972317
OS 3.570298 0.9639375
OS 3.5619185 0.953727
OS 3.555692 0.942078
OS 3.5518577 0.9294381
OS 3.550563 0.916293
OS 3.5518577 0.9031479
OS 3.555692 0.890508
OS 3.5619185 0.878859
OS 3.570298 0.8686485
OS 3.5805085 0.860269
OS 3.5921575 0.8540425
OS 3.6047974 0.8502082
OS 3.6179425 0.8489135
OS 3.6310876 0.8502082
OS 3.6437275 0.8540425
OS 3.6553765 0.860269
OS 3.665587 0.8686485
OS 3.6739665 0.878859
OS 3.680193 0.890508
OS 3.6840273 0.9031479
OS 3.685322 0.916293
OS 3.6840273 0.9294381
OS 3.680193 0.942078
OS 3.6739665 0.953727
OS 3.665587 0.9639375
OS 3.6553765 0.972317
OS 3.6437275 0.9785435
OS 3.6310876 0.9823778
OS 3.6179425 0.9836725
OE
OB 1.6529425 0.9836725 H
OS 1.6397974 0.9823778
OS 1.6271575 0.9785435
OS 1.6155085 0.972317
OS 1.605298 0.9639375
OS 1.5969185 0.953727
OS 1.590692 0.942078
OS 1.5868577 0.9294381
OS 1.585563 0.916293
OS 1.5868577 0.9031479
OS 1.590692 0.890508
OS 1.5969185 0.878859
OS 1.605298 0.8686485
OS 1.6155085 0.860269
OS 1.6271575 0.8540425
OS 1.6397974 0.8502082
OS 1.6529425 0.8489135
OS 1.6660876 0.8502082
OS 1.6787275 0.8540425
OS 1.6903765 0.860269
OS 1.700587 0.8686485
OS 1.7089665 0.878859
OS 1.715193 0.890508
OS 1.7190273 0.9031479
OS 1.720322 0.916293
OS 1.7190273 0.9294381
OS 1.715193 0.942078
OS 1.7089665 0.953727
OS 1.700587 0.9639375
OS 1.6903765 0.972317
OS 1.6787275 0.9785435
OS 1.6660876 0.9823778
OS 1.6529425 0.9836725
OE
OB 5.5781524 0.9365112 H
OS 5.5662745 0.9349474
OS 5.5552061 0.9303628
OS 5.5457014 0.9230696
OS 5.5384082 0.9135649
OS 5.5338236 0.9024965
OS 5.5322598 0.8906186
OS 5.5338236 0.8787407
OS 5.5384082 0.8676723
OS 5.5457014 0.8581676
OS 5.5552061 0.8508744
OS 5.5662745 0.8462898
OS 5.5781524 0.844726
OS 5.5900303 0.8462898
OS 5.6010987 0.8508744
OS 5.6106034 0.8581676
OS 5.6178966 0.8676723
OS 5.6224812 0.8787407
OS 5.624045 0.8906186
OS 5.6224812 0.9024965
OS 5.6178966 0.9135649
OS 5.6106034 0.9230696
OS 5.6010987 0.9303628
OS 5.5900303 0.9349474
OS 5.5781524 0.9365112
OE
OB 3.9797272 0.9365112 H
OS 3.9678493 0.9349474
OS 3.9567809 0.9303628
OS 3.9472762 0.9230696
OS 3.939983 0.9135649
OS 3.9353984 0.9024965
OS 3.9338346 0.8906186
OS 3.9353984 0.8787407
OS 3.939983 0.8676723
OS 3.9472762 0.8581676
OS 3.9567809 0.8508744
OS 3.9678493 0.8462898
OS 3.9797272 0.844726
OS 3.9916051 0.8462898
OS 4.0026735 0.8508744
OS 4.0121782 0.8581676
OS 4.0194714 0.8676723
OS 4.024056 0.8787407
OS 4.0256198 0.8906186
OS 4.024056 0.9024965
OS 4.0194714 0.9135649
OS 4.0121782 0.9230696
OS 4.0026735 0.9303628
OS 3.9916051 0.9349474
OS 3.9797272 0.9365112
OE
OB 0.1998425 0.9703727 H
OS 0.1872963 0.969137
OS 0.1752322 0.9654774
OS 0.1641139 0.9595346
OS 0.1543687 0.9515368
OS 0.1463709 0.9417916
OS 0.1404281 0.9306733
OS 0.1367685 0.9186092
OS 0.1355328 0.906063
OS 0.1367685 0.8935168
OS 0.1404281 0.8814527
OS 0.1463709 0.8703344
OS 0.1543687 0.8605892
OS 0.1641139 0.8525914
OS 0.1752322 0.8466486
OS 0.1872963 0.842989
OS 0.1998425 0.8417533
OS 0.2123887 0.842989
OS 0.2244528 0.8466486
OS 0.2355711 0.8525914
OS 0.2453163 0.8605892
OS 0.2533141 0.8703344
OS 0.2592569 0.8814527
OS 0.2629165 0.8935168
OS 0.2641522 0.906063
OS 0.2629165 0.9186092
OS 0.2592569 0.9306733
OS 0.2533141 0.9417916
OS 0.2453163 0.9515368
OS 0.2355711 0.9595346
OS 0.2244528 0.9654774
OS 0.2123887 0.969137
OS 0.1998425 0.9703727
OE
OB 2.7598425 0.8115891 H
OS 2.7535996 0.8103473
OS 2.7483072 0.806811
OS 2.7438188 0.806811
OS 2.7385264 0.8103473
OS 2.7322835 0.8115891
OS 2.7260406 0.8103473
OS 2.7207481 0.806811
OS 2.7172118 0.8015185
OS 2.71597 0.7952756
OS 2.7172118 0.7890327
OS 2.7207481 0.7837402
OS 2.7260406 0.7802039
OS 2.7322835 0.7789621
OS 2.7385264 0.7802039
OS 2.7438188 0.7837402
OS 2.7483072 0.7837402
OS 2.7535996 0.7802039
OS 2.7598425 0.7789621
OS 2.7660854 0.7802039
OS 2.7713779 0.7837402
OS 2.7749142 0.7890327
OS 2.776156 0.7952756
OS 2.7749142 0.8015185
OS 2.7713779 0.806811
OS 2.7660854 0.8103473
OS 2.7598425 0.8115891
OE
OB 2.6929134 0.8115891 H
OS 2.6866705 0.8103473
OS 2.6813781 0.806811
OS 2.6768896 0.806811
OS 2.6715972 0.8103473
OS 2.6653543 0.8115891
OS 2.6591114 0.8103473
OS 2.6538189 0.806811
OS 2.6502826 0.8015185
OS 2.6490408 0.7952756
OS 2.6502826 0.7890327
OS 2.6538189 0.7837402
OS 2.6591114 0.7802039
OS 2.6653543 0.7789621
OS 2.6715972 0.7802039
OS 2.6768896 0.7837402
OS 2.6813781 0.7837402
OS 2.6866705 0.7802039
OS 2.6929134 0.7789621
OS 2.6991563 0.7802039
OS 2.7044488 0.7837402
OS 2.7079851 0.7890327
OS 2.7092269 0.7952756
OS 2.7079851 0.8015185
OS 2.7044488 0.806811
OS 2.6991563 0.8103473
OS 2.6929134 0.8115891
OE
OB 2.6259843 0.8115891 H
OS 2.6197414 0.8103473
OS 2.614449 0.806811
OS 2.6099605 0.806811
OS 2.6046681 0.8103473
OS 2.5984252 0.8115891
OS 2.5921823 0.8103473
OS 2.5868898 0.806811
OS 2.5833535 0.8015185
OS 2.5821117 0.7952756
OS 2.5833535 0.7890327
OS 2.5868898 0.7837402
OS 2.5921823 0.7802039
OS 2.5984252 0.7789621
OS 2.6046681 0.7802039
OS 2.6099605 0.7837402
OS 2.614449 0.7837402
OS 2.6197414 0.7802039
OS 2.6259843 0.7789621
OS 2.6322272 0.7802039
OS 2.6375197 0.7837402
OS 2.641056 0.7890327
OS 2.6422978 0.7952756
OS 2.641056 0.8015185
OS 2.6375197 0.806811
OS 2.6322272 0.8103473
OS 2.6259843 0.8115891
OE
OB 2.8937008 0.8115891 H
OS 2.8874579 0.8103473
OS 2.8821654 0.806811
OS 2.8809595 0.8050062
OS 2.874946 0.8050062
OS 2.8737401 0.806811
OS 2.8684476 0.8103473
OS 2.8622047 0.8115891
OS 2.8559618 0.8103473
OS 2.8506693 0.806811
OS 2.847133 0.8015185
OS 2.8470372 0.8010368
OS 2.8419392 0.8010368
OS 2.8418434 0.8015185
OS 2.8383071 0.806811
OS 2.8330146 0.8103473
OS 2.8267717 0.8115891
OS 2.8205288 0.8103473
OS 2.8152364 0.806811
OS 2.8107479 0.806811
OS 2.8054555 0.8103473
OS 2.7992126 0.8115891
OS 2.7929697 0.8103473
OS 2.7876772 0.806811
OS 2.7841409 0.8015185
OS 2.7828991 0.7952756
OS 2.7841409 0.7890327
OS 2.7876772 0.7837402
OS 2.7929697 0.7802039
OS 2.7992126 0.7789621
OS 2.8054555 0.7802039
OS 2.8107479 0.7837402
OS 2.8152364 0.7837402
OS 2.8205288 0.7802039
OS 2.8267717 0.7789621
OS 2.8330146 0.7802039
OS 2.8383071 0.7837402
OS 2.8418434 0.7890327
OS 2.8419392 0.7895144
OS 2.8470372 0.7895144
OS 2.847133 0.7890327
OS 2.8506693 0.7837402
OS 2.8559618 0.7802039
OS 2.8622047 0.7789621
OS 2.8684476 0.7802039
OS 2.8737401 0.7837402
OS 2.874946 0.785545
OS 2.8809595 0.785545
OS 2.8821654 0.7837402
OS 2.8874579 0.7802039
OS 2.8937008 0.7789621
OS 2.8999437 0.7802039
OS 2.9052362 0.7837402
OS 2.9087725 0.7890327
OS 2.9100143 0.7952756
OS 2.9087725 0.8015185
OS 2.9052362 0.806811
OS 2.8999437 0.8103473
OS 2.8937008 0.8115891
OE
OB 0.9901575 0.7033214 H
OS 0.9839146 0.7020796
OS 0.9786221 0.6985433
OS 0.9750858 0.6932508
OS 0.973844 0.6870079
OS 0.9750858 0.680765
OS 0.9786221 0.6754725
OS 0.9839146 0.6719362
OS 0.9901575 0.6706944
OS 0.9964004 0.6719362
OS 1.0016929 0.6754725
OS 1.0052292 0.680765
OS 1.006471 0.6870079
OS 1.0052292 0.6932508
OS 1.0016929 0.6985433
OS 0.9964004 0.7020796
OS 0.9901575 0.7033214
OE
OB 2.4698827 0.4273018 H
OS 2.4636398 0.42606
OS 2.4583473 0.4225237
OS 2.454811 0.4172312
OS 2.4535692 0.4109883
OS 2.454811 0.4047454
OS 2.4583473 0.3994529
OS 2.4636398 0.3959166
OS 2.4698827 0.3946748
OS 2.4761256 0.3959166
OS 2.4814181 0.3994529
OS 2.4849544 0.4047454
OS 2.4861962 0.4109883
OS 2.4849544 0.4172312
OS 2.4814181 0.4225237
OS 2.4761256 0.42606
OS 2.4698827 0.4273018
OE
OB 2.980457 0.4254674 H
OS 2.9742141 0.4242256
OS 2.9689216 0.4206893
OS 2.9653853 0.4153968
OS 2.9641435 0.4091539
OS 2.9653853 0.402911
OS 2.9689216 0.3976185
OS 2.9742141 0.3940822
OS 2.980457 0.3928404
OS 2.9866999 0.3940822
OS 2.9919924 0.3976185
OS 2.9955287 0.402911
OS 2.9967705 0.4091539
OS 2.9955287 0.4153968
OS 2.9919924 0.4206893
OS 2.9866999 0.4242256
OS 2.980457 0.4254674
OE
OB 3.019685 0.4218253 H
OS 3.0134421 0.4205835
OS 3.0081496 0.4170472
OS 3.0046133 0.4117547
OS 3.0033715 0.4055118
OS 3.0046133 0.3992689
OS 3.0081496 0.3939764
OS 3.0134421 0.3904401
OS 3.019685 0.3891983
OS 3.0259279 0.3904401
OS 3.0312204 0.3939764
OS 3.0347567 0.3992689
OS 3.0359985 0.4055118
OS 3.0347567 0.4117547
OS 3.0312204 0.4170472
OS 3.0259279 0.4205835
OS 3.019685 0.4218253
OE
OB 2.8219832 0.4241654 H
OS 2.8157403 0.4229236
OS 2.8104478 0.4193873
OS 2.8069115 0.4140948
OS 2.8056697 0.4078519
OS 2.8069115 0.401609
OS 2.8104478 0.3963165
OS 2.8157403 0.3927802
OS 2.8219832 0.3915384
OS 2.8282261 0.3927802
OS 2.8335186 0.3963165
OS 2.8345973 0.3979309
OS 2.8352825 0.3981275
OS 2.8403819 0.3975883
OS 2.8427953 0.3939764
OS 2.8480878 0.3904401
OS 2.8543307 0.3891983
OS 2.8605736 0.3904401
OS 2.8658661 0.3939764
OS 2.8694024 0.3992689
OS 2.8706442 0.4055118
OS 2.8694024 0.4117547
OS 2.8658661 0.4170472
OS 2.8605736 0.4205835
OS 2.8543307 0.4218253
OS 2.8480878 0.4205835
OS 2.8427953 0.4170472
OS 2.8417166 0.4154328
OS 2.8410314 0.4152362
OS 2.835932 0.4157754
OS 2.8335186 0.4193873
OS 2.8282261 0.4229236
OS 2.8219832 0.4241654
OE
OB 2.7047244 0.4218253 H
OS 2.6984815 0.4205835
OS 2.693189 0.4170472
OS 2.6896527 0.4117547
OS 2.6884109 0.4055118
OS 2.6896527 0.3992689
OS 2.693189 0.3939764
OS 2.6984815 0.3904401
OS 2.7047244 0.3891983
OS 2.7109673 0.3904401
OS 2.7162598 0.3939764
OS 2.7197961 0.3992689
OS 2.7210379 0.4055118
OS 2.7197961 0.4117547
OS 2.7162598 0.4170472
OS 2.7109673 0.4205835
OS 2.7047244 0.4218253
OE
OB 2.6653543 0.4218253 H
OS 2.6591114 0.4205835
OS 2.6538189 0.4170472
OS 2.6502826 0.4117547
OS 2.6490408 0.4055118
OS 2.6502826 0.3992689
OS 2.6538189 0.3939764
OS 2.6591114 0.3904401
OS 2.6653543 0.3891983
OS 2.6715972 0.3904401
OS 2.6768897 0.3939764
OS 2.680426 0.3992689
OS 2.6816678 0.4055118
OS 2.680426 0.4117547
OS 2.6768897 0.4170472
OS 2.6715972 0.4205835
OS 2.6653543 0.4218253
OE
OB 2.511811 0.4218253 H
OS 2.5055681 0.4205835
OS 2.5002756 0.4170472
OS 2.4967393 0.4117547
OS 2.4954975 0.4055118
OS 2.4967393 0.3992689
OS 2.5002756 0.3939764
OS 2.5055681 0.3904401
OS 2.511811 0.3891983
OS 2.5180539 0.3904401
OS 2.5233464 0.3939764
OS 2.5268827 0.3992689
OS 2.5281245 0.4055118
OS 2.5268827 0.4117547
OS 2.5233464 0.4170472
OS 2.5180539 0.4205835
OS 2.511811 0.4218253
OE
OB 2.3897638 0.4218253 H
OS 2.3835209 0.4205835
OS 2.3782284 0.4170472
OS 2.3746921 0.4117547
OS 2.3734503 0.4055118
OS 2.3746921 0.3992689
OS 2.3782284 0.3939764
OS 2.3835209 0.3904401
OS 2.3897638 0.3891983
OS 2.3960067 0.3904401
OS 2.4012992 0.3939764
OS 2.4048355 0.3992689
OS 2.4060773 0.4055118
OS 2.4048355 0.4117547
OS 2.4012992 0.4170472
OS 2.3960067 0.4205835
OS 2.3897638 0.4218253
OE
OB 2.3503937 0.4218253 H
OS 2.3441508 0.4205835
OS 2.3388583 0.4170472
OS 2.335322 0.4117547
OS 2.3340802 0.4055118
OS 2.335322 0.3992689
OS 2.3388583 0.3939764
OS 2.3441508 0.3904401
OS 2.3503937 0.3891983
OS 2.3566366 0.3904401
OS 2.3619291 0.3939764
OS 2.3654654 0.3992689
OS 2.3667072 0.4055118
OS 2.3654654 0.4117547
OS 2.3619291 0.4170472
OS 2.3566366 0.4205835
OS 2.3503937 0.4218253
OE
OB 1.8720472 0.3037151 H
OS 1.8658043 0.3024733
OS 1.8622047 0.3000681
OS 1.8586051 0.3024733
OS 1.8523622 0.3037151
OS 1.8461193 0.3024733
OS 1.8425197 0.3000681
OS 1.83892 0.3024733
OS 1.8326771 0.3037151
OS 1.8264342 0.3024733
OS 1.8211417 0.298937
OS 1.8176054 0.2936445
OS 1.8163636 0.2874016
OS 1.8176054 0.2811587
OS 1.8211417 0.2758662
OS 1.8229465 0.2746603
OS 1.8229465 0.2686468
OS 1.8211417 0.2674409
OS 1.8176054 0.2621484
OS 1.8163636 0.2559055
OS 1.8176054 0.2496626
OS 1.8211417 0.2443701
OS 1.8264342 0.2408338
OS 1.8326771 0.239592
OS 1.83892 0.2408338
OS 1.8425197 0.243239
OS 1.8461193 0.2408338
OS 1.8523622 0.239592
OS 1.8586051 0.2408338
OS 1.8622047 0.243239
OS 1.8658043 0.2408338
OS 1.8720472 0.239592
OS 1.8782901 0.2408338
OS 1.8835826 0.2443701
OS 1.8871189 0.2496626
OS 1.8883607 0.2559055
OS 1.8871189 0.2621484
OS 1.8835826 0.2674409
OS 1.8817778 0.2686468
OS 1.8817778 0.2746603
OS 1.8835826 0.2758662
OS 1.8871189 0.2811587
OS 1.8883607 0.2874016
OS 1.8871189 0.2936445
OS 1.8835826 0.298937
OS 1.8782901 0.3024733
OS 1.8720472 0.3037151
OE
OB 0.2854331 0.4390502 H
OS 0.2715934 0.4376871
OS 0.2582855 0.4336502
OS 0.2460209 0.4270947
OS 0.2352709 0.4182724
OS 0.2264486 0.4075224
OS 0.2198931 0.3952578
OS 0.2158562 0.3819499
OS 0.2144931 0.3681102
OS 0.2158562 0.3542705
OS 0.2198931 0.3409626
OS 0.2264486 0.328698
OS 0.2352709 0.317948
OS 0.2460209 0.3091257
OS 0.2582855 0.3025702
OS 0.2715934 0.2985333
OS 0.2854331 0.2971702
OS 0.2992728 0.2985333
OS 0.3125807 0.3025702
OS 0.3248453 0.3091257
OS 0.3355953 0.317948
OS 0.3444176 0.328698
OS 0.3509731 0.3409626
OS 0.35501 0.3542705
OS 0.3563731 0.3681102
OS 0.35501 0.3819499
OS 0.3509731 0.3952578
OS 0.3444176 0.4075224
OS 0.3355953 0.4182724
OS 0.3248453 0.4270947
OS 0.3125807 0.4336502
OS 0.2992728 0.4376871
OS 0.2854331 0.4390502
OE
OB 2.1122047 0.3037151 H
OS 2.1059618 0.3024733
OS 2.1006693 0.298937
OS 2.097133 0.2936445
OS 2.0970371 0.2931626
OS 2.0919392 0.2931626
OS 2.0918433 0.2936445
OS 2.088307 0.298937
OS 2.0830145 0.3024733
OS 2.0767716 0.3037151
OS 2.0705287 0.3024733
OS 2.0652362 0.298937
OS 2.0616999 0.2936445
OS 2.0604581 0.2874016
OS 2.0616999 0.2811587
OS 2.0652362 0.2758662
OS 2.067041 0.2746603
OS 2.067041 0.2686468
OS 2.0652362 0.2674409
OS 2.0616999 0.2621484
OS 2.0604581 0.2559055
OS 2.0616999 0.2496626
OS 2.0652362 0.2443701
OS 2.0705287 0.2408338
OS 2.0767716 0.239592
OS 2.0830145 0.2408338
OS 2.088307 0.2443701
OS 2.0918433 0.2496626
OS 2.0919392 0.2501445
OS 2.0970371 0.2501445
OS 2.097133 0.2496626
OS 2.1006693 0.2443701
OS 2.1059618 0.2408338
OS 2.1122047 0.239592
OS 2.1184476 0.2408338
OS 2.1237401 0.2443701
OS 2.1272764 0.2496626
OS 2.1285182 0.2559055
OS 2.1272764 0.2621484
OS 2.1237401 0.2674409
OS 2.1219353 0.2686468
OS 2.1219353 0.2746603
OS 2.1237401 0.2758662
OS 2.1272764 0.2811587
OS 2.1285182 0.2874016
OS 2.1272764 0.2936445
OS 2.1237401 0.298937
OS 2.1184476 0.3024733
OS 2.1122047 0.3037151
OE
OB 2.6102362 0.2958411 H
OS 2.6039933 0.2945993
OS 2.5987008 0.291063
OS 2.5974949 0.2892583
OS 2.5914815 0.2892583
OS 2.5902756 0.291063
OS 2.5849831 0.2945993
OS 2.5787402 0.2958411
OS 2.5724973 0.2945993
OS 2.5672048 0.291063
OS 2.5636685 0.2857705
OS 2.5624267 0.2795276
OS 2.5636685 0.2732847
OS 2.5672048 0.2679922
OS 2.5724973 0.2644559
OS 2.5787402 0.2632141
OS 2.5849831 0.2644559
OS 2.5902756 0.2679922
OS 2.5914815 0.2697969
OS 2.5974949 0.2697969
OS 2.5987008 0.2679922
OS 2.6039933 0.2644559
OS 2.6102362 0.2632141
OS 2.6164791 0.2644559
OS 2.6217716 0.2679922
OS 2.6253079 0.2732847
OS 2.6265497 0.2795276
OS 2.6253079 0.2857705
OS 2.6217716 0.291063
OS 2.6164791 0.2945993
OS 2.6102362 0.2958411
OE
OB 2.4448819 0.2958411 H
OS 2.438639 0.2945993
OS 2.4333465 0.291063
OS 2.4321406 0.2892582
OS 2.4261271 0.2892582
OS 2.4249212 0.291063
OS 2.4196287 0.2945993
OS 2.4133858 0.2958411
OS 2.4071429 0.2945993
OS 2.4018504 0.291063
OS 2.3983141 0.2857705
OS 2.3970723 0.2795276
OS 2.3983141 0.2732847
OS 2.4018504 0.2679922
OS 2.4071429 0.2644559
OS 2.4133858 0.2632141
OS 2.4196287 0.2644559
OS 2.4249212 0.2679922
OS 2.4261271 0.269797
OS 2.4321406 0.269797
OS 2.4333465 0.2679922
OS 2.438639 0.2644559
OS 2.4448819 0.2632141
OS 2.4511248 0.2644559
OS 2.4564173 0.2679922
OS 2.4599536 0.2732847
OS 2.4611954 0.2795276
OS 2.4599536 0.2857705
OS 2.4564173 0.291063
OS 2.4511248 0.2945993
OS 2.4448819 0.2958411
OE
OB 2.9370079 0.2958411 H
OS 2.930765 0.2945993
OS 2.9254725 0.291063
OS 2.9242523 0.2892367
OS 2.9182388 0.2892367
OS 2.91703 0.2910458
OS 2.9117375 0.2945821
OS 2.9054946 0.2958239
OS 2.8992517 0.2945821
OS 2.8939592 0.2910458
OS 2.8904229 0.2857533
OS 2.8891811 0.2795104
OS 2.8904229 0.2732675
OS 2.8939592 0.267975
OS 2.8992517 0.2644387
OS 2.9054946 0.2631969
OS 2.9117375 0.2644387
OS 2.91703 0.267975
OS 2.9182502 0.2698013
OS 2.9242637 0.2698013
OS 2.9254725 0.2679922
OS 2.930765 0.2644559
OS 2.9370079 0.2632141
OS 2.9432508 0.2644559
OS 2.9485433 0.2679922
OS 2.9520796 0.2732847
OS 2.9533214 0.2795276
OS 2.9520796 0.2857705
OS 2.9485433 0.291063
OS 2.9432508 0.2945993
OS 2.9370079 0.2958411
OE
OB 2.74882 0.2986255 H
OS 2.7425771 0.2973837
OS 2.7372846 0.2938474
OS 2.7337483 0.2885549
OS 2.7325065 0.282312
OS 2.7337483 0.2760691
OS 2.7372846 0.2707766
OS 2.7425771 0.2672403
OS 2.74882 0.2659985
OS 2.7550629 0.2672403
OS 2.7603553 0.2707766
OS 2.7662503 0.2705991
OS 2.7679922 0.2679922
OS 2.7732847 0.2644559
OS 2.7795276 0.2632141
OS 2.7857705 0.2644559
OS 2.791063 0.2679922
OS 2.7945993 0.2732847
OS 2.7958411 0.2795276
OS 2.7945993 0.2857705
OS 2.791063 0.291063
OS 2.7857705 0.2945993
OS 2.7795276 0.2958411
OS 2.7732847 0.2945993
OS 2.7679923 0.291063
OS 2.7620973 0.2912405
OS 2.7603554 0.2938474
OS 2.7550629 0.2973837
OS 2.74882 0.2986255
OE
OB 2.1515748 0.3037151 H
OS 2.1453319 0.3024733
OS 2.1400394 0.298937
OS 2.1365031 0.2936445
OS 2.1352613 0.2874016
OS 2.1365031 0.2811587
OS 2.1400394 0.2758662
OS 2.1418442 0.2746603
OS 2.1418442 0.2686468
OS 2.1400394 0.2674409
OS 2.1365031 0.2621484
OS 2.1352613 0.2559055
OS 2.1365031 0.2496626
OS 2.1400394 0.2443701
OS 2.1453319 0.2408338
OS 2.1515748 0.239592
OS 2.1578177 0.2408338
OS 2.1631102 0.2443701
OS 2.1666465 0.2496626
OS 2.1678883 0.2559055
OS 2.1666465 0.2621484
OS 2.1631102 0.2674409
OS 2.1613054 0.2686468
OS 2.1613054 0.2746603
OS 2.1631102 0.2758662
OS 2.1666465 0.2811587
OS 2.1678883 0.2874016
OS 2.1666465 0.2936445
OS 2.1631102 0.298937
OS 2.1578177 0.3024733
OS 2.1515748 0.3037151
OE
SE
P 0.149508 2.830047 9 P 0 0 ;0=7,1=1
P 0.149508 3.853669 9 P 0 0 ;0=7,1=1
P 0.6538425 1.551063 10 P 0 0 ;0=8,1=1
P 0.6539669 2.5938902 10 P 0 0 ;0=8,1=1
P 0.6548425 0.790063 10 P 0 0 ;0=8,1=1
P 0.6548425 1.314063 10 P 0 0 ;0=8,1=1
P 0.6548425 1.839063 10 P 0 0 ;0=8,1=1
P 0.6548425 2.073063 10 P 0 0 ;0=8,1=1
P 0.6548425 2.365063 10 P 0 0 ;0=8,1=1
P 0.6558425 1.028063 10 P 0 0 ;0=8,1=1
P 0.9370078 2.3179133 10 P 0 0 ;0=8,1=1
P 1.2428425 1.472063 10 P 0 0 ;0=8,1=1
P 1.2488425 2.000063 10 P 0 0 ;0=8,1=1
P 1.2568425 0.942063 10 P 0 0 ;0=8,1=1
P 1.2618425 2.482063 10 P 0 0 ;0=8,1=1
P 1.6708425 1.595063 10 P 0 0 ;0=8,1=1
P 1.6708425 1.694063 10 P 0 0 ;0=8,1=1
P 1.6718425 1.399063 10 P 0 0 ;0=8,1=1
P 1.6718425 1.497063 10 P 0 0 ;0=8,1=1
P 1.6718425 1.792063 10 P 0 0 ;0=8,1=1
P 1.6748425 1.989063 10 P 0 0 ;0=8,1=1
P 1.6758425 1.891063 10 P 0 0 ;0=8,1=1
P 1.6918425 4.079063 10 P 0 0 ;0=8,1=1
P 1.7148425 1.595063 10 P 0 0 ;0=8,1=1
P 1.7168425 1.399063 10 P 0 0 ;0=8,1=1
P 1.7188425 1.497063 10 P 0 0 ;0=8,1=1
P 1.7188425 1.792063 10 P 0 0 ;0=8,1=1
P 1.7218425 1.694063 10 P 0 0 ;0=8,1=1
P 1.7218425 1.890063 10 P 0 0 ;0=8,1=1
P 1.7218425 1.989063 10 P 0 0 ;0=8,1=1
P 1.7268425 4.329374 10 P 0 0 ;0=8,1=1
P 1.7498425 4.110063 10 P 0 0 ;0=8,1=1
P 1.7888425 4.329374 10 P 0 0 ;0=8,1=1
P 1.9161425 0.244763 10 P 0 0 ;0=8,1=1
P 2.0348425 0.246063 10 P 0 0 ;0=8,1=1
P 2.1398425 3.738063 10 P 0 0 ;0=8,1=1
P 2.2538425 2.279063 10 P 0 0 ;0=8,1=1
P 2.2588425 3.741063 10 P 0 0 ;0=8,1=1
P 2.2908425 4.217063 10 P 0 0 ;0=8,1=1
P 2.3098425 0.246063 10 P 0 0 ;0=8,1=1
P 2.3114125 1.0900094 10 P 0 0 ;0=8,1=1
P 2.3118425 0.934063 10 P 0 0 ;0=8,1=1
P 2.3215354 2.586063 10 P 0 0 ;0=8,1=1
P 2.3215354 3.361063 10 P 0 0 ;0=8,1=1
P 2.4048425 2.412063 10 P 0 0 ;0=8,1=1
P 2.4098325 0.932053 10 P 0 0 ;0=8,1=1
P 2.4098325 1.088053 10 P 0 0 ;0=8,1=1
P 2.4098425 2.579063 10 P 0 0 ;0=8,1=1
P 2.4138425 3.295063 10 P 0 0 ;0=8,1=1
P 2.4192759 2.7886295 10 P 0 0 ;0=8,1=1
P 2.4470546 0.2425914 10 P 0 0 ;0=8,1=1
P 2.4738425 2.980063 10 P 0 0 ;0=8,1=1
P 2.4758425 2.456063 10 P 0 0 ;0=8,1=1
P 2.4888425 2.413063 10 P 0 0 ;0=8,1=1
P 2.5082625 0.931483 10 P 0 0 ;0=8,1=1
P 2.5088425 1.090063 10 P 0 0 ;0=8,1=1
P 2.531398 2.830047 9 P 0 0 ;0=7,1=1
P 2.531398 3.853669 9 P 0 0 ;0=7,1=1
P 2.5460625 0.244843 10 P 0 0 ;0=8,1=1
P 2.5818425 2.308063 10 P 0 0 ;0=8,1=1
P 2.5868425 2.569063 10 P 0 0 ;0=8,1=1
P 2.6066825 0.931903 10 P 0 0 ;0=8,1=1
P 2.6068425 1.091063 10 P 0 0 ;0=8,1=1
P 2.6318425 2.876063 10 P 0 0 ;0=8,1=1
P 2.636874 0.2479055 10 P 0 0 ;0=8,1=1
P 2.6658425 1.092063 10 P 0 0 ;0=8,1=1
P 2.6748425 3.501063 10 P 0 0 ;0=8,1=1
P 2.6858425 2.311063 10 P 0 0 ;0=8,1=1
P 2.6858425 2.568063 10 P 0 0 ;0=8,1=1
P 2.7244825 1.093063 10 P 0 0 ;0=8,1=1
P 2.7248425 3.521063 10 P 0 0 ;0=8,1=1
P 2.7248425 3.729063 10 P 0 0 ;0=8,1=1
P 2.7838425 2.429063 10 P 0 0 ;0=8,1=1
P 2.7838425 2.568063 10 P 0 0 ;0=8,1=1
P 2.7841625 1.094063 10 P 0 0 ;0=8,1=1
P 2.7999951 0.2519685 10 P 0 0 ;0=8,1=1
P 2.8428425 1.095063 10 P 0 0 ;0=8,1=1
P 2.8608425 3.787063 10 P 0 0 ;0=8,1=1
P 2.8718425 2.297063 10 P 0 0 ;0=8,1=1
P 2.8782843 0.2495967 10 P 0 0 ;0=8,1=1
P 2.8818425 2.566063 10 P 0 0 ;0=8,1=1
P 2.8888425 4.221063 10 P 0 0 ;0=8,1=1
P 2.9018425 1.095063 10 P 0 0 ;0=8,1=1
P 2.9338425 0.953063 10 P 0 0 ;0=8,1=1
P 2.9574751 0.2519685 10 P 0 0 ;0=8,1=1
P 3.0974409 0.2519685 10 P 0 0 ;0=8,1=1
P 3.1830708 3.1358268 10 P 0 0 ;0=8,1=1
P 3.2698425 3.788063 10 P 0 0 ;0=8,1=1
P 3.277559 2.9635827 10 P 0 0 ;0=8,1=1
P 3.3308425 3.301063 10 P 0 0 ;0=8,1=1
P 3.3708425 2.888063 10 P 0 0 ;0=8,1=1
P 3.3958425 4.222063 10 P 0 0 ;0=8,1=1
P 3.4068425 1.461063 10 P 0 0 ;0=8,1=1
P 3.4108425 1.7136509 10 P 0 0 ;0=8,1=1
P 3.4138425 1.573063 10 P 0 0 ;0=8,1=1
P 3.4144661 1.805063 10 P 0 0 ;0=8,1=1
P 3.5318425 3.660063 10 P 0 0 ;0=8,1=1
P 3.5498425 1.413063 10 P 0 0 ;0=8,1=1
P 3.5548425 1.841063 10 P 0 0 ;0=8,1=1
P 3.5548425 1.941063 10 P 0 0 ;0=8,1=1
P 3.5548425 1.991063 10 P 0 0 ;0=8,1=1
P 3.5908425 1.662063 10 P 0 0 ;0=8,1=1
P 3.5948425 1.514063 10 P 0 0 ;0=8,1=1
P 3.6038425 0.682063 10 P 0 0 ;0=8,1=1
P 3.6428425 0.636063 10 P 0 0 ;0=8,1=1
P 3.7178425 3.072063 10 P 0 0 ;0=8,1=1
P 3.7188425 1.713063 10 P 0 0 ;0=8,1=1
P 3.7198425 1.921063 10 P 0 0 ;0=8,1=1
P 3.7198425 1.996063 10 P 0 0 ;0=8,1=1
P 3.7328425 1.418063 10 P 0 0 ;0=8,1=1
P 3.7448425 3.342063 10 P 0 0 ;0=8,1=1
P 3.7778425 4.023063 10 P 0 0 ;0=8,1=1
P 3.8308425 3.762063 10 P 0 0 ;0=8,1=1
P 3.8808425 3.109063 10 P 0 0 ;0=8,1=1
P 3.9608425 2.724063 10 P 0 0 ;0=8,1=1
P 3.9688425 1.671063 10 P 0 0 ;0=8,1=1
P 3.9968425 1.711063 10 P 0 0 ;0=8,1=1
P 4.0398425 3.784063 10 P 0 0 ;0=8,1=1
P 4.0648425 2.722063 10 P 0 0 ;0=8,1=1
P 4.0688425 3.135063 10 P 0 0 ;0=8,1=1
P 4.0858425 3.892063 10 P 0 0 ;0=8,1=1
P 4.1148425 3.135063 10 P 0 0 ;0=8,1=1
P 4.1203866 3.5941508 10 P 0 0 ;0=8,1=1
P 4.1318425 1.686063 10 P 0 0 ;0=8,1=1
P 4.1528425 3.135063 10 P 0 0 ;0=8,1=1
P 4.1948425 3.884063 10 P 0 0 ;0=8,1=1
P 4.2088425 3.135063 10 P 0 0 ;0=8,1=1
P 4.2348425 2.725063 10 P 0 0 ;0=8,1=1
P 4.2728425 3.135063 10 P 0 0 ;0=8,1=1
P 4.3338425 3.135063 10 P 0 0 ;0=8,1=1
P 4.3398425 2.725063 10 P 0 0 ;0=8,1=1
P 4.3878425 4.206063 10 P 0 0 ;0=8,1=1
P 4.4318425 3.135063 10 P 0 0 ;0=8,1=1
P 4.4778425 3.135063 10 P 0 0 ;0=8,1=1
P 4.9108425 4.203063 10 P 0 0 ;0=8,1=1
P 5.6768425 3.546063 10 P 0 0 ;0=8,1=1
P 5.7338425 3.556063 10 P 0 0 ;0=8,1=1
P 6.0048425 2.434063 10 P 0 0 ;0=8,1=1
P 6.0488425 2.171063 10 P 0 0 ;0=8,1=1
P 6.253937 2.9094488 10 P 0 0 ;0=8,1=1
P 6.2748425 2.391063 10 P 0 0 ;0=8,1=1
P 6.3720472 2.9094488 10 P 0 0 ;0=8,1=1
P 6.3958425 2.111063 10 P 0 0 ;0=8,1=1
P 6.3968425 2.556063 10 P 0 0 ;0=8,1=1
P 6.3978425 2.501063 10 P 0 0 ;0=8,1=1
P 6.3978425 2.610063 10 P 0 0 ;0=8,1=1
P 6.3988425 2.453063 10 P 0 0 ;0=8,1=1
P 6.3988425 2.657063 10 P 0 0 ;0=8,1=1
P 6.4568425 3.009063 10 P 0 0 ;0=8,1=1
P 6.4768425 3.231063 10 P 0 0 ;0=8,1=1
P 6.5488425 1.531063 10 P 0 0 ;0=8,1=1
P 6.6018425 1.777063 10 P 0 0 ;0=8,1=1
P 6.6028425 1.612063 10 P 0 0 ;0=8,1=1
P 6.6028425 1.672063 10 P 0 0 ;0=8,1=1
P 6.6028425 1.722063 10 P 0 0 ;0=8,1=1
P 6.6078425 2.176063 10 P 0 0 ;0=8,1=1
P 6.6268425 3.032063 10 P 0 0 ;0=8,1=1
P 6.6288425 1.372063 10 P 0 0 ;0=8,1=1
P 6.6476378 3.1299213 10 P 0 0 ;0=8,1=1
P 6.6488425 3.341063 10 P 0 0 ;0=8,1=1
P 6.6858425 1.828063 10 P 0 0 ;0=8,1=1
P 6.6998425 1.881063 10 P 0 0 ;0=8,1=1
P 6.9498425 2.095063 10 P 0 0 ;0=8,1=1
P 6.9744094 1.9399606 10 P 0 0 ;0=8,1=1

### steps/pcb/layers/sgnd1/features
#Layer_Physical_Order=5
#Layer_Color=16737945
#
#Feature symbol names
#
$0 r3.937
$1 r1
$2 r250
$3 r75
$4 r61.0236
$5 oval177.1654x88.5827
$6 oval88.5827x177.1654
$7 r120
$8 r98.4252
$9 r200
$10 r16

#
#Feature attribute names
#
@0 .geometry
@1 .pad_usage

#
#Feature attribute text strings
#
&0 Pad_Simple_X250.0000Y250.0000H125.1969C165.1969
&1 Pad_Simple_X75.0000Y75.0000H50.0000C90.0000
&2 Pad_Simple_X61.0236Y61.0236H41.3386C81.3386
&3 Pad_Simple_X177.1654Y88.5827H39.3701C79.3701
&4 Pad_Simple_X88.5827Y177.1654H39.3701C79.3701
&5 Pad_Simple_X120.0000Y120.0000H68.0000C108.0000
&6 Pad_Simple_X98.4252Y98.4252H70.8661C110.8661
&7 VIA_RoundD200.0000H125.9843C165.9843
&8 VIA_RoundD16.0000H8.0000C48.0000

#
#Layer features
#
A 1.7712204 0.4310709 1.6275196 0.4310709 1.69937 0.4310709 0 P 0 N
L -0.0001175 0.177913 0.5908825 0.177913 1 P 0
L -0.0004331 0.1781182 0.5901181 0.1781182 0 P 0
L 0.5901181 0.1781182 0.5901181 0.5029213 0 P 0
L 0.5901181 0.5029213 1.312559 0.5029213 0 P 0
L 0.5908825 0.177913 0.5908825 0.502913 1 P 0
L 1.312559 0.313945 1.312559 0.5029213 0 P 0
L 1.312559 0.313945 1.6275197 0.313945 0 P 0
L 1.6275197 0.313945 1.6275197 0.4310709 0 P 0
P 0.0998425 0.806063 7 P 0 0 ;0=5,1=0
P 0.0998425 1.006063 7 P 0 0 ;0=5,1=0
P 0.0998425 1.331063 7 P 0 0 ;0=5,1=0
P 0.0998425 1.531063 7 P 0 0 ;0=5,1=0
P 0.0998425 1.856063 7 P 0 0 ;0=5,1=0
P 0.0998425 2.056063 7 P 0 0 ;0=5,1=0
P 0.0998425 2.381063 7 P 0 0 ;0=5,1=0
P 0.0998425 2.581063 7 P 0 0 ;0=5,1=0
P 0.285433 4.152063 2 P 0 0 ;0=0,1=0
P 0.2854331 0.3681102 2 P 0 0 ;0=0,1=0
P 0.2998425 0.806063 7 P 0 0 ;0=5,1=0
P 0.2998425 1.006063 7 P 0 0 ;0=5,1=0
P 0.2998425 1.331063 7 P 0 0 ;0=5,1=0
P 0.2998425 1.531063 7 P 0 0 ;0=5,1=0
P 0.2998425 1.856063 7 P 0 0 ;0=5,1=0
P 0.2998425 2.056063 7 P 0 0 ;0=5,1=0
P 0.2998425 2.381063 7 P 0 0 ;0=5,1=0
P 0.2998425 2.581063 7 P 0 0 ;0=5,1=0
P 3.9797272 2.4890438 3 P 0 0 ;0=1,1=0
P 5.1277559 2.3074803 4 P 0 0 ;0=2,1=0
P 5.5781524 1.6898312 3 P 0 0 ;0=1,1=0
P 5.9348031 3.9379527 6 P 0 0 ;0=4,1=0
P 6.1198425 4.056063 5 P 0 0 ;0=3,1=0
P 6.5694882 3.5895276 8 P 0 0 ;0=6,1=0
P 6.7348425 3.5895276 8 P 0 0 ;0=6,1=0
P 6.9001969 3.5895276 8 P 0 0 ;0=6,1=0
S P 0
OB 7.0826772 4.3531339 I
OS 7.0826772 0.5051339
OS 3.1099214 0.505134
OS 3.1099214 0.2253937
OS 2.2899214 0.2253937
OS 2.2899214 0.310134
OS 2.2579214 0.342134
OS 2.2299214 0.342134
OS 2.1979214 0.310134
OS 2.1979214 0.2253937
OS 1.7769214 0.2253937
OS 1.7769214 0.3525976
OS 1.7819212 0.3530901
OS 1.7820868 0.3522587
OS 1.7827708 0.3488201
OS 1.7863071 0.3435276
OS 1.7915996 0.3399913
OS 1.7978425 0.3387495
OS 1.8040854 0.3399913
OS 1.8093779 0.3435276
OS 1.8129142 0.3488201
OS 1.814156 0.355063
OS 1.8129142 0.3613059
OS 1.8093779 0.3665984
OS 1.8040854 0.3701347
OS 1.7978425 0.3713765
OS 1.7915996 0.3701347
OS 1.7863071 0.3665984
OS 1.7827708 0.3613059
OS 1.7820868 0.3578674
OS 1.7819212 0.3570359
OS 1.7769214 0.3575284
OS 1.7769214 0.465134
OS 1.7309214 0.511134
OS 1.6589214 0.511134
OS 1.6139214 0.466134
OS 1.6139214 0.3129921
OS 1.3169214 0.3129921
OS 1.3169214 0.508134
OS 0.5769214 0.508134
OS 0.5769214 0.184134
OS 0.0029214 0.184134
OS 0.0029214 4.3493766
OS 0.0066788 4.353134
OS 7.0826772 4.3531339
OE
OB 2.5708425 4.2993765 H
OS 2.5645996 4.2981347
OS 2.5593071 4.2945984
OS 2.5557708 4.2893059
OS 2.554529 4.283063
OS 2.5557708 4.2768201
OS 2.5593071 4.2715276
OS 2.5645996 4.2679913
OS 2.5708425 4.2667495
OS 2.5770854 4.2679913
OS 2.5823779 4.2715276
OS 2.5859142 4.2768201
OS 2.587156 4.283063
OS 2.5859142 4.2893059
OS 2.5823779 4.2945984
OS 2.5770854 4.2981347
OS 2.5708425 4.2993765
OE
OB 1.2948425 4.2723765 H
OS 1.2885996 4.2711347
OS 1.2833071 4.2675984
OS 1.2797708 4.2623059
OS 1.278529 4.256063
OS 1.2797708 4.2498201
OS 1.2833071 4.2445276
OS 1.2885996 4.2409913
OS 1.2948425 4.2397495
OS 1.3010854 4.2409913
OS 1.3063779 4.2445276
OS 1.3099142 4.2498201
OS 1.311156 4.256063
OS 1.3099142 4.2623059
OS 1.3063779 4.2675984
OS 1.3010854 4.2711347
OS 1.2948425 4.2723765
OE
OB 2.0788071 4.293374 H
OS 2.0078071 4.293374
OS 2.0078071 4.222374
OS 2.0788071 4.222374
OS 2.0788071 4.293374
OE
OB 1.4931771 4.289437 H
OS 1.4221771 4.289437
OS 1.4221771 4.218437
OS 1.4931771 4.218437
OS 1.4931771 4.289437
OE
OB 1.5578425 4.2453765 H
OS 1.5515996 4.2441347
OS 1.5463071 4.2405984
OS 1.5427708 4.2353059
OS 1.541529 4.229063
OS 1.5427708 4.2228201
OS 1.5463071 4.2175276
OS 1.5515996 4.2139913
OS 1.5578425 4.2127495
OS 1.5640854 4.2139913
OS 1.5693779 4.2175276
OS 1.5729142 4.2228201
OS 1.574156 4.229063
OS 1.5729142 4.2353059
OS 1.5693779 4.2405984
OS 1.5640854 4.2441347
OS 1.5578425 4.2453765
OE
OB 1.3454724 4.1915104 H
OS 1.3392295 4.1902686
OS 1.333937 4.1867323
OS 1.3304007 4.1814398
OS 1.3291589 4.1751969
OS 1.3304007 4.168954
OS 1.333937 4.1636615
OS 1.3392295 4.1601252
OS 1.3454724 4.1588834
OS 1.3517153 4.1601252
OS 1.3570078 4.1636615
OS 1.3605441 4.168954
OS 1.3617859 4.1751969
OS 1.3605441 4.1814398
OS 1.3570078 4.1867323
OS 1.3517153 4.1902686
OS 1.3454724 4.1915104
OE
OB 1.5698819 4.1875734 H
OS 1.563639 4.1863316
OS 1.5583465 4.1827953
OS 1.5548102 4.1775028
OS 1.5535684 4.1712599
OS 1.5548102 4.165017
OS 1.5583465 4.1597245
OS 1.563639 4.1561882
OS 1.5698819 4.1549464
OS 1.5761248 4.1561882
OS 1.5814173 4.1597245
OS 1.5849536 4.165017
OS 1.5861954 4.1712599
OS 1.5849536 4.1775028
OS 1.5814173 4.1827953
OS 1.5761248 4.1863316
OS 1.5698819 4.1875734
OE
OB 1.7798425 4.1723765 H
OS 1.7735996 4.1711347
OS 1.7683071 4.1675984
OS 1.7647708 4.1623059
OS 1.763529 4.156063
OS 1.7647708 4.1498201
OS 1.7683071 4.1445276
OS 1.7735996 4.1409913
OS 1.7798425 4.1397495
OS 1.7860854 4.1409913
OS 1.7913779 4.1445276
OS 1.7949142 4.1498201
OS 1.796156 4.156063
OS 1.7949142 4.1623059
OS 1.7913779 4.1675984
OS 1.7860854 4.1711347
OS 1.7798425 4.1723765
OE
OB 2.0433071 4.1936803 H
OS 2.0340397 4.1924602
OS 2.0254039 4.1888832
OS 2.0179882 4.1831929
OS 2.0122979 4.1757772
OS 2.0087209 4.1671414
OS 2.0075008 4.157874
OS 2.0087209 4.1486066
OS 2.0122979 4.1399708
OS 2.0179882 4.1325551
OS 2.0254039 4.1268648
OS 2.0340397 4.1232878
OS 2.0433071 4.1220677
OS 2.0525745 4.1232878
OS 2.0612103 4.1268648
OS 2.068626 4.1325551
OS 2.0743163 4.1399708
OS 2.0778933 4.1486066
OS 2.0791134 4.157874
OS 2.0778933 4.1671414
OS 2.0743163 4.1757772
OS 2.068626 4.1831929
OS 2.0612103 4.1888832
OS 2.0525745 4.1924602
OS 2.0433071 4.1936803
OE
OB 1.4576771 4.1897433 H
OS 1.4484097 4.1885232
OS 1.4397739 4.1849462
OS 1.4323582 4.1792559
OS 1.4266679 4.1718402
OS 1.4230909 4.1632044
OS 1.4218708 4.153937
OS 1.4230909 4.1446696
OS 1.4266679 4.1360338
OS 1.4323582 4.1286181
OS 1.4397739 4.1229278
OS 1.4484097 4.1193508
OS 1.4576771 4.1181307
OS 1.4669445 4.1193508
OS 1.4755803 4.1229278
OS 1.482996 4.1286181
OS 1.4886863 4.1360338
OS 1.4922633 4.1446696
OS 1.4934834 4.153937
OS 1.4922633 4.1632044
OS 1.4886863 4.1718402
OS 1.482996 4.1792559
OS 1.4755803 4.1849462
OS 1.4669445 4.1885232
OS 1.4576771 4.1897433
OE
OB 3.9580709 4.1520014 H
OS 3.9513575 4.1511176
OS 3.9451017 4.1485263
OS 3.9397297 4.1444042
OS 3.9356076 4.1390322
OS 3.9330163 4.1327764
OS 3.9321325 4.126063
OS 3.9330163 4.1193496
OS 3.9356076 4.1130938
OS 3.9397297 4.1077218
OS 3.9451017 4.1035997
OS 3.9513575 4.1010084
OS 3.9580709 4.1001246
OS 3.9647843 4.1010084
OS 3.9710401 4.1035997
OS 3.9764121 4.1077218
OS 3.9805342 4.1130938
OS 3.9831255 4.1193496
OS 3.9840093 4.126063
OS 3.9831255 4.1327764
OS 3.9805342 4.1390322
OS 3.9764121 4.1444042
OS 3.9710401 4.1485263
OS 3.9647843 4.1511176
OS 3.9580709 4.1520014
OE
OB 3.7848425 4.1520014 H
OS 3.7781291 4.1511176
OS 3.7718733 4.1485263
OS 3.7665013 4.1444042
OS 3.7623792 4.1390322
OS 3.7597879 4.1327764
OS 3.7589041 4.126063
OS 3.7597879 4.1193496
OS 3.7623792 4.1130938
OS 3.7665013 4.1077218
OS 3.7718733 4.1035997
OS 3.7781291 4.1010084
OS 3.7848425 4.1001246
OS 3.7915559 4.1010084
OS 3.7978117 4.1035997
OS 3.8031837 4.1077218
OS 3.8073058 4.1130938
OS 3.8098971 4.1193496
OS 3.8107809 4.126063
OS 3.8098971 4.1327764
OS 3.8073058 4.1390322
OS 3.8031837 4.1444042
OS 3.7978117 4.1485263
OS 3.7915559 4.1511176
OS 3.7848425 4.1520014
OE
OB 4.7547119 4.1322459 H
OS 4.748469 4.1310041
OS 4.7431765 4.1274678
OS 4.7396402 4.1221753
OS 4.7383984 4.1159324
OS 4.7396402 4.1096895
OS 4.7431765 4.104397
OS 4.748469 4.1008607
OS 4.7547119 4.0996189
OS 4.7609548 4.1008607
OS 4.7662473 4.104397
OS 4.7697836 4.1096895
OS 4.7710254 4.1159324
OS 4.7697836 4.1221753
OS 4.7662473 4.1274678
OS 4.7609548 4.1310041
OS 4.7547119 4.1322459
OE
OB 2.1460663 4.1201044 H
OS 2.1398234 4.1188626
OS 2.1345309 4.1153263
OS 2.1309946 4.1100338
OS 2.1297528 4.1037909
OS 2.1309946 4.097548
OS 2.1345309 4.0922555
OS 2.1398234 4.0887192
OS 2.1460663 4.0874774
OS 2.1523092 4.0887192
OS 2.1576017 4.0922555
OS 2.161138 4.097548
OS 2.1623798 4.1037909
OS 2.161138 4.1100338
OS 2.1576017 4.1153263
OS 2.1523092 4.1188626
OS 2.1460663 4.1201044
OE
OB 0.285433 4.223003 H
OS 0.2715933 4.2216399
OS 0.2582854 4.217603
OS 0.2460208 4.2110475
OS 0.2352708 4.2022252
OS 0.2264485 4.1914752
OS 0.219893 4.1792106
OS 0.2158561 4.1659027
OS 0.214493 4.152063
OS 0.2158561 4.1382233
OS 0.219893 4.1249154
OS 0.2264485 4.1126508
OS 0.2352708 4.1019008
OS 0.2460208 4.0930785
OS 0.2582854 4.086523
OS 0.2715933 4.0824861
OS 0.285433 4.081123
OS 0.2992727 4.0824861
OS 0.3125806 4.086523
OS 0.3248452 4.0930785
OS 0.3355952 4.1019008
OS 0.3444175 4.1126508
OS 0.350973 4.1249154
OS 0.3550099 4.1382233
OS 0.356373 4.152063
OS 0.3550099 4.1659027
OS 0.350973 4.1792106
OS 0.3444175 4.1914752
OS 0.3355952 4.2022252
OS 0.3248452 4.2110475
OS 0.3125806 4.217603
OS 0.2992727 4.2216399
OS 0.285433 4.223003
OE
OB 5.2670079 4.1052111 H
OS 5.260765 4.1039693
OS 5.2554725 4.100433
OS 5.2519362 4.0951405
OS 5.2506944 4.0888976
OS 5.2519362 4.0826547
OS 5.2554725 4.0773622
OS 5.260765 4.0738259
OS 5.2670079 4.0725841
OS 5.2732508 4.0738259
OS 5.2785433 4.0773622
OS 5.2820796 4.0826547
OS 5.2833214 4.0888976
OS 5.2820796 4.0951405
OS 5.2785433 4.100433
OS 5.2732508 4.1039693
OS 5.2670079 4.1052111
OE
OB 2.253937 4.1029277 H
OS 2.2476941 4.1016859
OS 2.2424016 4.0981496
OS 2.2388653 4.0928571
OS 2.2376235 4.0866142
OS 2.2388653 4.0803713
OS 2.2424016 4.0750788
OS 2.2476941 4.0715425
OS 2.253937 4.0703007
OS 2.2601799 4.0715425
OS 2.2654724 4.0750788
OS 2.2690087 4.0803713
OS 2.2702505 4.0866142
OS 2.2690087 4.0928571
OS 2.2654724 4.0981496
OS 2.2601799 4.1016859
OS 2.253937 4.1029277
OE
OB 3.5048425 4.1023765 H
OS 3.4985996 4.1011347
OS 3.4933071 4.0975984
OS 3.4897708 4.0923059
OS 3.488529 4.086063
OS 3.4897708 4.0798201
OS 3.4933071 4.0745276
OS 3.4985996 4.0709913
OS 3.5048425 4.0697495
OS 3.5110854 4.0709913
OS 3.5163779 4.0745276
OS 3.5199142 4.0798201
OS 3.521156 4.086063
OS 3.5199142 4.0923059
OS 3.5163779 4.0975984
OS 3.5110854 4.1011347
OS 3.5048425 4.1023765
OE
OB 3.2948425 4.1274482 H
OS 3.2841414 4.1260394
OS 3.2741696 4.1219089
OS 3.2656066 4.1153383
OS 3.259036 4.1067753
OS 3.2549055 4.0968035
OS 3.2534967 4.0861024
OS 3.2549055 4.0754013
OS 3.259036 4.0654295
OS 3.2656066 4.0568665
OS 3.2741696 4.0502959
OS 3.2841414 4.0461654
OS 3.2948425 4.0447566
OS 3.3055436 4.0461654
OS 3.3155154 4.0502959
OS 3.3240784 4.0568665
OS 3.330649 4.0654295
OS 3.3347795 4.0754013
OS 3.3361883 4.0861024
OS 3.3347795 4.0968035
OS 3.330649 4.1067753
OS 3.3240784 4.1153383
OS 3.3155154 4.1219089
OS 3.3055436 4.1260394
OS 3.2948425 4.1274482
OE
OB 2.9948425 4.1274482 H
OS 2.9841414 4.1260394
OS 2.9741696 4.1219089
OS 2.9656066 4.1153383
OS 2.959036 4.1067753
OS 2.9549055 4.0968035
OS 2.9534967 4.0861024
OS 2.9549055 4.0754013
OS 2.959036 4.0654295
OS 2.9656066 4.0568665
OS 2.9741696 4.0502959
OS 2.9841414 4.0461654
OS 2.9948425 4.0447566
OS 3.0055436 4.0461654
OS 3.0155154 4.0502959
OS 3.0240784 4.0568665
OS 3.030649 4.0654295
OS 3.0347795 4.0754013
OS 3.0361883 4.0861024
OS 3.0347795 4.0968035
OS 3.030649 4.1067753
OS 3.0240784 4.1153383
OS 3.0155154 4.1219089
OS 3.0055436 4.1260394
OS 2.9948425 4.1274482
OE
OB 6.9001969 4.1608442 H
OS 6.8870518 4.1595495
OS 6.8744118 4.1557152
OS 6.8627628 4.1494887
OS 6.8525523 4.1411092
OS 6.8441728 4.1308987
OS 6.8379463 4.1192497
OS 6.834112 4.1066097
OS 6.8328173 4.0934646
OS 6.834112 4.0803195
OS 6.8379463 4.0676795
OS 6.8441728 4.0560305
OS 6.8525523 4.04582
OS 6.8627628 4.0374405
OS 6.8744118 4.031214
OS 6.8870518 4.0273797
OS 6.9001969 4.026085
OS 6.913342 4.0273797
OS 6.925982 4.031214
OS 6.937631 4.0374405
OS 6.9478415 4.04582
OS 6.956221 4.0560305
OS 6.9624475 4.0676795
OS 6.9662818 4.0803195
OS 6.9675765 4.0934646
OS 6.9662818 4.1066097
OS 6.9624475 4.1192497
OS 6.956221 4.1308987
OS 6.9478415 4.1411092
OS 6.937631 4.1494887
OS 6.925982 4.1557152
OS 6.913342 4.1595495
OS 6.9001969 4.1608442
OE
OB 6.5694882 4.1608442 H
OS 6.5563431 4.1595495
OS 6.5437031 4.1557152
OS 6.5320541 4.1494887
OS 6.5218436 4.1411092
OS 6.5134641 4.1308987
OS 6.5072376 4.1192497
OS 6.5034033 4.1066097
OS 6.5021086 4.0934646
OS 6.5034033 4.0803195
OS 6.5072376 4.0676795
OS 6.5134641 4.0560305
OS 6.5218436 4.04582
OS 6.5320541 4.0374405
OS 6.5437031 4.031214
OS 6.5563431 4.0273797
OS 6.5694882 4.026085
OS 6.5826333 4.0273797
OS 6.5952733 4.031214
OS 6.6069223 4.0374405
OS 6.6171328 4.04582
OS 6.6255123 4.0560305
OS 6.6317388 4.0676795
OS 6.6355731 4.0803195
OS 6.6368678 4.0934646
OS 6.6355731 4.1066097
OS 6.6317388 4.1192497
OS 6.6255123 4.1308987
OS 6.6171328 4.1411092
OS 6.6069223 4.1494887
OS 6.5952733 4.1557152
OS 6.5826333 4.1595495
OS 6.5694882 4.1608442
OE
OB 2.0433071 4.0936803 H
OS 2.0340397 4.0924602
OS 2.0254039 4.0888832
OS 2.0179882 4.0831929
OS 2.0122979 4.0757772
OS 2.0087209 4.0671414
OS 2.0075008 4.057874
OS 2.0087209 4.0486066
OS 2.0122979 4.0399708
OS 2.0179882 4.0325551
OS 2.0254039 4.0268648
OS 2.0340397 4.0232878
OS 2.0433071 4.0220677
OS 2.0525745 4.0232878
OS 2.0612103 4.0268648
OS 2.068626 4.0325551
OS 2.0743163 4.0399708
OS 2.0778933 4.0486066
OS 2.0791134 4.057874
OS 2.0778933 4.0671414
OS 2.0743163 4.0757772
OS 2.068626 4.0831929
OS 2.0612103 4.0888832
OS 2.0525745 4.0924602
OS 2.0433071 4.0936803
OE
OB 1.4576771 4.0897433 H
OS 1.4484097 4.0885232
OS 1.4397739 4.0849462
OS 1.4323582 4.0792559
OS 1.4266679 4.0718402
OS 1.4230909 4.0632044
OS 1.4218708 4.053937
OS 1.4230909 4.0446696
OS 1.4266679 4.0360338
OS 1.4323582 4.0286181
OS 1.4397739 4.0229278
OS 1.4484097 4.0193508
OS 1.4576771 4.0181307
OS 1.4669445 4.0193508
OS 1.4755803 4.0229278
OS 1.482996 4.0286181
OS 1.4886863 4.0360338
OS 1.4922633 4.0446696
OS 1.4934834 4.053937
OS 1.4922633 4.0632044
OS 1.4886863 4.0718402
OS 1.482996 4.0792559
OS 1.4755803 4.0849462
OS 1.4669445 4.0885232
OS 1.4576771 4.0897433
OE
OB 1.9038425 4.0343765 H
OS 1.8975996 4.0331347
OS 1.8923071 4.0295984
OS 1.8887708 4.0243059
OS 1.887529 4.018063
OS 1.8887708 4.0118201
OS 1.8923071 4.0065276
OS 1.8975996 4.0029913
OS 1.9038425 4.0017495
OS 1.9100854 4.0029913
OS 1.9153779 4.0065276
OS 1.9189142 4.0118201
OS 1.920156 4.018063
OS 1.9189142 4.0243059
OS 1.9153779 4.0295984
OS 1.9100854 4.0331347
OS 1.9038425 4.0343765
OE
OB 2.3533464 4.03403 H
OS 2.3471035 4.0327882
OS 2.341811 4.0292519
OS 2.3382747 4.0239594
OS 2.3370329 4.0177165
OS 2.3382747 4.0114736
OS 2.341811 4.0061811
OS 2.3471035 4.0026448
OS 2.3533464 4.001403
OS 2.3595893 4.0026448
OS 2.3648818 4.0061811
OS 2.3684181 4.0114736
OS 2.3696599 4.0177165
OS 2.3684181 4.0239594
OS 2.3648818 4.0292519
OS 2.3595893 4.0327882
OS 2.3533464 4.03403
OE
OB 5.7234252 4.0832969 H
OS 5.7084897 4.0813306
OS 5.6945721 4.0755657
OS 5.6826207 4.0663951
OS 5.6734501 4.0544438
OS 5.6676852 4.0405261
OS 5.6657189 4.0255906
OS 5.6676852 4.0106551
OS 5.6734501 3.9967374
OS 5.6826207 3.9847861
OS 5.6945721 3.9756155
OS 5.7084897 3.9698506
OS 5.7234252 3.9678843
OS 5.7383607 3.9698506
OS 5.7522783 3.9756155
OS 5.7642297 3.9847861
OS 5.7734003 3.9967374
OS 5.7791652 4.0106551
OS 5.7811315 4.0255906
OS 5.7791652 4.0405261
OS 5.7734003 4.0544438
OS 5.7642297 4.0663951
OS 5.7522783 4.0755657
OS 5.7383607 4.0813306
OS 5.7234252 4.0832969
OE
OB 1.4084645 3.9966285 H
OS 1.4022216 3.9953867
OS 1.3969291 3.9918504
OS 1.3933928 3.9865579
OS 1.392151 3.980315
OS 1.3933928 3.9740721
OS 1.3969291 3.9687796
OS 1.4022216 3.9652433
OS 1.4084645 3.9640015
OS 1.4147074 3.9652433
OS 1.4199999 3.9687796
OS 1.4235362 3.9740721
OS 1.424778 3.980315
OS 1.4235362 3.9865579
OS 1.4199999 3.9918504
OS 1.4147074 3.9953867
OS 1.4084645 3.9966285
OE
OB 2.0848425 3.9123765 H
OS 2.0785996 3.9111347
OS 2.0733071 3.9075984
OS 2.0697708 3.9023059
OS 2.068529 3.896063
OS 2.0697708 3.8898201
OS 2.0699331 3.8895773
OS 2.0663282 3.8859724
OS 2.0660854 3.8861347
OS 2.0598425 3.8873765
OS 2.0535996 3.8861347
OS 2.0483071 3.8825984
OS 2.0447708 3.8773059
OS 2.043529 3.871063
OS 2.0447708 3.8648201
OS 2.0483071 3.8595276
OS 2.0535996 3.8559913
OS 2.0598425 3.8547495
OS 2.0660854 3.8559913
OS 2.0713779 3.8595276
OS 2.0749142 3.8648201
OS 2.076156 3.871063
OS 2.0749142 3.8773059
OS 2.0747519 3.8775487
OS 2.0783568 3.8811536
OS 2.0785996 3.8809913
OS 2.0848425 3.8797495
OS 2.0910854 3.8809913
OS 2.0963779 3.8845276
OS 2.0999142 3.8898201
OS 2.101156 3.896063
OS 2.0999142 3.9023059
OS 2.0963779 3.9075984
OS 2.0910854 3.9111347
OS 2.0848425 3.9123765
OE
OB 2.0298425 3.8523765 H
OS 2.0235996 3.8511347
OS 2.0183071 3.8475984
OS 2.0147708 3.8423059
OS 2.013529 3.836063
OS 2.0136749 3.8353296
OS 2.0130932 3.8343873
OS 2.0093423 3.8314814
OS 2.0048425 3.8323765
OS 1.9985996 3.8311347
OS 1.9933071 3.8275984
OS 1.9897708 3.8223059
OS 1.988529 3.816063
OS 1.9897708 3.8098201
OS 1.9933071 3.8045276
OS 1.9985996 3.8009913
OS 2.0048425 3.7997495
OS 2.0110854 3.8009913
OS 2.0163779 3.8045276
OS 2.0199142 3.8098201
OS 2.021156 3.816063
OS 2.0210101 3.8167964
OS 2.0215918 3.8177387
OS 2.0253427 3.8206446
OS 2.0298425 3.8197495
OS 2.0360854 3.8209913
OS 2.0413779 3.8245276
OS 2.0449142 3.8298201
OS 2.046156 3.836063
OS 2.0449142 3.8423059
OS 2.0413779 3.8475984
OS 2.0360854 3.8511347
OS 2.0298425 3.8523765
OE
OB 3.6998425 3.8523765 H
OS 3.6935996 3.8511347
OS 3.6883071 3.8475984
OS 3.6847708 3.8423059
OS 3.683529 3.836063
OS 3.6847708 3.8298201
OS 3.6883071 3.8245276
OS 3.6935996 3.8209913
OS 3.6998425 3.8197495
OS 3.7060854 3.8209913
OS 3.7113779 3.8245276
OS 3.7149142 3.8298201
OS 3.716156 3.836063
OS 3.7149142 3.8423059
OS 3.7113779 3.8475984
OS 3.7060854 3.8511347
OS 3.6998425 3.8523765
OE
OB 3.0148425 3.8473765 H
OS 3.0085996 3.8461347
OS 3.0033071 3.8425984
OS 2.9997708 3.8373059
OS 2.998529 3.831063
OS 2.9997708 3.8248201
OS 3.0033071 3.8195276
OS 3.0085996 3.8159913
OS 3.0148425 3.8147495
OS 3.0210854 3.8159913
OS 3.0263779 3.8195276
OS 3.0299142 3.8248201
OS 3.031156 3.831063
OS 3.0299142 3.8373059
OS 3.0263779 3.8425984
OS 3.0210854 3.8461347
OS 3.0148425 3.8473765
OE
OB 3.8298425 3.8223765 H
OS 3.8235996 3.8211347
OS 3.8183071 3.8175984
OS 3.8147708 3.8123059
OS 3.813529 3.806063
OS 3.8147708 3.7998201
OS 3.8183071 3.7945276
OS 3.8235996 3.7909913
OS 3.8298425 3.7897495
OS 3.8360854 3.7909913
OS 3.8413779 3.7945276
OS 3.8449142 3.7998201
OS 3.846156 3.806063
OS 3.8449142 3.8123059
OS 3.8413779 3.8175984
OS 3.8360854 3.8211347
OS 3.8298425 3.8223765
OE
OB 3.5398425 3.8223765 H
OS 3.5335996 3.8211347
OS 3.5283071 3.8175984
OS 3.5247708 3.8123059
OS 3.523529 3.806063
OS 3.5247708 3.7998201
OS 3.5283071 3.7945276
OS 3.5335996 3.7909913
OS 3.5398425 3.7897495
OS 3.5460854 3.7909913
OS 3.5513779 3.7945276
OS 3.5549142 3.7998201
OS 3.556156 3.806063
OS 3.5549142 3.8123059
OS 3.5513779 3.8175984
OS 3.5460854 3.8211347
OS 3.5398425 3.8223765
OE
OB 3.2198425 3.8223765 H
OS 3.2135996 3.8211347
OS 3.2083071 3.8175984
OS 3.2047708 3.8123059
OS 3.203529 3.806063
OS 3.2047708 3.7998201
OS 3.2083071 3.7945276
OS 3.2135996 3.7909913
OS 3.2198425 3.7897495
OS 3.2260854 3.7909913
OS 3.2313779 3.7945276
OS 3.2349142 3.7998201
OS 3.236156 3.806063
OS 3.2349142 3.8123059
OS 3.2313779 3.8175984
OS 3.2260854 3.8211347
OS 3.2198425 3.8223765
OE
OB 5.7234252 3.9021945 H
OS 5.7084897 3.9002282
OS 5.6945721 3.8944633
OS 5.6826207 3.8852927
OS 5.6734501 3.8733414
OS 5.6676852 3.8594237
OS 5.6657189 3.8444882
OS 5.6676852 3.8295527
OS 5.6734501 3.815635
OS 5.6826207 3.8036837
OS 5.6945721 3.7945131
OS 5.7084897 3.7887482
OS 5.7234252 3.7867819
OS 5.7383607 3.7887482
OS 5.7522783 3.7945131
OS 5.7642297 3.8036837
OS 5.7734003 3.815635
OS 5.7791652 3.8295527
OS 5.7811315 3.8444882
OS 5.7791652 3.8594237
OS 5.7734003 3.8733414
OS 5.7642297 3.8852927
OS 5.7522783 3.8944633
OS 5.7383607 3.9002282
OS 5.7234252 3.9021945
OE
OB 2.7224094 3.8023844 H
OS 2.7161665 3.8011426
OS 2.710874 3.7976063
OS 2.7073377 3.7923138
OS 2.7060959 3.7860709
OS 2.7073377 3.779828
OS 2.710874 3.7745355
OS 2.7161665 3.7709992
OS 2.7224094 3.7697574
OS 2.7286523 3.7709992
OS 2.7339448 3.7745355
OS 2.7374811 3.779828
OS 2.7387229 3.7860709
OS 2.7374811 3.7923138
OS 2.7339448 3.7976063
OS 2.7286523 3.8011426
OS 2.7224094 3.8023844
OE
OB 6.1690551 3.8775488 H
OS 6.0706299 3.8775488
OS 6.0556944 3.8755825
OS 6.0417767 3.8698176
OS 6.0298254 3.860647
OS 6.0206548 3.8486956
OS 6.0148899 3.834778
OS 6.0129236 3.8198425
OS 6.0148899 3.804907
OS 6.0206548 3.7909894
OS 6.0298254 3.779038
OS 6.0417767 3.7698674
OS 6.0556944 3.7641025
OS 6.0706299 3.7621362
OS 6.1690551 3.7621362
OS 6.1839906 3.7641025
OS 6.1979083 3.7698674
OS 6.2098596 3.779038
OS 6.2190302 3.7909894
OS 6.2247951 3.804907
OS 6.2267614 3.8198425
OS 6.2247951 3.834778
OS 6.2190302 3.8486956
OS 6.2098596 3.860647
OS 6.1979083 3.8698176
OS 6.1839906 3.8755825
OS 6.1690551 3.8775488
OE
OB 4.2548425 3.7923765 H
OS 4.2485996 3.7911347
OS 4.2433071 3.7875984
OS 4.2397708 3.7823059
OS 4.238529 3.776063
OS 4.2397708 3.7698201
OS 4.2433071 3.7645276
OS 4.2485996 3.7609913
OS 4.2548425 3.7597495
OS 4.2610854 3.7609913
OS 4.2663779 3.7645276
OS 4.2699142 3.7698201
OS 4.271156 3.776063
OS 4.2699142 3.7823059
OS 4.2663779 3.7875984
OS 4.2610854 3.7911347
OS 4.2548425 3.7923765
OE
OB 6.9001969 3.8637693 H
OS 6.8852614 3.861803
OS 6.8713437 3.8560381
OS 6.8593924 3.8468675
OS 6.8502218 3.8349162
OS 6.8444569 3.8209985
OS 6.8424906 3.806063
OS 6.8444569 3.7911275
OS 6.8502218 3.7772098
OS 6.8593924 3.7652585
OS 6.8713437 3.7560879
OS 6.8852614 3.750323
OS 6.9001969 3.7483567
OS 6.9151324 3.750323
OS 6.9290501 3.7560879
OS 6.9410014 3.7652585
OS 6.950172 3.7772098
OS 6.9559369 3.7911275
OS 6.9579032 3.806063
OS 6.9559369 3.8209985
OS 6.950172 3.8349162
OS 6.9410014 3.8468675
OS 6.9290501 3.8560381
OS 6.9151324 3.861803
OS 6.9001969 3.8637693
OE
OB 6.7348425 3.8637693 H
OS 6.719907 3.861803
OS 6.7059893 3.8560381
OS 6.694038 3.8468675
OS 6.6848674 3.8349162
OS 6.6791025 3.8209985
OS 6.6771362 3.806063
OS 6.6791025 3.7911275
OS 6.6848674 3.7772098
OS 6.694038 3.7652585
OS 6.7059893 3.7560879
OS 6.719907 3.750323
OS 6.7348425 3.7483567
OS 6.749778 3.750323
OS 6.7636957 3.7560879
OS 6.775647 3.7652585
OS 6.7848176 3.7772098
OS 6.7905825 3.7911275
OS 6.7925488 3.806063
OS 6.7905825 3.8209985
OS 6.7848176 3.8349162
OS 6.775647 3.8468675
OS 6.7636957 3.8560381
OS 6.749778 3.861803
OS 6.7348425 3.8637693
OE
OB 6.5694882 3.8637693 H
OS 6.5545527 3.861803
OS 6.540635 3.8560381
OS 6.5286837 3.8468675
OS 6.5195131 3.8349161
OS 6.5137482 3.8209985
OS 6.5117819 3.806063
OS 6.5137482 3.7911275
OS 6.5195131 3.7772099
OS 6.5286837 3.7652585
OS 6.540635 3.7560879
OS 6.5545527 3.750323
OS 6.5694882 3.7483567
OS 6.5844237 3.750323
OS 6.5983414 3.7560879
OS 6.6102927 3.7652585
OS 6.6194633 3.7772099
OS 6.6252282 3.7911275
OS 6.6271945 3.806063
OS 6.6252282 3.8209985
OS 6.6194633 3.8349161
OS 6.6102927 3.8468675
OS 6.5983414 3.8560381
OS 6.5844237 3.861803
OS 6.5694882 3.8637693
OE
OB 3.6998425 3.7673765 H
OS 3.6935996 3.7661347
OS 3.6883071 3.7625984
OS 3.6847708 3.7573059
OS 3.683529 3.751063
OS 3.6847708 3.7448201
OS 3.6883071 3.7395276
OS 3.6935996 3.7359913
OS 3.6998425 3.7347495
OS 3.7060854 3.7359913
OS 3.7113779 3.7395276
OS 3.7149142 3.7448201
OS 3.716156 3.751063
OS 3.7149142 3.7573059
OS 3.7113779 3.7625984
OS 3.7060854 3.7661347
OS 3.6998425 3.7673765
OE
OB 2.9933858 3.7673765 H
OS 2.9871429 3.7661347
OS 2.9818504 3.7625984
OS 2.9783141 3.7573059
OS 2.9770723 3.751063
OS 2.9783141 3.7448201
OS 2.9818504 3.7395276
OS 2.9871429 3.7359913
OS 2.9933858 3.7347495
OS 2.9996287 3.7359913
OS 3.0049212 3.7395276
OS 3.0084575 3.7448201
OS 3.0096993 3.751063
OS 3.0084575 3.7573059
OS 3.0049212 3.7625984
OS 2.9996287 3.7661347
OS 2.9933858 3.7673765
OE
OB 6.2948425 3.7173765 H
OS 6.2885996 3.7161347
OS 6.2833071 3.7125984
OS 6.2797708 3.7073059
OS 6.278529 3.701063
OS 6.2797708 3.6948201
OS 6.2833071 3.6895276
OS 6.2885996 3.6859913
OS 6.2948425 3.6847495
OS 6.3010854 3.6859913
OS 6.3063779 3.6895276
OS 6.3099142 3.6948201
OS 6.311156 3.701063
OS 6.3099142 3.7073059
OS 6.3063779 3.7125984
OS 6.3010854 3.7161347
OS 6.2948425 3.7173765
OE
OB 1.8498425 3.7173765 H
OS 1.8435996 3.7161347
OS 1.8383071 3.7125984
OS 1.8347708 3.7073059
OS 1.833529 3.701063
OS 1.8347708 3.6948201
OS 1.8383071 3.6895276
OS 1.8435996 3.6859913
OS 1.8498425 3.6847495
OS 1.8560854 3.6859913
OS 1.8613779 3.6895276
OS 1.8649142 3.6948201
OS 1.866156 3.701063
OS 1.8649142 3.7073059
OS 1.8613779 3.7125984
OS 1.8560854 3.7161347
OS 1.8498425 3.7173765
OE
OB 4.0498425 3.6813765 H
OS 4.0435996 3.6801347
OS 4.0383071 3.6765984
OS 4.0347708 3.6713059
OS 4.033529 3.665063
OS 4.0347708 3.6588201
OS 4.0383071 3.6535276
OS 4.0435996 3.6499913
OS 4.0498425 3.6487495
OS 4.0560854 3.6499913
OS 4.0613779 3.6535276
OS 4.0649142 3.6588201
OS 4.066156 3.665063
OS 4.0649142 3.6713059
OS 4.0613779 3.6765984
OS 4.0560854 3.6801347
OS 4.0498425 3.6813765
OE
OB 2.6798425 3.6773765 H
OS 2.6735996 3.6761347
OS 2.6683071 3.6725984
OS 2.6647708 3.6673059
OS 2.663529 3.661063
OS 2.6647708 3.6548201
OS 2.6683071 3.6495276
OS 2.6735996 3.6459913
OS 2.6798425 3.6447495
OS 2.6860854 3.6459913
OS 2.6913779 3.6495276
OS 2.6949142 3.6548201
OS 2.696156 3.661063
OS 2.6949142 3.6673059
OS 2.6913779 3.6725984
OS 2.6860854 3.6761347
OS 2.6798425 3.6773765
OE
OB 1.7548425 3.6773765 H
OS 1.7485996 3.6761347
OS 1.7433071 3.6725984
OS 1.7397708 3.6673059
OS 1.738529 3.661063
OS 1.7397708 3.6548201
OS 1.7433071 3.6495276
OS 1.7485996 3.6459913
OS 1.7548425 3.6447495
OS 1.7610854 3.6459913
OS 1.7663779 3.6495276
OS 1.7699142 3.6548201
OS 1.771156 3.661063
OS 1.7699142 3.6673059
OS 1.7663779 3.6725984
OS 1.7610854 3.6761347
OS 1.7548425 3.6773765
OE
OB 3.4248425 3.6523765 H
OS 3.4185996 3.6511347
OS 3.4133071 3.6475984
OS 3.4097708 3.6423059
OS 3.408529 3.636063
OS 3.4097708 3.6298201
OS 3.4133071 3.6245276
OS 3.4185996 3.6209913
OS 3.4248425 3.6197495
OS 3.4310854 3.6209913
OS 3.4363779 3.6245276
OS 3.4399142 3.6298201
OS 3.441156 3.636063
OS 3.4399142 3.6423059
OS 3.4363779 3.6475984
OS 3.4310854 3.6511347
OS 3.4248425 3.6523765
OE
OB 2.7998425 3.6323765 H
OS 2.7935996 3.6311347
OS 2.7883071 3.6275984
OS 2.7847708 3.6223059
OS 2.783529 3.616063
OS 2.7847708 3.6098201
OS 2.7883071 3.6045276
OS 2.7935996 3.6009913
OS 2.7998425 3.5997495
OS 2.8060854 3.6009913
OS 2.8113779 3.6045276
OS 2.8149142 3.6098201
OS 2.816156 3.616063
OS 2.8149142 3.6223059
OS 2.8113779 3.6275984
OS 2.8060854 3.6311347
OS 2.7998425 3.6323765
OE
OB 2.1398425 3.6273765 H
OS 2.1335996 3.6261347
OS 2.1283071 3.6225984
OS 2.1247708 3.6173059
OS 2.123529 3.611063
OS 2.1247708 3.6048201
OS 2.1283071 3.5995276
OS 2.1335996 3.5959913
OS 2.1398425 3.5947495
OS 2.1460854 3.5959913
OS 2.1513779 3.5995276
OS 2.1549142 3.6048201
OS 2.156156 3.611063
OS 2.1549142 3.6173059
OS 2.1513779 3.6225984
OS 2.1460854 3.6261347
OS 2.1398425 3.6273765
OE
OB 1.8848425 3.6173765 H
OS 1.8785996 3.6161347
OS 1.8733071 3.6125984
OS 1.8697708 3.6073059
OS 1.868529 3.601063
OS 1.8697708 3.5948201
OS 1.8733071 3.5895276
OS 1.8785996 3.5859913
OS 1.8848425 3.5847495
OS 1.8910854 3.5859913
OS 1.8963779 3.5895276
OS 1.8999142 3.5948201
OS 1.901156 3.601063
OS 1.8999142 3.6073059
OS 1.8963779 3.6125984
OS 1.8910854 3.6161347
OS 1.8848425 3.6173765
OE
OB 3.2398425 3.6123765 H
OS 3.2335996 3.6111347
OS 3.2283071 3.6075984
OS 3.2247708 3.6023059
OS 3.223529 3.596063
OS 3.2247708 3.5898201
OS 3.2283071 3.5845276
OS 3.2335996 3.5809913
OS 3.2398425 3.5797495
OS 3.2460854 3.5809913
OS 3.2513779 3.5845276
OS 3.2549142 3.5898201
OS 3.256156 3.596063
OS 3.2549142 3.6023059
OS 3.2513779 3.6075984
OS 3.2460854 3.6111347
OS 3.2398425 3.6123765
OE
OB 1.5498425 3.6373765 H
OS 1.5435996 3.6361347
OS 1.5383071 3.6325984
OS 1.5347708 3.6273059
OS 1.533529 3.621063
OS 1.5347708 3.6148201
OS 1.5383071 3.6095276
OS 1.5435996 3.6059913
OS 1.5498425 3.6047495
OS 1.5560854 3.6059913
OS 1.5563282 3.6061536
OS 1.5599331 3.6025487
OS 1.5597708 3.6023059
OS 1.558529 3.596063
OS 1.5597708 3.5898201
OS 1.5633071 3.5845276
OS 1.5685996 3.5809913
OS 1.5748425 3.5797495
OS 1.5810854 3.5809913
OS 1.5863779 3.5845276
OS 1.5899142 3.5898201
OS 1.591156 3.596063
OS 1.5899142 3.6023059
OS 1.5863779 3.6075984
OS 1.5810854 3.6111347
OS 1.5748425 3.6123765
OS 1.5685996 3.6111347
OS 1.5683568 3.6109724
OS 1.5647519 3.6145773
OS 1.5649142 3.6148201
OS 1.566156 3.621063
OS 1.5649142 3.6273059
OS 1.5613779 3.6325984
OS 1.5560854 3.6361347
OS 1.5498425 3.6373765
OE
OB 2.4223425 3.6247884 H
OS 2.4133837 3.6230064
OS 2.4057888 3.6179317
OS 2.4007141 3.6103368
OS 2.3989321 3.601378
OS 2.4007141 3.5924192
OS 2.4057888 3.5848243
OS 2.4133837 3.5797496
OS 2.4223425 3.5779676
OS 2.4313013 3.5797496
OS 2.4388962 3.5848243
OS 2.4439709 3.5924192
OS 2.4457529 3.601378
OS 2.4439709 3.6103368
OS 2.4388962 3.6179317
OS 2.4313013 3.6230064
OS 2.4223425 3.6247884
OE
OB 2.7748425 3.5823765 H
OS 2.7685996 3.5811347
OS 2.7633071 3.5775984
OS 2.7597708 3.5723059
OS 2.758529 3.566063
OS 2.7597708 3.5598201
OS 2.7633071 3.5545276
OS 2.7685996 3.5509913
OS 2.7748425 3.5497495
OS 2.7810854 3.5509913
OS 2.7863779 3.5545276
OS 2.7899142 3.5598201
OS 2.791156 3.566063
OS 2.7899142 3.5723059
OS 2.7863779 3.5775984
OS 2.7810854 3.5811347
OS 2.7748425 3.5823765
OE
OB 1.4408425 3.5733765 H
OS 1.4345996 3.5721347
OS 1.4293071 3.5685984
OS 1.4257708 3.5633059
OS 1.424529 3.557063
OS 1.4257708 3.5508201
OS 1.4293071 3.5455276
OS 1.4345996 3.5419913
OS 1.4408425 3.5407495
OS 1.4470854 3.5419913
OS 1.4523779 3.5455276
OS 1.4559142 3.5508201
OS 1.457156 3.557063
OS 1.4559142 3.5633059
OS 1.4523779 3.5685984
OS 1.4470854 3.5721347
OS 1.4408425 3.5733765
OE
OB 5.9948425 3.5683765 H
OS 5.9885996 3.5671347
OS 5.9833071 3.5635984
OS 5.9797708 3.5583059
OS 5.978529 3.552063
OS 5.9797708 3.5458201
OS 5.9833071 3.5405276
OS 5.9885996 3.5369913
OS 5.9948425 3.5357495
OS 6.0010854 3.5369913
OS 6.0063779 3.5405276
OS 6.0099142 3.5458201
OS 6.011156 3.552063
OS 6.0099142 3.5583059
OS 6.0063779 3.5635984
OS 6.0010854 3.5671347
OS 5.9948425 3.5683765
OE
OB 2.4348425 3.5623765 H
OS 2.4285996 3.5611347
OS 2.4233071 3.5575984
OS 2.4197708 3.5523059
OS 2.418529 3.546063
OS 2.4197708 3.5398201
OS 2.4233071 3.5345276
OS 2.4285996 3.5309913
OS 2.4348425 3.5297495
OS 2.4410854 3.5309913
OS 2.4463779 3.5345276
OS 2.4499142 3.5398201
OS 2.451156 3.546063
OS 2.4499142 3.5523059
OS 2.4463779 3.5575984
OS 2.4410854 3.5611347
OS 2.4348425 3.5623765
OE
OB 2.2548425 3.5523765 H
OS 2.2485996 3.5511347
OS 2.2433071 3.5475984
OS 2.2397708 3.5423059
OS 2.238529 3.536063
OS 2.2397708 3.5298201
OS 2.2424883 3.5257531
OS 2.2396399 3.5214222
OS 2.2348425 3.5223765
OS 2.2285996 3.5211347
OS 2.2233071 3.5175984
OS 2.2197708 3.5123059
OS 2.218529 3.506063
OS 2.2197708 3.4998201
OS 2.2233071 3.4945276
OS 2.2285996 3.4909913
OS 2.2348425 3.4897495
OS 2.2410854 3.4909913
OS 2.2463779 3.4945276
OS 2.2499142 3.4998201
OS 2.251156 3.506063
OS 2.2499142 3.5123059
OS 2.2471967 3.5163729
OS 2.2500451 3.5207038
OS 2.2548425 3.5197495
OS 2.2610854 3.5209913
OS 2.2663779 3.5245276
OS 2.2699142 3.5298201
OS 2.271156 3.536063
OS 2.2699142 3.5423059
OS 2.2663779 3.5475984
OS 2.2610854 3.5511347
OS 2.2548425 3.5523765
OE
OB 5.2748425 3.5273765 H
OS 5.2685996 3.5261347
OS 5.2633071 3.5225984
OS 5.2597708 3.5173059
OS 5.258529 3.511063
OS 5.2597708 3.5048201
OS 5.2633071 3.4995276
OS 5.2685996 3.4959913
OS 5.2748425 3.4947495
OS 5.2810854 3.4959913
OS 5.2863779 3.4995276
OS 5.2899142 3.5048201
OS 5.291156 3.511063
OS 5.2899142 3.5173059
OS 5.2863779 3.5225984
OS 5.2810854 3.5261347
OS 5.2748425 3.5273765
OE
OB 3.6228425 3.5023765 H
OS 3.6165996 3.5011347
OS 3.6113071 3.4975984
OS 3.6077708 3.4923059
OS 3.606529 3.486063
OS 3.6077708 3.4798201
OS 3.6113071 3.4745276
OS 3.6165996 3.4709913
OS 3.6228425 3.4697495
OS 3.6290854 3.4709913
OS 3.6343779 3.4745276
OS 3.6379142 3.4798201
OS 3.639156 3.486063
OS 3.6379142 3.4923059
OS 3.6343779 3.4975984
OS 3.6290854 3.5011347
OS 3.6228425 3.5023765
OE
OB 2.5798425 3.5023765 H
OS 2.5735996 3.5011347
OS 2.5683071 3.4975984
OS 2.5647708 3.4923059
OS 2.563529 3.486063
OS 2.5647708 3.4798201
OS 2.5683071 3.4745276
OS 2.5735996 3.4709913
OS 2.5798425 3.4697495
OS 2.5860854 3.4709913
OS 2.5913779 3.4745276
OS 2.5949142 3.4798201
OS 2.596156 3.486063
OS 2.5949142 3.4923059
OS 2.5913779 3.4975984
OS 2.5860854 3.5011347
OS 2.5798425 3.5023765
OE
OB 3.5298425 3.4973765 H
OS 3.5235996 3.4961347
OS 3.5183071 3.4925984
OS 3.5147708 3.4873059
OS 3.513529 3.481063
OS 3.5147708 3.4748201
OS 3.5183071 3.4695276
OS 3.5235996 3.4659913
OS 3.5298425 3.4647495
OS 3.5360854 3.4659913
OS 3.5413779 3.4695276
OS 3.5449142 3.4748201
OS 3.546156 3.481063
OS 3.5449142 3.4873059
OS 3.5413779 3.4925984
OS 3.5360854 3.4961347
OS 3.5298425 3.4973765
OE
OB 2.3898425 3.4973765 H
OS 2.3835996 3.4961347
OS 2.3783071 3.4925984
OS 2.3747708 3.4873059
OS 2.373529 3.481063
OS 2.3747708 3.4748201
OS 2.3783071 3.4695276
OS 2.3835996 3.4659913
OS 2.3898425 3.4647495
OS 2.3960854 3.4659913
OS 2.4013779 3.4695276
OS 2.4049142 3.4748201
OS 2.406156 3.481063
OS 2.4049142 3.4873059
OS 2.4013779 3.4925984
OS 2.3960854 3.4961347
OS 2.3898425 3.4973765
OE
OB 6.5098425 3.4723765 H
OS 6.5035996 3.4711347
OS 6.4983071 3.4675984
OS 6.4947708 3.4623059
OS 6.493529 3.456063
OS 6.4947708 3.4498201
OS 6.4983071 3.4445276
OS 6.5035996 3.4409913
OS 6.5098425 3.4397495
OS 6.5160854 3.4409913
OS 6.5213779 3.4445276
OS 6.5249142 3.4498201
OS 6.526156 3.456063
OS 6.5249142 3.4623059
OS 6.5213779 3.4675984
OS 6.5160854 3.4711347
OS 6.5098425 3.4723765
OE
OB 3.4368425 3.4733765 H
OS 3.4305996 3.4721347
OS 3.4253071 3.4685984
OS 3.4217708 3.4633059
OS 3.420529 3.457063
OS 3.4217708 3.4508201
OS 3.4253071 3.4455276
OS 3.4305996 3.4419913
OS 3.4368425 3.4407495
OS 3.4430854 3.4419913
OS 3.4483779 3.4455276
OS 3.4502305 3.4483003
OS 3.4506142 3.4484287
OS 3.4560152 3.4479578
OS 3.4583071 3.4445276
OS 3.4635996 3.4409913
OS 3.4698425 3.4397495
OS 3.4760854 3.4409913
OS 3.4813779 3.4445276
OS 3.4849142 3.4498201
OS 3.486156 3.456063
OS 3.4849142 3.4623059
OS 3.4813779 3.4675984
OS 3.4760854 3.4711347
OS 3.4698425 3.4723765
OS 3.4635996 3.4711347
OS 3.4583071 3.4675984
OS 3.4564545 3.4648257
OS 3.4560708 3.4646973
OS 3.4506698 3.4651682
OS 3.4483779 3.4685984
OS 3.4430854 3.4721347
OS 3.4368425 3.4733765
OE
OB 3.3588425 3.4643765 H
OS 3.3525996 3.4631347
OS 3.3473071 3.4595984
OS 3.3437708 3.4543059
OS 3.342529 3.448063
OS 3.3437708 3.4418201
OS 3.3473071 3.4365276
OS 3.3525996 3.4329913
OS 3.3588425 3.4317495
OS 3.3650854 3.4329913
OS 3.3703779 3.4365276
OS 3.3739142 3.4418201
OS 3.3741941 3.443227
OS 3.379292 3.443227
OS 3.3797708 3.4408201
OS 3.3833071 3.4355276
OS 3.3885996 3.4319913
OS 3.3948425 3.4307495
OS 3.4010854 3.4319913
OS 3.4063779 3.4355276
OS 3.4099142 3.4408201
OS 3.411156 3.447063
OS 3.4099142 3.4533059
OS 3.4063779 3.4585984
OS 3.4010854 3.4621347
OS 3.3948425 3.4633765
OS 3.3885996 3.4621347
OS 3.3833071 3.4585984
OS 3.3797708 3.4533059
OS 3.3794909 3.451899
OS 3.374393 3.451899
OS 3.3739142 3.4543059
OS 3.3703779 3.4595984
OS 3.3650854 3.4631347
OS 3.3588425 3.4643765
OE
OB 2.4223425 3.4673081 H
OS 2.4133837 3.4655261
OS 2.4057888 3.4604514
OS 2.4007141 3.4528565
OS 2.3989321 3.4438977
OS 2.4007141 3.4349389
OS 2.4057888 3.427344
OS 2.4133837 3.4222693
OS 2.4223425 3.4204873
OS 2.4313013 3.4222693
OS 2.4388962 3.427344
OS 2.4439709 3.4349389
OS 2.4457529 3.4438977
OS 2.4439709 3.4528565
OS 2.4388962 3.4604514
OS 2.4313013 3.4655261
OS 2.4223425 3.4673081
OE
OB 6.4798425 3.4423765 H
OS 6.4735996 3.4411347
OS 6.4683071 3.4375984
OS 6.4647708 3.4323059
OS 6.463529 3.426063
OS 6.4647708 3.4198201
OS 6.4683071 3.4145276
OS 6.4735996 3.4109913
OS 6.4798425 3.4097495
OS 6.4860854 3.4109913
OS 6.4913779 3.4145276
OS 6.4949142 3.4198201
OS 6.496156 3.426063
OS 6.4949142 3.4323059
OS 6.4913779 3.4375984
OS 6.4860854 3.4411347
OS 6.4798425 3.4423765
OE
OB 2.6348425 3.4223765 H
OS 2.6285996 3.4211347
OS 2.6233071 3.4175984
OS 2.6197708 3.4123059
OS 2.618529 3.406063
OS 2.6197708 3.3998201
OS 2.6233071 3.3945276
OS 2.6285996 3.3909913
OS 2.6348425 3.3897495
OS 2.6410854 3.3909913
OS 2.6463779 3.3945276
OS 2.6499142 3.3998201
OS 2.651156 3.406063
OS 2.6499142 3.4123059
OS 2.6463779 3.4175984
OS 2.6410854 3.4211347
OS 2.6348425 3.4223765
OE
OB 6.4475772 3.4123765 H
OS 6.4413343 3.4111347
OS 6.4360418 3.4075984
OS 6.4325055 3.4023059
OS 6.4312637 3.396063
OS 6.4325055 3.3898201
OS 6.4360418 3.3845276
OS 6.4413343 3.3809913
OS 6.4475772 3.3797495
OS 6.4538201 3.3809913
OS 6.4591126 3.3845276
OS 6.4626489 3.3898201
OS 6.4638907 3.396063
OS 6.4626489 3.4023059
OS 6.4591126 3.4075984
OS 6.4538201 3.4111347
OS 6.4475772 3.4123765
OE
OB 3.0688976 3.4119828 H
OS 3.0626547 3.410741
OS 3.0573622 3.4072047
OS 3.0538259 3.4019122
OS 3.0525841 3.3956693
OS 3.0538259 3.3894264
OS 3.0573622 3.3841339
OS 3.0626547 3.3805976
OS 3.0688976 3.3793558
OS 3.0751405 3.3805976
OS 3.080433 3.3841339
OS 3.0839693 3.3894264
OS 3.0852111 3.3956693
OS 3.0839693 3.4019122
OS 3.080433 3.4072047
OS 3.0751405 3.410741
OS 3.0688976 3.4119828
OE
OB 6.4098425 3.3873765 H
OS 6.4035996 3.3861347
OS 6.3983071 3.3825984
OS 6.3947708 3.3773059
OS 6.393529 3.371063
OS 6.3947708 3.3648201
OS 6.3983071 3.3595276
OS 6.4035996 3.3559913
OS 6.4098425 3.3547495
OS 6.4160854 3.3559913
OS 6.4213779 3.3595276
OS 6.4249142 3.3648201
OS 6.426156 3.371063
OS 6.4249142 3.3773059
OS 6.4213779 3.3825984
OS 6.4160854 3.3861347
OS 6.4098425 3.3873765
OE
OB 3.3028425 3.3603765 H
OS 3.2965996 3.3591347
OS 3.2913071 3.3555984
OS 3.2877708 3.3503059
OS 3.286529 3.344063
OS 3.2877708 3.3378201
OS 3.2913071 3.3325276
OS 3.2965996 3.3289913
OS 3.3028425 3.3277495
OS 3.3090854 3.3289913
OS 3.3143779 3.3325276
OS 3.3179142 3.3378201
OS 3.319156 3.344063
OS 3.3179142 3.3503059
OS 3.3143779 3.3555984
OS 3.3090854 3.3591347
OS 3.3028425 3.3603765
OE
OB 6.3547483 3.3474519 H
OS 6.3485054 3.3462101
OS 6.3432129 3.3426738
OS 6.3396766 3.3373813
OS 6.3384348 3.3311384
OS 6.3396766 3.3248955
OS 6.3432129 3.319603
OS 6.3485054 3.3160667
OS 6.3547483 3.3148249
OS 6.3609912 3.3160667
OS 6.3662837 3.319603
OS 6.36982 3.3248955
OS 6.3710618 3.3311384
OS 6.36982 3.3373813
OS 6.3662837 3.3426738
OS 6.3609912 3.3462101
OS 6.3547483 3.3474519
OE
OB 3.542865 3.335354 H
OS 3.5366221 3.3341122
OS 3.5313296 3.3305759
OS 3.5277933 3.3252834
OS 3.5265515 3.3190405
OS 3.5277933 3.3127976
OS 3.5313296 3.3075051
OS 3.5366221 3.3039688
OS 3.542865 3.302727
OS 3.5491079 3.3039688
OS 3.5544004 3.3075051
OS 3.5579367 3.3127976
OS 3.5591785 3.3190405
OS 3.5579367 3.3252834
OS 3.5544004 3.3305759
OS 3.5491079 3.3341122
OS 3.542865 3.335354
OE
OB 3.2636972 3.3202312 H
OS 3.2574543 3.3189894
OS 3.2521618 3.3154531
OS 3.2486255 3.3101606
OS 3.2473837 3.3039177
OS 3.2486255 3.2976748
OS 3.2521618 3.2923823
OS 3.2574543 3.288846
OS 3.2636972 3.2876042
OS 3.2699401 3.288846
OS 3.2752326 3.2923823
OS 3.2787689 3.2976748
OS 3.2800107 3.3039177
OS 3.2787689 3.3101606
OS 3.2752326 3.3154531
OS 3.2699401 3.3189894
OS 3.2636972 3.3202312
OE
OB 3.4918425 3.3133765 H
OS 3.4855996 3.3121347
OS 3.4803071 3.3085984
OS 3.4767708 3.3033059
OS 3.475529 3.297063
OS 3.4767708 3.2908201
OS 3.4803071 3.2855276
OS 3.4855996 3.2819913
OS 3.4918425 3.2807495
OS 3.4980854 3.2819913
OS 3.5033779 3.2855276
OS 3.5069142 3.2908201
OS 3.508156 3.297063
OS 3.5069142 3.3033059
OS 3.5033779 3.3085984
OS 3.4980854 3.3121347
OS 3.4918425 3.3133765
OE
OB 3.6538425 3.3093765 H
OS 3.6475996 3.3081347
OS 3.6423071 3.3045984
OS 3.6387708 3.2993059
OS 3.637529 3.293063
OS 3.6387708 3.2868201
OS 3.6423071 3.2815276
OS 3.6475996 3.2779913
OS 3.6538425 3.2767495
OS 3.6600854 3.2779913
OS 3.6653779 3.2815276
OS 3.6689142 3.2868201
OS 3.670156 3.293063
OS 3.6689142 3.2993059
OS 3.6653779 3.3045984
OS 3.6600854 3.3081347
OS 3.6538425 3.3093765
OE
OB 6.4448425 3.3073765 H
OS 6.4385996 3.3061347
OS 6.4333071 3.3025984
OS 6.4297708 3.2973059
OS 6.428529 3.291063
OS 6.4297708 3.2848201
OS 6.4333071 3.2795276
OS 6.4385996 3.2759913
OS 6.4448425 3.2747495
OS 6.4510854 3.2759913
OS 6.4563779 3.2795276
OS 6.4599142 3.2848201
OS 6.461156 3.291063
OS 6.4599142 3.2973059
OS 6.4563779 3.3025984
OS 6.4510854 3.3061347
OS 6.4448425 3.3073765
OE
OB 2.5908425 3.3043765 H
OS 2.5845996 3.3031347
OS 2.5793071 3.2995984
OS 2.5757708 3.2943059
OS 2.574529 3.288063
OS 2.5757708 3.2818201
OS 2.5793071 3.2765276
OS 2.5845996 3.2729913
OS 2.5908425 3.2717495
OS 2.5970854 3.2729913
OS 2.6023779 3.2765276
OS 2.6059142 3.2818201
OS 2.607156 3.288063
OS 2.6059142 3.2943059
OS 2.6023779 3.2995984
OS 2.5970854 3.3031347
OS 2.5908425 3.3043765
OE
OB 3.3748425 3.2893765 H
OS 3.3685996 3.2881347
OS 3.3633071 3.2845984
OS 3.3597708 3.2793059
OS 3.358529 3.273063
OS 3.3597708 3.2668201
OS 3.3633071 3.2615276
OS 3.3685996 3.2579913
OS 3.3748425 3.2567495
OS 3.3810854 3.2579913
OS 3.3863779 3.2615276
OS 3.3899142 3.2668201
OS 3.391156 3.273063
OS 3.3899142 3.2793059
OS 3.3863779 3.2845984
OS 3.3810854 3.2881347
OS 3.3748425 3.2893765
OE
OB 6.3348425 3.2823765 H
OS 6.3285996 3.2811347
OS 6.3233071 3.2775984
OS 6.3197708 3.2723059
OS 6.318529 3.266063
OS 6.3197708 3.2598201
OS 6.3233071 3.2545276
OS 6.3285996 3.2509913
OS 6.3348425 3.2497495
OS 6.3410854 3.2509913
OS 6.3463779 3.2545276
OS 6.3499142 3.2598201
OS 6.351156 3.266063
OS 6.3499142 3.2723059
OS 6.3463779 3.2775984
OS 6.3410854 3.2811347
OS 6.3348425 3.2823765
OE
OB 3.7448425 3.2773765 H
OS 3.7385996 3.2761347
OS 3.7333071 3.2725984
OS 3.7297708 3.2673059
OS 3.728529 3.261063
OS 3.7297708 3.2548201
OS 3.7333071 3.2495276
OS 3.7385996 3.2459913
OS 3.7448425 3.2447495
OS 3.7510854 3.2459913
OS 3.7563779 3.2495276
OS 3.7599142 3.2548201
OS 3.761156 3.261063
OS 3.7599142 3.2673059
OS 3.7563779 3.2725984
OS 3.7510854 3.2761347
OS 3.7448425 3.2773765
OE
OB 2.2598425 3.2773765 H
OS 2.2535996 3.2761347
OS 2.2483071 3.2725984
OS 2.2447708 3.2673059
OS 2.243529 3.261063
OS 2.2447708 3.2548201
OS 2.2483071 3.2495276
OS 2.2535996 3.2459913
OS 2.2598425 3.2447495
OS 2.2660854 3.2459913
OS 2.2713779 3.2495276
OS 2.2749142 3.2548201
OS 2.276156 3.261063
OS 2.2749142 3.2673059
OS 2.2713779 3.2725984
OS 2.2660854 3.2761347
OS 2.2598425 3.2773765
OE
OB 3.2308425 3.2513765 H
OS 3.2245996 3.2501347
OS 3.2193071 3.2465984
OS 3.2157708 3.2413059
OS 3.214529 3.235063
OS 3.2157708 3.2288201
OS 3.2193071 3.2235276
OS 3.2245996 3.2199913
OS 3.2308425 3.2187495
OS 3.2370854 3.2199913
OS 3.2423779 3.2235276
OS 3.2459142 3.2288201
OS 3.247156 3.235063
OS 3.2459142 3.2413059
OS 3.2423779 3.2465984
OS 3.2370854 3.2501347
OS 3.2308425 3.2513765
OE
OB 6.2824161 3.2423765 H
OS 6.2761732 3.2411347
OS 6.2708807 3.2375984
OS 6.2673444 3.2323059
OS 6.2661026 3.226063
OS 6.2673444 3.2198201
OS 6.2708807 3.2145276
OS 6.2761732 3.2109913
OS 6.2824161 3.2097495
OS 6.288659 3.2109913
OS 6.2939515 3.2145276
OS 6.2974878 3.2198201
OS 6.2987296 3.226063
OS 6.2974878 3.2323059
OS 6.2939515 3.2375984
OS 6.288659 3.2411347
OS 6.2824161 3.2423765
OE
OB 3.8068425 3.2513765 H
OS 3.8005996 3.2501347
OS 3.7953071 3.2465984
OS 3.7917708 3.2413059
OS 3.790529 3.235063
OS 3.7917708 3.2288201
OS 3.7953071 3.2235276
OS 3.7975621 3.2220209
OS 3.7965063 3.2167129
OS 3.7935996 3.2161347
OS 3.7883071 3.2125984
OS 3.7847708 3.2073059
OS 3.783529 3.201063
OS 3.7847708 3.1948201
OS 3.7883071 3.1895276
OS 3.7935996 3.1859913
OS 3.7998425 3.1847495
OS 3.8060854 3.1859913
OS 3.8113779 3.1895276
OS 3.8149142 3.1948201
OS 3.816156 3.201063
OS 3.8149142 3.2073059
OS 3.8113779 3.2125984
OS 3.8091229 3.2141051
OS 3.8101787 3.2194131
OS 3.8130854 3.2199913
OS 3.8183779 3.2235276
OS 3.8219142 3.2288201
OS 3.823156 3.235063
OS 3.8219142 3.2413059
OS 3.8183779 3.2465984
OS 3.8130854 3.2501347
OS 3.8068425 3.2513765
OE
OB 2.2058425 3.2163765 H
OS 2.1995996 3.2151347
OS 2.1943071 3.2115984
OS 2.1907708 3.2063059
OS 2.189529 3.200063
OS 2.1907708 3.1938201
OS 2.1943071 3.1885276
OS 2.1995996 3.1849913
OS 2.2058425 3.1837495
OS 2.2120854 3.1849913
OS 2.2173779 3.1885276
OS 2.2209142 3.1938201
OS 2.222156 3.200063
OS 2.2209142 3.2063059
OS 2.2173779 3.2115984
OS 2.2120854 3.2151347
OS 2.2058425 3.2163765
OE
OB 2.4223425 3.2631033 H
OS 2.4133837 3.2613213
OS 2.4057888 3.2562466
OS 2.4007141 3.2486517
OS 2.3989321 3.2396929
OS 2.4007141 3.2307341
OS 2.4057888 3.2231392
OS 2.4098502 3.2204255
OS 2.4087944 3.2151175
OS 2.4078122 3.2149221
OS 2.4025197 3.2113858
OS 2.3989834 3.2060933
OS 2.3977416 3.1998504
OS 2.3989834 3.1936075
OS 2.4025197 3.188315
OS 2.4078122 3.1847787
OS 2.4140551 3.1835369
OS 2.420298 3.1847787
OS 2.4255905 3.188315
OS 2.4291268 3.1936075
OS 2.4303686 3.1998504
OS 2.4291268 3.2060933
OS 2.4255905 3.2113858
OS 2.4250776 3.2117285
OS 2.4261334 3.2170365
OS 2.4313013 3.2180645
OS 2.4388962 3.2231392
OS 2.4439709 3.2307341
OS 2.4457529 3.2396929
OS 2.4439709 3.2486517
OS 2.4388962 3.2562466
OS 2.4313013 3.2613213
OS 2.4223425 3.2631033
OE
OB 6.3094161 3.2153765 H
OS 6.3031732 3.2141347
OS 6.2978807 3.2105984
OS 6.2943444 3.2053059
OS 6.2931026 3.199063
OS 6.2943444 3.1928201
OS 6.2978807 3.1875276
OS 6.3031732 3.1839913
OS 6.3094161 3.1827495
OS 6.315659 3.1839913
OS 6.3209515 3.1875276
OS 6.3244878 3.1928201
OS 6.3257296 3.199063
OS 6.3244878 3.2053059
OS 6.3209515 3.2105984
OS 6.315659 3.2141347
OS 6.3094161 3.2153765
OE
OB 6.4398425 3.2073765 H
OS 6.4335996 3.2061347
OS 6.4283071 3.2025984
OS 6.4247708 3.1973059
OS 6.423529 3.191063
OS 6.4247708 3.1848201
OS 6.4283071 3.1795276
OS 6.4335996 3.1759913
OS 6.4398425 3.1747495
OS 6.4460854 3.1759913
OS 6.4513779 3.1795276
OS 6.4549142 3.1848201
OS 6.456156 3.191063
OS 6.4549142 3.1973059
OS 6.4513779 3.2025984
OS 6.4460854 3.2061347
OS 6.4398425 3.2073765
OE
OB 3.1889764 3.2033214 H
OS 3.1827335 3.2020796
OS 3.177441 3.1985433
OS 3.1739047 3.1932508
OS 3.1726629 3.1870079
OS 3.1739047 3.180765
OS 3.177441 3.1754725
OS 3.1827335 3.1719362
OS 3.1889764 3.1706944
OS 3.1952193 3.1719362
OS 3.2005118 3.1754725
OS 3.2040481 3.180765
OS 3.2052899 3.1870079
OS 3.2040481 3.1932508
OS 3.2005118 3.1985433
OS 3.1952193 3.2020796
OS 3.1889764 3.2033214
OE
OB 2.5918425 3.202534 H
OS 2.5855996 3.2012922
OS 2.5803071 3.1977559
OS 2.5767708 3.1924634
OS 2.575529 3.1862205
OS 2.5767708 3.1799776
OS 2.5803071 3.1746851
OS 2.5855996 3.1711488
OS 2.5918425 3.169907
OS 2.5980854 3.1711488
OS 2.6033779 3.1746851
OS 2.6069142 3.1799776
OS 2.608156 3.1862205
OS 2.6069142 3.1924634
OS 2.6033779 3.1977559
OS 2.5980854 3.2012922
OS 2.5918425 3.202534
OE
OB 2.462374 3.1885576 H
OS 2.4561311 3.1873158
OS 2.4508386 3.1837795
OS 2.4473023 3.178487
OS 2.4460605 3.1722441
OS 2.4473023 3.1660012
OS 2.4508386 3.1607087
OS 2.4561311 3.1571724
OS 2.462374 3.1559306
OS 2.4686169 3.1571724
OS 2.4739094 3.1607087
OS 2.4774457 3.1660012
OS 2.4786875 3.1722441
OS 2.4774457 3.178487
OS 2.4739094 3.1837795
OS 2.4686169 3.1873158
OS 2.462374 3.1885576
OE
OB 6.3398425 3.1673765 H
OS 6.3335996 3.1661347
OS 6.3283071 3.1625984
OS 6.3247708 3.1573059
OS 6.323529 3.151063
OS 6.3247708 3.1448201
OS 6.3283071 3.1395276
OS 6.3335996 3.1359913
OS 6.3398425 3.1347495
OS 6.3460854 3.1359913
OS 6.3513779 3.1395276
OS 6.3549142 3.1448201
OS 6.356156 3.151063
OS 6.3549142 3.1573059
OS 6.3513779 3.1625984
OS 6.3460854 3.1661347
OS 6.3398425 3.1673765
OE
OB 3.8298425 3.1923765 H
OS 3.8235996 3.1911347
OS 3.8183071 3.1875984
OS 3.8147708 3.1823059
OS 3.813529 3.176063
OS 3.8147708 3.1698201
OS 3.8183071 3.1645276
OS 3.8235996 3.1609913
OS 3.8298425 3.1597495
OS 3.8360854 3.1609913
OS 3.8363282 3.1611536
OS 3.8399331 3.1575487
OS 3.8397708 3.1573059
OS 3.838529 3.151063
OS 3.8397708 3.1448201
OS 3.8433071 3.1395276
OS 3.8485996 3.1359913
OS 3.8548425 3.1347495
OS 3.8610854 3.1359913
OS 3.8663779 3.1395276
OS 3.8699142 3.1448201
OS 3.871156 3.151063
OS 3.8699142 3.1573059
OS 3.8663779 3.1625984
OS 3.8610854 3.1661347
OS 3.8548425 3.1673765
OS 3.8485996 3.1661347
OS 3.8483568 3.1659724
OS 3.8447519 3.1695773
OS 3.8449142 3.1698201
OS 3.846156 3.176063
OS 3.8449142 3.1823059
OS 3.8413779 3.1875984
OS 3.8360854 3.1911347
OS 3.8298425 3.1923765
OE
OB 1.4598425 3.1633765 H
OS 1.4535996 3.1621347
OS 1.4483071 3.1585984
OS 1.4447708 3.1533059
OS 1.443529 3.147063
OS 1.4447708 3.1408201
OS 1.4483071 3.1355276
OS 1.4535996 3.1319913
OS 1.4598425 3.1307495
OS 1.4660854 3.1319913
OS 1.4713779 3.1355276
OS 1.4749142 3.1408201
OS 1.476156 3.147063
OS 1.4749142 3.1533059
OS 1.4713779 3.1585984
OS 1.4660854 3.1621347
OS 1.4598425 3.1633765
OE
OB 3.2755905 3.1580458 H
OS 3.2693476 3.156804
OS 3.2640551 3.1532677
OS 3.2605188 3.1479752
OS 3.259277 3.1417323
OS 3.2605188 3.1354894
OS 3.2640551 3.1301969
OS 3.2693476 3.1266606
OS 3.2755905 3.1254188
OS 3.2818334 3.1266606
OS 3.2871259 3.1301969
OS 3.2906622 3.1354894
OS 3.291904 3.1417323
OS 3.2906622 3.1479752
OS 3.2871259 3.1532677
OS 3.2818334 3.156804
OS 3.2755905 3.1580458
OE
OB 6.3048425 3.1373765 H
OS 6.2985996 3.1361347
OS 6.2933071 3.1325984
OS 6.2897708 3.1273059
OS 6.288529 3.121063
OS 6.2897708 3.1148201
OS 6.2933071 3.1095276
OS 6.2985996 3.1059913
OS 6.3048425 3.1047495
OS 6.3110854 3.1059913
OS 6.3163779 3.1095276
OS 6.3199142 3.1148201
OS 6.321156 3.121063
OS 6.3199142 3.1273059
OS 6.3163779 3.1325984
OS 6.3110854 3.1361347
OS 6.3048425 3.1373765
OE
OB 3.9398425 3.1373765 H
OS 3.9335996 3.1361347
OS 3.9283071 3.1325984
OS 3.9247708 3.1273059
OS 3.923529 3.121063
OS 3.9247708 3.1148201
OS 3.9283071 3.1095276
OS 3.9335996 3.1059913
OS 3.9398425 3.1047495
OS 3.9460854 3.1059913
OS 3.9513779 3.1095276
OS 3.9549142 3.1148201
OS 3.956156 3.121063
OS 3.9549142 3.1273059
OS 3.9513779 3.1325984
OS 3.9460854 3.1361347
OS 3.9398425 3.1373765
OE
OB 3.4918425 3.1193765 H
OS 3.4855996 3.1181347
OS 3.4803071 3.1145984
OS 3.4767708 3.1093059
OS 3.475529 3.103063
OS 3.4767708 3.0968201
OS 3.4803071 3.0915276
OS 3.4855996 3.0879913
OS 3.4918425 3.0867495
OS 3.4980854 3.0879913
OS 3.5033779 3.0915276
OS 3.5069142 3.0968201
OS 3.508156 3.103063
OS 3.5069142 3.1093059
OS 3.5033779 3.1145984
OS 3.4980854 3.1181347
OS 3.4918425 3.1193765
OE
OB 2.4187174 3.1348201 H
OS 2.4124745 3.1335783
OS 2.407182 3.130042
OS 2.4036457 3.1247495
OS 2.4024039 3.1185066
OS 2.4036457 3.1122637
OS 2.407182 3.1069712
OS 2.4081253 3.1063409
OS 2.4081253 3.1003275
OS 2.4057888 3.0987663
OS 2.4007141 3.0911714
OS 2.3989321 3.0822126
OS 2.4007141 3.0732538
OS 2.4057888 3.0656589
OS 2.4133837 3.0605842
OS 2.4223425 3.0588022
OS 2.4313013 3.0605842
OS 2.4388962 3.0656589
OS 2.4439709 3.0732538
OS 2.4457529 3.0822126
OS 2.4439709 3.0911714
OS 2.4388962 3.0987663
OS 2.4329346 3.1027496
OS 2.4313655 3.1052197
OS 2.4315364 3.1088922
OS 2.4337891 3.1122637
OS 2.4350309 3.1185066
OS 2.4337891 3.1247495
OS 2.4302528 3.130042
OS 2.4249603 3.1335783
OS 2.4187174 3.1348201
OE
OB 3.3688425 3.0663765 H
OS 3.3625996 3.0651347
OS 3.3573071 3.0615984
OS 3.3537708 3.0563059
OS 3.352529 3.050063
OS 3.3537708 3.0438201
OS 3.3573071 3.0385276
OS 3.3625996 3.0349913
OS 3.3688425 3.0337495
OS 3.3750854 3.0349913
OS 3.3803779 3.0385276
OS 3.3839142 3.0438201
OS 3.385156 3.050063
OS 3.3839142 3.0563059
OS 3.3803779 3.0615984
OS 3.3750854 3.0651347
OS 3.3688425 3.0663765
OE
OB 3.3448425 3.0123765 H
OS 3.3385996 3.0111347
OS 3.3333071 3.0075984
OS 3.3297708 3.0023059
OS 3.328529 2.996063
OS 3.3297708 2.9898201
OS 3.3333071 2.9845276
OS 3.3385996 2.9809913
OS 3.3448425 2.9797495
OS 3.3510854 2.9809913
OS 3.3563779 2.9845276
OS 3.3599142 2.9898201
OS 3.361156 2.996063
OS 3.3599142 3.0023059
OS 3.3563779 3.0075984
OS 3.3510854 3.0111347
OS 3.3448425 3.0123765
OE
OB 3.1978425 2.9863765 H
OS 3.1915996 2.9851347
OS 3.1863071 2.9815984
OS 3.1827708 2.9763059
OS 3.181529 2.970063
OS 3.1827708 2.9638201
OS 3.1863071 2.9585276
OS 3.1915996 2.9549913
OS 3.1978425 2.9537495
OS 3.2040854 2.9549913
OS 3.2093779 2.9585276
OS 3.2129142 2.9638201
OS 3.214156 2.970063
OS 3.2129142 2.9763059
OS 3.2093779 2.9815984
OS 3.2040854 2.9851347
OS 3.1978425 2.9863765
OE
OB 4.7942913 2.8243844 H
OS 4.7880484 2.8231426
OS 4.7827559 2.8196063
OS 4.7792196 2.8143138
OS 4.7779778 2.8080709
OS 4.7792196 2.801828
OS 4.7827559 2.7965355
OS 4.7880484 2.7929992
OS 4.7942913 2.7917574
OS 4.8005342 2.7929992
OS 4.8058267 2.7965355
OS 4.809363 2.801828
OS 4.8106048 2.8080709
OS 4.809363 2.8143138
OS 4.8058267 2.8196063
OS 4.8005342 2.8231426
OS 4.7942913 2.8243844
OE
OB 4.5036614 2.8061954 H
OS 4.4974185 2.8049536
OS 4.492126 2.8014173
OS 4.4885897 2.7961248
OS 4.4873479 2.7898819
OS 4.4885897 2.783639
OS 4.492126 2.7783465
OS 4.4974185 2.7748102
OS 4.5036614 2.7735684
OS 4.5099043 2.7748102
OS 4.5151968 2.7783465
OS 4.5187331 2.783639
OS 4.5199749 2.7898819
OS 4.5187331 2.7961248
OS 4.5151968 2.8014173
OS 4.5099043 2.8049536
OS 4.5036614 2.8061954
OE
OB 2.1468425 2.7693765 H
OS 2.1405996 2.7681347
OS 2.1353071 2.7645984
OS 2.1317708 2.7593059
OS 2.130529 2.753063
OS 2.1317708 2.7468201
OS 2.1353071 2.7415276
OS 2.1405996 2.7379913
OS 2.1468425 2.7367495
OS 2.1530854 2.7379913
OS 2.1583779 2.7415276
OS 2.1619142 2.7468201
OS 2.163156 2.753063
OS 2.1619142 2.7593059
OS 2.1583779 2.7645984
OS 2.1530854 2.7681347
OS 2.1468425 2.7693765
OE
OB 2.6929134 2.7377702 H
OS 2.6866705 2.7365284
OS 2.681378 2.7329921
OS 2.6778417 2.7276996
OS 2.6765999 2.7214567
OS 2.6778417 2.7152138
OS 2.681378 2.7099213
OS 2.6866705 2.706385
OS 2.6929134 2.7051432
OS 2.6991563 2.706385
OS 2.7044488 2.7099213
OS 2.7079851 2.7152138
OS 2.7092269 2.7214567
OS 2.7079851 2.7276996
OS 2.7044488 2.7329921
OS 2.6991563 2.7365284
OS 2.6929134 2.7377702
OE
OB 2.394685 2.7367859 H
OS 2.3884421 2.7355441
OS 2.3831496 2.7320078
OS 2.3796133 2.7267153
OS 2.3783715 2.7204724
OS 2.3796133 2.7142295
OS 2.3831496 2.708937
OS 2.3884421 2.7054007
OS 2.394685 2.7041589
OS 2.4009279 2.7054007
OS 2.4062204 2.708937
OS 2.4097567 2.7142295
OS 2.4109985 2.7204724
OS 2.4097567 2.7267153
OS 2.4062204 2.7320078
OS 2.4009279 2.7355441
OS 2.394685 2.7367859
OE
OB 2.4948425 2.7123765 H
OS 2.4885996 2.7111347
OS 2.4833071 2.7075984
OS 2.4797708 2.7023059
OS 2.478529 2.696063
OS 2.4797708 2.6898201
OS 2.4833071 2.6845276
OS 2.4883212 2.6811773
OS 2.4885995 2.6790399
OS 2.4885995 2.6780861
OS 2.4883212 2.6759487
OS 2.4833071 2.6725984
OS 2.4797708 2.6673059
OS 2.478529 2.661063
OS 2.4797708 2.6548201
OS 2.4833071 2.6495276
OS 2.4885996 2.6459913
OS 2.4948425 2.6447495
OS 2.5010854 2.6459913
OS 2.5063779 2.6495276
OS 2.5099142 2.6548201
OS 2.511156 2.661063
OS 2.5099142 2.6673059
OS 2.5063779 2.6725984
OS 2.5013638 2.6759487
OS 2.5010855 2.6780861
OS 2.5010855 2.6790399
OS 2.5013638 2.6811773
OS 2.5063779 2.6845276
OS 2.5099142 2.6898201
OS 2.511156 2.696063
OS 2.5099142 2.7023059
OS 2.5063779 2.7075984
OS 2.5010854 2.7111347
OS 2.4948425 2.7123765
OE
OB 2.9588425 2.6373765 H
OS 2.9525996 2.6361347
OS 2.9473071 2.6325984
OS 2.9437708 2.6273059
OS 2.942529 2.621063
OS 2.9437708 2.6148201
OS 2.9473071 2.6095276
OS 2.9525996 2.6059913
OS 2.9588425 2.6047495
OS 2.9650854 2.6059913
OS 2.9703779 2.6095276
OS 2.9739142 2.6148201
OS 2.975156 2.621063
OS 2.9739142 2.6273059
OS 2.9703779 2.6325984
OS 2.9650854 2.6361347
OS 2.9588425 2.6373765
OE
OB 2.4291925 2.6373765 H
OS 2.4229496 2.6361347
OS 2.4176571 2.6325984
OS 2.4141208 2.6273059
OS 2.412879 2.621063
OS 2.4141208 2.6148201
OS 2.4176571 2.6095276
OS 2.4229496 2.6059913
OS 2.4291925 2.6047495
OS 2.4354354 2.6059913
OS 2.4407279 2.6095276
OS 2.4442642 2.6148201
OS 2.445506 2.621063
OS 2.4442642 2.6273059
OS 2.4407279 2.6325984
OS 2.4354354 2.6361347
OS 2.4291925 2.6373765
OE
OB 2.2523425 2.6298765 H
OS 2.2460996 2.6286347
OS 2.2408071 2.6250984
OS 2.2372708 2.6198059
OS 2.236029 2.613563
OS 2.2372708 2.6073201
OS 2.239748 2.6036127
OS 2.2364566 2.5995388
OS 2.2317425 2.6004765
OS 2.2254996 2.5992347
OS 2.2202071 2.5956984
OS 2.2166708 2.5904059
OS 2.215429 2.584163
OS 2.2166708 2.5779201
OS 2.2202071 2.5726276
OS 2.2254996 2.5690913
OS 2.2317425 2.5678495
OS 2.2379854 2.5690913
OS 2.2432779 2.5726276
OS 2.2468142 2.5779201
OS 2.248056 2.584163
OS 2.2468142 2.5904059
OS 2.244337 2.5941133
OS 2.2476284 2.5981872
OS 2.2523425 2.5972495
OS 2.2585854 2.5984913
OS 2.2638779 2.6020276
OS 2.2674142 2.6073201
OS 2.268656 2.613563
OS 2.2674142 2.6198059
OS 2.2638779 2.6250984
OS 2.2585854 2.6286347
OS 2.2523425 2.6298765
OE
OB 2.8218425 2.6173765 H
OS 2.8155996 2.6161347
OS 2.8103071 2.6125984
OS 2.8067708 2.6073059
OS 2.805529 2.601063
OS 2.8067708 2.5948201
OS 2.8103071 2.5895276
OS 2.8155996 2.5859913
OS 2.8218425 2.5847495
OS 2.8280854 2.5859913
OS 2.8333779 2.5895276
OS 2.8369142 2.5948201
OS 2.838156 2.601063
OS 2.8369142 2.6073059
OS 2.8333779 2.6125984
OS 2.8280854 2.6161347
OS 2.8218425 2.6173765
OE
OB 3.6238425 2.6033765 H
OS 3.6175996 2.6021347
OS 3.6123071 2.5985984
OS 3.6087708 2.5933059
OS 3.607529 2.587063
OS 3.6087708 2.5808201
OS 3.6123071 2.5755276
OS 3.6175996 2.5719913
OS 3.6238425 2.5707495
OS 3.6300854 2.5719913
OS 3.6353779 2.5755276
OS 3.6389142 2.5808201
OS 3.640156 2.587063
OS 3.6389142 2.5933059
OS 3.6353779 2.5985984
OS 3.6300854 2.6021347
OS 3.6238425 2.6033765
OE
OB 4.2986248 2.6412356 H
OS 4.2867469 2.6396718
OS 4.2756785 2.6350872
OS 4.2661738 2.627794
OS 4.2588806 2.6182893
OS 4.254296 2.6072209
OS 4.2527322 2.595343
OS 4.254296 2.5834651
OS 4.2588806 2.5723967
OS 4.2661738 2.562892
OS 4.2756785 2.5555988
OS 4.2867469 2.5510142
OS 4.2986248 2.5494504
OS 4.3105027 2.5510142
OS 4.3215711 2.5555988
OS 4.3310758 2.562892
OS 4.338369 2.5723967
OS 4.3429536 2.5834651
OS 4.3445174 2.595343
OS 4.3429536 2.6072209
OS 4.338369 2.6182893
OS 4.3310758 2.627794
OS 4.3215711 2.6350872
OS 4.3105027 2.6396718
OS 4.2986248 2.6412356
OE
OB 4.1805146 2.6412356 H
OS 4.1686367 2.6396718
OS 4.1575683 2.6350872
OS 4.1480636 2.627794
OS 4.1407704 2.6182893
OS 4.1361858 2.6072209
OS 4.134622 2.595343
OS 4.1361858 2.5834651
OS 4.1407704 2.5723967
OS 4.1480636 2.562892
OS 4.1575683 2.5555988
OS 4.1686367 2.5510142
OS 4.1805146 2.5494504
OS 4.1923925 2.5510142
OS 4.2034609 2.5555988
OS 4.2129656 2.562892
OS 4.2202588 2.5723967
OS 4.2248434 2.5834651
OS 4.2264072 2.595343
OS 4.2248434 2.6072209
OS 4.2202588 2.6182893
OS 4.2129656 2.627794
OS 4.2034609 2.6350872
OS 4.1923925 2.6396718
OS 4.1805146 2.6412356
OE
OB 4.0624044 2.6412356 H
OS 4.0505265 2.6396718
OS 4.0394581 2.6350872
OS 4.0299534 2.627794
OS 4.0226602 2.6182893
OS 4.0180756 2.6072209
OS 4.0165118 2.595343
OS 4.0180756 2.5834651
OS 4.0226602 2.5723967
OS 4.0299534 2.562892
OS 4.0394581 2.5555988
OS 4.0505265 2.5510142
OS 4.0624044 2.5494504
OS 4.0742823 2.5510142
OS 4.0853507 2.5555988
OS 4.0948554 2.562892
OS 4.1021486 2.5723967
OS 4.1067332 2.5834651
OS 4.108297 2.595343
OS 4.1067332 2.6072209
OS 4.1021486 2.6182893
OS 4.0948554 2.627794
OS 4.0853507 2.6350872
OS 4.0742823 2.6396718
OS 4.0624044 2.6412356
OE
OB 6.2848425 2.5173765 H
OS 6.2785996 2.5161347
OS 6.2733071 2.5125984
OS 6.2697708 2.5073059
OS 6.268529 2.501063
OS 6.2697708 2.4948201
OS 6.2733071 2.4895276
OS 6.2785996 2.4859913
OS 6.2848425 2.4847495
OS 6.2910854 2.4859913
OS 6.2963779 2.4895276
OS 6.2999142 2.4948201
OS 6.301156 2.501063
OS 6.2999142 2.5073059
OS 6.2963779 2.5125984
OS 6.2910854 2.5161347
OS 6.2848425 2.5173765
OE
OB 1.0208425 2.4973765 H
OS 1.0145996 2.4961347
OS 1.0093071 2.4925984
OS 1.0057708 2.4873059
OS 1.004529 2.481063
OS 1.0057708 2.4748201
OS 1.0093071 2.4695276
OS 1.0145996 2.4659913
OS 1.0208425 2.4647495
OS 1.0270854 2.4659913
OS 1.0323779 2.4695276
OS 1.0359142 2.4748201
OS 1.037156 2.481063
OS 1.0359142 2.4873059
OS 1.0323779 2.4925984
OS 1.0270854 2.4961347
OS 1.0208425 2.4973765
OE
OB 2.6248425 2.4773765 H
OS 2.6185996 2.4761347
OS 2.6133071 2.4725984
OS 2.6097708 2.4673059
OS 2.608529 2.461063
OS 2.6097708 2.4548201
OS 2.6099331 2.4545773
OS 2.6063282 2.4509724
OS 2.6060854 2.4511347
OS 2.5998425 2.4523765
OS 2.5935996 2.4511347
OS 2.5883071 2.4475984
OS 2.5847708 2.4423059
OS 2.583529 2.436063
OS 2.5844621 2.4313719
OS 2.583986 2.4305231
OS 2.5813824 2.4279195
OS 2.5805336 2.4274434
OS 2.5758425 2.4283765
OS 2.5695996 2.4271347
OS 2.5643071 2.4235984
OS 2.5607708 2.4183059
OS 2.559529 2.412063
OS 2.5607708 2.4058201
OS 2.5643071 2.4005276
OS 2.5695996 2.3969913
OS 2.5758425 2.3957495
OS 2.5820854 2.3969913
OS 2.5873779 2.4005276
OS 2.5909142 2.4058201
OS 2.592156 2.412063
OS 2.5912229 2.4167541
OS 2.591699 2.4176029
OS 2.5943026 2.4202065
OS 2.5951514 2.4206826
OS 2.5998425 2.4197495
OS 2.6060854 2.4209913
OS 2.6113779 2.4245276
OS 2.6149142 2.4298201
OS 2.616156 2.436063
OS 2.6149142 2.4423059
OS 2.6147519 2.4425487
OS 2.6183568 2.4461536
OS 2.6185996 2.4459913
OS 2.6248425 2.4447495
OS 2.6310854 2.4459913
OS 2.6363779 2.4495276
OS 2.6399142 2.4548201
OS 2.641156 2.461063
OS 2.6399142 2.4673059
OS 2.6363779 2.4725984
OS 2.6310854 2.4761347
OS 2.6248425 2.4773765
OE
OB 2.2720325 2.4801865 H
OS 2.2657896 2.4789447
OS 2.2604971 2.4754084
OS 2.2569608 2.4701159
OS 2.255719 2.463873
OS 2.2569608 2.4576301
OS 2.2604971 2.4523376
OS 2.2657896 2.4488013
OS 2.2720325 2.4475595
OS 2.2782754 2.4488013
OS 2.2835679 2.4523376
OS 2.2871042 2.4576301
OS 2.288346 2.463873
OS 2.2871042 2.4701159
OS 2.2835679 2.4754084
OS 2.2782754 2.4789447
OS 2.2720325 2.4801865
OE
OB 2.5258425 2.4793765 H
OS 2.5195996 2.4781347
OS 2.5143071 2.4745984
OS 2.5107708 2.4693059
OS 2.509529 2.463063
OS 2.5107708 2.4568201
OS 2.5143071 2.4515276
OS 2.5195996 2.4479913
OS 2.5258425 2.4467495
OS 2.5320854 2.4479913
OS 2.5373779 2.4515276
OS 2.5409142 2.4568201
OS 2.542156 2.463063
OS 2.5409142 2.4693059
OS 2.5373779 2.4745984
OS 2.5320854 2.4781347
OS 2.5258425 2.4793765
OE
OB 5.5781524 2.5349364 H
OS 5.5662745 2.5333726
OS 5.5552061 2.528788
OS 5.5457014 2.5214948
OS 5.5384082 2.5119901
OS 5.5338236 2.5009217
OS 5.5322598 2.4890438
OS 5.5338236 2.4771659
OS 5.5384082 2.4660975
OS 5.5457014 2.4565928
OS 5.5552061 2.4492996
OS 5.5662745 2.444715
OS 5.5781524 2.4431512
OS 5.5900303 2.444715
OS 5.6010987 2.4492996
OS 5.6106034 2.4565928
OS 5.6178966 2.4660975
OS 5.6224812 2.4771659
OS 5.624045 2.4890438
OS 5.6224812 2.5009217
OS 5.6178966 2.5119901
OS 5.6106034 2.5214948
OS 5.6010987 2.528788
OS 5.5900303 2.5333726
OS 5.5781524 2.5349364
OE
OB 2.9488425 2.4723765 H
OS 2.9425996 2.4711347
OS 2.9373071 2.4675984
OS 2.9337708 2.4623059
OS 2.932529 2.456063
OS 2.9337708 2.4498201
OS 2.9373071 2.4445276
OS 2.9425996 2.4409913
OS 2.9488425 2.4397495
OS 2.9550854 2.4409913
OS 2.9603779 2.4445276
OS 2.9639142 2.4498201
OS 2.965156 2.456063
OS 2.9639142 2.4623059
OS 2.9603779 2.4675984
OS 2.9550854 2.4711347
OS 2.9488425 2.4723765
OE
OB 2.9905325 2.4577319 H
OS 2.9831854 2.4562705
OS 2.9769568 2.4521087
OS 2.972795 2.4458801
OS 2.9713336 2.438533
OS 2.972795 2.4311859
OS 2.9769568 2.4249573
OS 2.9831854 2.4207955
OS 2.9905325 2.4193341
OS 2.9978796 2.4207955
OS 3.0041082 2.4249573
OS 3.00827 2.4311859
OS 3.0097314 2.438533
OS 3.00827 2.4458801
OS 3.0041082 2.4521087
OS 2.9978796 2.4562705
OS 2.9905325 2.4577319
OE
OB 2.2031325 2.4577319 H
OS 2.1957854 2.4562705
OS 2.1895568 2.4521087
OS 2.185395 2.4458801
OS 2.1839336 2.438533
OS 2.185395 2.4311859
OS 2.1895568 2.4249573
OS 2.1957854 2.4207955
OS 2.2031325 2.4193341
OS 2.2104796 2.4207955
OS 2.2167082 2.4249573
OS 2.22087 2.4311859
OS 2.2223314 2.438533
OS 2.22087 2.4458801
OS 2.2167082 2.4521087
OS 2.2104796 2.4562705
OS 2.2031325 2.4577319
OE
OB 3.6179425 2.5536725 H
OS 3.6047974 2.5523778
OS 3.5921575 2.5485435
OS 3.5805085 2.542317
OS 3.570298 2.5339375
OS 3.5619185 2.523727
OS 3.555692 2.512078
OS 3.5518577 2.4994381
OS 3.550563 2.486293
OS 3.5518577 2.4731479
OS 3.555692 2.460508
OS 3.5619185 2.448859
OS 3.570298 2.4386485
OS 3.5805085 2.430269
OS 3.5921575 2.4240425
OS 3.6047974 2.4202082
OS 3.6179425 2.4189135
OS 3.6310876 2.4202082
OS 3.6437275 2.4240425
OS 3.6553765 2.430269
OS 3.665587 2.4386485
OS 3.6739665 2.448859
OS 3.680193 2.460508
OS 3.6840273 2.4731479
OS 3.685322 2.486293
OS 3.6840273 2.4994381
OS 3.680193 2.512078
OS 3.6739665 2.523727
OS 3.665587 2.5339375
OS 3.6553765 2.542317
OS 3.6437275 2.5485435
OS 3.6310876 2.5523778
OS 3.6179425 2.5536725
OE
OB 1.6519425 2.5536725 H
OS 1.6387974 2.5523778
OS 1.6261575 2.5485435
OS 1.6145085 2.542317
OS 1.604298 2.5339375
OS 1.5959185 2.523727
OS 1.589692 2.512078
OS 1.5858577 2.4994381
OS 1.584563 2.486293
OS 1.5858577 2.4731479
OS 1.589692 2.460508
OS 1.5959185 2.448859
OS 1.604298 2.4386485
OS 1.6145085 2.430269
OS 1.6261575 2.4240425
OS 1.6387974 2.4202082
OS 1.6519425 2.4189135
OS 1.6650876 2.4202082
OS 1.6777275 2.4240425
OS 1.6893765 2.430269
OS 1.699587 2.4386485
OS 1.7079665 2.448859
OS 1.714193 2.460508
OS 1.7180273 2.4731479
OS 1.719322 2.486293
OS 1.7180273 2.4994381
OS 1.714193 2.512078
OS 1.7079665 2.523727
OS 1.699587 2.5339375
OS 1.6893765 2.542317
OS 1.6777275 2.5485435
OS 1.6650876 2.5523778
OS 1.6519425 2.5536725
OE
OB 0.1998425 2.5453727 H
OS 0.1872963 2.544137
OS 0.1752322 2.5404774
OS 0.1641139 2.5345346
OS 0.1543687 2.5265368
OS 0.1463709 2.5167916
OS 0.1404281 2.5056733
OS 0.1367685 2.4936092
OS 0.1355328 2.481063
OS 0.1367685 2.4685168
OS 0.1404281 2.4564527
OS 0.1463709 2.4453344
OS 0.1543687 2.4355892
OS 0.1641139 2.4275914
OS 0.1752322 2.4216486
OS 0.1872963 2.417989
OS 0.1998425 2.4167533
OS 0.2123887 2.417989
OS 0.2244528 2.4216486
OS 0.2355711 2.4275914
OS 0.2453163 2.4355892
OS 0.2533141 2.4453344
OS 0.2592569 2.4564527
OS 0.2629165 2.4685168
OS 0.2641522 2.481063
OS 0.2629165 2.4936092
OS 0.2592569 2.5056733
OS 0.2533141 2.5167916
OS 0.2453163 2.5265368
OS 0.2355711 2.5345346
OS 0.2244528 2.5404774
OS 0.2123887 2.544137
OS 0.1998425 2.5453727
OE
OB 2.8948425 2.4473765 H
OS 2.8885996 2.4461347
OS 2.8833071 2.4425984
OS 2.8797708 2.4373059
OS 2.878529 2.431063
OS 2.8797708 2.4248201
OS 2.8833071 2.4195276
OS 2.8885996 2.4159913
OS 2.8948425 2.4147495
OS 2.9010854 2.4159913
OS 2.9063778 2.4195276
OS 2.9073026 2.4195276
OS 2.9093071 2.4165276
OS 2.9145996 2.4129913
OS 2.9208425 2.4117495
OS 2.9270854 2.4129913
OS 2.9323779 2.4165276
OS 2.9359142 2.4218201
OS 2.937156 2.428063
OS 2.9359142 2.4343059
OS 2.9323779 2.4395984
OS 2.9270854 2.4431347
OS 2.9208425 2.4443765
OS 2.9145996 2.4431347
OS 2.9093072 2.4395984
OS 2.9083824 2.4395984
OS 2.9063779 2.4425984
OS 2.9010854 2.4461347
OS 2.8948425 2.4473765
OE
OB 4.0398425 2.4223765 H
OS 4.0335996 2.4211347
OS 4.0283071 2.4175984
OS 4.0247708 2.4123059
OS 4.023529 2.406063
OS 4.0247708 2.3998201
OS 4.0283071 2.3945276
OS 4.0335996 2.3909913
OS 4.0398425 2.3897495
OS 4.0460854 2.3909913
OS 4.0513779 2.3945276
OS 4.0549142 2.3998201
OS 4.056156 2.406063
OS 4.0549142 2.4123059
OS 4.0513779 2.4175984
OS 4.0460854 2.4211347
OS 4.0398425 2.4223765
OE
OB 3.4988425 2.3573765 H
OS 3.4925996 2.3561347
OS 3.4873071 2.3525984
OS 3.4837708 2.3473059
OS 3.482529 2.341063
OS 3.4837708 2.3348201
OS 3.4873071 2.3295276
OS 3.4925996 2.3259913
OS 3.4988425 2.3247495
OS 3.5050854 2.3259913
OS 3.5103779 2.3295276
OS 3.5139142 2.3348201
OS 3.515156 2.341063
OS 3.5139142 2.3473059
OS 3.5103779 2.3525984
OS 3.5050854 2.3561347
OS 3.4988425 2.3573765
OE
OB 2.7268425 2.3093765 H
OS 2.7205996 2.3081347
OS 2.7153071 2.3045984
OS 2.7131725 2.3014038
OS 2.7090854 2.3041347
OS 2.7028425 2.3053765
OS 2.6965996 2.3041347
OS 2.6913071 2.3005984
OS 2.6877708 2.2953059
OS 2.6868962 2.2909101
OS 2.6821561 2.2910632
OS 2.6809142 2.2973059
OS 2.6773779 2.3025984
OS 2.6720854 2.3061347
OS 2.6658425 2.3073765
OS 2.6595996 2.3061347
OS 2.6543071 2.3025984
OS 2.6507708 2.2973059
OS 2.649529 2.2910631
OS 2.6483447 2.2898788
OS 2.6458425 2.2903765
OS 2.6395996 2.2891347
OS 2.6343071 2.2855984
OS 2.6307708 2.2803059
OS 2.629529 2.274063
OS 2.6307708 2.2678201
OS 2.6343071 2.2625276
OS 2.6395996 2.2589913
OS 2.6458425 2.2577495
OS 2.6520854 2.2589913
OS 2.6573779 2.2625276
OS 2.6609142 2.2678201
OS 2.662156 2.2740629
OS 2.6633403 2.2752472
OS 2.6658425 2.2747495
OS 2.6720854 2.2759913
OS 2.6773779 2.2795276
OS 2.6809142 2.2848201
OS 2.6817888 2.2892159
OS 2.6865289 2.2890628
OS 2.6877708 2.2828201
OS 2.6913071 2.2775276
OS 2.6965996 2.2739913
OS 2.7028425 2.2727495
OS 2.7090854 2.2739913
OS 2.7143779 2.2775276
OS 2.7165125 2.2807222
OS 2.7205996 2.2779913
OS 2.7268425 2.2767495
OS 2.7330854 2.2779913
OS 2.7383779 2.2815276
OS 2.7419142 2.2868201
OS 2.743156 2.293063
OS 2.7419142 2.2993059
OS 2.7383779 2.3045984
OS 2.7330854 2.3081347
OS 2.7268425 2.3093765
OE
OB 2.4758425 2.3073765 H
OS 2.4695996 2.3061347
OS 2.4643071 2.3025984
OS 2.4623321 2.2996425
OS 2.4575823 2.2973722
OS 2.4556938 2.2974115
OS 2.4508425 2.2983765
OS 2.4445996 2.2971347
OS 2.4393071 2.2935984
OS 2.4357708 2.2883059
OS 2.434529 2.282063
OS 2.4357708 2.2758201
OS 2.4393071 2.2705276
OS 2.4445996 2.2669913
OS 2.4508425 2.2657495
OS 2.4570854 2.2669913
OS 2.4623779 2.2705276
OS 2.4659142 2.27582
OS 2.4709912 2.2757145
OS 2.4758425 2.2747495
OS 2.4820854 2.2759913
OS 2.4873779 2.2795276
OS 2.4909142 2.2848201
OS 2.492156 2.291063
OS 2.4909142 2.2973059
OS 2.4873779 2.3025984
OS 2.4820854 2.3061347
OS 2.4758425 2.3073765
OE
OB 2.8038425 2.3233765 H
OS 2.7975996 2.3221347
OS 2.7923071 2.3185984
OS 2.7887708 2.3133059
OS 2.787529 2.307063
OS 2.7887708 2.3008201
OS 2.7923071 2.2955276
OS 2.7975996 2.2919913
OS 2.8038425 2.2907495
OS 2.8100854 2.2919913
OS 2.8153779 2.2955276
OS 2.8189142 2.3008201
OS 2.820156 2.307063
OS 2.8189142 2.3133059
OS 2.8153779 2.3185984
OS 2.8100854 2.3221347
OS 2.8038425 2.3233765
OE
OB 2.9858425 2.3033765 H
OS 2.9795996 2.3021347
OS 2.9743071 2.2985984
OS 2.9707708 2.2933059
OS 2.969529 2.287063
OS 2.9707708 2.2808201
OS 2.9743071 2.2755276
OS 2.9795996 2.2719913
OS 2.9858425 2.2707495
OS 2.9920854 2.2719913
OS 2.9973779 2.2755276
OS 3.0009142 2.2808201
OS 3.002156 2.287063
OS 3.0009142 2.2933059
OS 2.9973779 2.2985984
OS 2.9920854 2.3021347
OS 2.9858425 2.3033765
OE
OB 2.9428425 2.3023765 H
OS 2.9365996 2.3011347
OS 2.9313071 2.2975984
OS 2.9277708 2.2923059
OS 2.926529 2.286063
OS 2.9277708 2.2798201
OS 2.9313071 2.2745276
OS 2.9365996 2.2709913
OS 2.9428425 2.2697495
OS 2.9490854 2.2709913
OS 2.9543779 2.2745276
OS 2.9579142 2.2798201
OS 2.959156 2.286063
OS 2.9579142 2.2923059
OS 2.9543779 2.2975984
OS 2.9490854 2.3011347
OS 2.9428425 2.3023765
OE
OB 5.3277559 2.3463244 H
OS 5.3177023 2.3450008
OS 5.3083338 2.3411203
OS 5.300289 2.3349472
OS 5.2941159 2.3269023
OS 5.2902354 2.3175339
OS 5.2889118 2.3074803
OS 5.2902354 2.2974267
OS 5.2941159 2.2880583
OS 5.300289 2.2800134
OS 5.3083338 2.2738403
OS 5.3177023 2.2699598
OS 5.3277559 2.2686362
OS 5.3378095 2.2699598
OS 5.347178 2.2738403
OS 5.3552228 2.2800134
OS 5.3613959 2.2880583
OS 5.3652764 2.2974267
OS 5.3666 2.3074803
OS 5.3652764 2.3175339
OS 5.3613959 2.3269023
OS 5.3552228 2.3349472
OS 5.347178 2.3411203
OS 5.3378095 2.3450008
OS 5.3277559 2.3463244
OE
OB 4.9277559 2.3463244 H
OS 4.9177023 2.3450008
OS 4.9083338 2.3411203
OS 4.900289 2.3349472
OS 4.8941159 2.3269023
OS 4.8902354 2.3175339
OS 4.8889118 2.3074803
OS 4.8902354 2.2974267
OS 4.8941159 2.2880583
OS 4.900289 2.2800134
OS 4.9083338 2.2738403
OS 4.9177023 2.2699598
OS 4.9277559 2.2686362
OS 4.9378095 2.2699598
OS 4.947178 2.2738403
OS 4.9552228 2.2800134
OS 4.9613959 2.2880583
OS 4.9652764 2.2974267
OS 4.9666 2.3074803
OS 4.9652764 2.3175339
OS 4.9613959 2.3269023
OS 4.9552228 2.3349472
OS 4.947178 2.3411203
OS 4.9378095 2.3450008
OS 4.9277559 2.3463244
OE
OB 4.7277559 2.3463244 H
OS 4.7177023 2.3450008
OS 4.7083338 2.3411203
OS 4.700289 2.3349472
OS 4.6941159 2.3269023
OS 4.6902354 2.3175339
OS 4.6889118 2.3074803
OS 4.6902354 2.2974267
OS 4.6941159 2.2880583
OS 4.700289 2.2800134
OS 4.7083338 2.2738403
OS 4.7177023 2.2699598
OS 4.7277559 2.2686362
OS 4.7378095 2.2699598
OS 4.747178 2.2738403
OS 4.7552228 2.2800134
OS 4.7613959 2.2880583
OS 4.7652764 2.2974267
OS 4.7666 2.3074803
OS 4.7652764 2.3175339
OS 4.7613959 2.3269023
OS 4.7552228 2.3349472
OS 4.747178 2.3411203
OS 4.7378095 2.3450008
OS 4.7277559 2.3463244
OE
OB 4.3277559 2.3463244 H
OS 4.3177023 2.3450008
OS 4.3083338 2.3411203
OS 4.300289 2.3349472
OS 4.2941159 2.3269023
OS 4.2902354 2.3175339
OS 4.2889118 2.3074803
OS 4.2902354 2.2974267
OS 4.2941159 2.2880583
OS 4.300289 2.2800134
OS 4.3083338 2.2738403
OS 4.3177023 2.2699598
OS 4.3277559 2.2686362
OS 4.3378095 2.2699598
OS 4.347178 2.2738403
OS 4.3552228 2.2800134
OS 4.3613959 2.2880583
OS 4.3652764 2.2974267
OS 4.3666 2.3074803
OS 4.3652764 2.3175339
OS 4.3613959 2.3269023
OS 4.3552228 2.3349472
OS 4.347178 2.3411203
OS 4.3378095 2.3450008
OS 4.3277559 2.3463244
OE
OB 2.4098425 2.3303765 H
OS 2.4035996 2.3291347
OS 2.3983071 2.3255984
OS 2.3947708 2.3203059
OS 2.393529 2.314063
OS 2.3947708 2.3078201
OS 2.3983071 2.3025276
OS 2.3997406 2.3015697
OS 2.3997406 2.2955563
OS 2.3983071 2.2945984
OS 2.3947708 2.2893059
OS 2.393529 2.283063
OS 2.3947708 2.2768201
OS 2.3983071 2.2715276
OS 2.4035996 2.2679913
OS 2.4098425 2.2667495
OS 2.4160854 2.2679913
OS 2.4213779 2.2715276
OS 2.4249142 2.2768201
OS 2.426156 2.283063
OS 2.4249142 2.2893059
OS 2.4213779 2.2945984
OS 2.4199444 2.2955563
OS 2.4199444 2.3015697
OS 2.4213779 2.3025276
OS 2.4249142 2.3078201
OS 2.426156 2.314063
OS 2.4249142 2.3203059
OS 2.4213779 2.3255984
OS 2.4160854 2.3291347
OS 2.4098425 2.3303765
OE
OB 2.5798425 2.2973765 H
OS 2.5735996 2.2961347
OS 2.5683071 2.2925984
OS 2.5647708 2.2873059
OS 2.563529 2.281063
OS 2.5647708 2.2748201
OS 2.5683071 2.2695276
OS 2.5735996 2.2659913
OS 2.5798425 2.2647495
OS 2.5860854 2.2659913
OS 2.5913779 2.2695276
OS 2.5949142 2.2748201
OS 2.596156 2.281063
OS 2.5949142 2.2873059
OS 2.5913779 2.2925984
OS 2.5860854 2.2961347
OS 2.5798425 2.2973765
OE
OB 3.3428425 2.2793765 H
OS 3.3365996 2.2781347
OS 3.3313071 2.2745984
OS 3.3277708 2.2693059
OS 3.326529 2.263063
OS 3.3277708 2.2568201
OS 3.3313071 2.2515276
OS 3.3365996 2.2479913
OS 3.3428425 2.2467495
OS 3.3490854 2.2479913
OS 3.3543779 2.2515276
OS 3.3579142 2.2568201
OS 3.359156 2.263063
OS 3.3579142 2.2693059
OS 3.3543779 2.2745984
OS 3.3490854 2.2781347
OS 3.3428425 2.2793765
OE
OB 2.8418425 2.2793765 H
OS 2.8355996 2.2781347
OS 2.8303071 2.2745984
OS 2.8267708 2.2693059
OS 2.825529 2.263063
OS 2.8267708 2.2568201
OS 2.8303071 2.2515276
OS 2.8355996 2.2479913
OS 2.8418425 2.2467495
OS 2.8480854 2.2479913
OS 2.8533779 2.2515276
OS 2.8569142 2.2568201
OS 2.858156 2.263063
OS 2.8569142 2.2693059
OS 2.8533779 2.2745984
OS 2.8480854 2.2781347
OS 2.8418425 2.2793765
OE
OB 0.9968357 2.2723495 H
OS 0.9905928 2.2711077
OS 0.9853003 2.2675714
OS 0.981764 2.2622789
OS 0.9805222 2.256036
OS 0.981764 2.2497931
OS 0.9853003 2.2445006
OS 0.9905928 2.2409643
OS 0.9968357 2.2397225
OS 1.0030786 2.2409643
OS 1.0083711 2.2445006
OS 1.0119074 2.2497931
OS 1.0131492 2.256036
OS 1.0119074 2.2622789
OS 1.0083711 2.2675714
OS 1.0030786 2.2711077
OS 0.9968357 2.2723495
OE
OB 5.6348425 2.2523765 H
OS 5.6285996 2.2511347
OS 5.6233071 2.2475984
OS 5.6197708 2.2423059
OS 5.618529 2.236063
OS 5.6197708 2.2298201
OS 5.6233071 2.2245276
OS 5.6285996 2.2209913
OS 5.6348425 2.2197495
OS 5.6410854 2.2209913
OS 5.6463779 2.2245276
OS 5.6499142 2.2298201
OS 5.651156 2.236063
OS 5.6499142 2.2423059
OS 5.6463779 2.2475984
OS 5.6410854 2.2511347
OS 5.6348425 2.2523765
OE
OB 2.4998425 2.2523765 H
OS 2.4935996 2.2511347
OS 2.4883071 2.2475984
OS 2.4847708 2.2423059
OS 2.483529 2.236063
OS 2.4847708 2.2298201
OS 2.4883071 2.2245276
OS 2.4935996 2.2209913
OS 2.4998425 2.2197495
OS 2.5060854 2.2209913
OS 2.5113779 2.2245276
OS 2.5149142 2.2298201
OS 2.516156 2.236063
OS 2.5149142 2.2423059
OS 2.5113779 2.2475984
OS 2.5060854 2.2511347
OS 2.4998425 2.2523765
OE
OB 2.3308425 2.2313765 H
OS 2.3245996 2.2301347
OS 2.3193071 2.2265984
OS 2.3157708 2.2213059
OS 2.314529 2.215063
OS 2.3157708 2.2088201
OS 2.3193071 2.2035276
OS 2.3245996 2.1999913
OS 2.3308425 2.1987495
OS 2.3370854 2.1999913
OS 2.3423779 2.2035276
OS 2.3459142 2.2088201
OS 2.347156 2.215063
OS 2.3459142 2.2213059
OS 2.3423779 2.2265984
OS 2.3370854 2.2301347
OS 2.3308425 2.2313765
OE
OB 5.5778425 2.2303765 H
OS 5.5715996 2.2291347
OS 5.5663071 2.2255984
OS 5.5627708 2.2203059
OS 5.561529 2.214063
OS 5.5627708 2.2078201
OS 5.5663071 2.2025276
OS 5.5715996 2.1989913
OS 5.5778425 2.1977495
OS 5.5840854 2.1989913
OS 5.5893779 2.2025276
OS 5.5929142 2.2078201
OS 5.594156 2.214063
OS 5.5929142 2.2203059
OS 5.5893779 2.2255984
OS 5.5840854 2.2291347
OS 5.5778425 2.2303765
OE
OB 6.4248425 2.1973765 H
OS 6.4185996 2.1961347
OS 6.4133071 2.1925984
OS 6.4097708 2.1873059
OS 6.408529 2.181063
OS 6.4097708 2.1748201
OS 6.4133071 2.1695276
OS 6.4185996 2.1659913
OS 6.4248425 2.1647495
OS 6.4310854 2.1659913
OS 6.4363779 2.1695276
OS 6.4399142 2.1748201
OS 6.441156 2.181063
OS 6.4399142 2.1873059
OS 6.4363779 2.1925984
OS 6.4310854 2.1961347
OS 6.4248425 2.1973765
OE
OB 1.7548425 2.1423765 H
OS 1.7485996 2.1411347
OS 1.7433071 2.1375984
OS 1.7397708 2.1323059
OS 1.738529 2.126063
OS 1.7397708 2.1198201
OS 1.7433071 2.1145276
OS 1.7485996 2.1109913
OS 1.7548425 2.1097495
OS 1.7610854 2.1109913
OS 1.7663779 2.1145276
OS 1.7699142 2.1198201
OS 1.771156 2.126063
OS 1.7699142 2.1323059
OS 1.7663779 2.1375984
OS 1.7610854 2.1411347
OS 1.7548425 2.1423765
OE
OB 1.6198425 2.1373765 H
OS 1.6135996 2.1361347
OS 1.6083071 2.1325984
OS 1.6047708 2.1273059
OS 1.603529 2.121063
OS 1.6047708 2.1148201
OS 1.6083071 2.1095276
OS 1.6135996 2.1059913
OS 1.6198425 2.1047495
OS 1.6260854 2.1059913
OS 1.6313779 2.1095276
OS 1.6349142 2.1148201
OS 1.636156 2.121063
OS 1.6349142 2.1273059
OS 1.6313779 2.1325984
OS 1.6260854 2.1361347
OS 1.6198425 2.1373765
OE
OB 1.6968325 2.1164319 H
OS 1.6894854 2.1149705
OS 1.6832568 2.1108087
OS 1.679095 2.1045801
OS 1.6776336 2.097233
OS 1.679095 2.0898859
OS 1.6832568 2.0836573
OS 1.6894854 2.0794955
OS 1.6968325 2.0780341
OS 1.7041796 2.0794955
OS 1.7104082 2.0836573
OS 1.71457 2.0898859
OS 1.7160314 2.097233
OS 1.71457 2.1045801
OS 1.7104082 2.1108087
OS 1.7041796 2.1149705
OS 1.6968325 2.1164319
OE
OB 1.8848425 2.0873765 H
OS 1.8785996 2.0861347
OS 1.8733071 2.0825984
OS 1.8697708 2.0773059
OS 1.868529 2.071063
OS 1.8697708 2.0648201
OS 1.8733071 2.0595276
OS 1.8785996 2.0559913
OS 1.8848425 2.0547495
OS 1.8910854 2.0559913
OS 1.8963779 2.0595276
OS 1.8999142 2.0648201
OS 1.901156 2.071063
OS 1.8999142 2.0773059
OS 1.8963779 2.0825984
OS 1.8910854 2.0861347
OS 1.8848425 2.0873765
OE
OB 1.5682025 2.0840165 H
OS 1.5619596 2.0827747
OS 1.5566671 2.0792384
OS 1.5531308 2.0739459
OS 1.551889 2.067703
OS 1.5531308 2.0614601
OS 1.5566671 2.0561676
OS 1.5619596 2.0526313
OS 1.5682025 2.0513895
OS 1.5744454 2.0526313
OS 1.5797379 2.0561676
OS 1.5832742 2.0614601
OS 1.584516 2.067703
OS 1.5832742 2.0739459
OS 1.5797379 2.0792384
OS 1.5744454 2.0827747
OS 1.5682025 2.0840165
OE
OB 3.5717425 2.1163919 H
OS 3.5643954 2.1149305
OS 3.5581668 2.1107687
OS 3.554005 2.1045401
OS 3.5525436 2.097193
OS 3.554005 2.0898459
OS 3.5581668 2.0836173
OS 3.5643954 2.0794555
OS 3.5680713 2.0787243
OS 3.5680713 2.0736264
OS 3.5655996 2.0731347
OS 3.5603071 2.0695984
OS 3.5567708 2.0643059
OS 3.555529 2.058063
OS 3.5567708 2.0518201
OS 3.5584204 2.0493513
OS 3.5599241 2.045563
OS 3.5584204 2.0417747
OS 3.5567708 2.0393059
OS 3.555529 2.033063
OS 3.5567708 2.0268201
OS 3.5603071 2.0215276
OS 3.5655996 2.0179913
OS 3.5718425 2.0167495
OS 3.5780854 2.0179913
OS 3.5833779 2.0215276
OS 3.5869142 2.0268201
OS 3.588156 2.033063
OS 3.5869142 2.0393059
OS 3.5852646 2.0417747
OS 3.5837609 2.045563
OS 3.5852646 2.0493513
OS 3.5869142 2.0518201
OS 3.588156 2.058063
OS 3.5869142 2.0643059
OS 3.5833779 2.0695984
OS 3.5780854 2.0731347
OS 3.5755137 2.0736462
OS 3.5755137 2.0787442
OS 3.5790896 2.0794555
OS 3.5853182 2.0836173
OS 3.58948 2.0898459
OS 3.5909414 2.097193
OS 3.58948 2.1045401
OS 3.5853182 2.1107687
OS 3.5790896 2.1149305
OS 3.5717425 2.1163919
OE
OB 2.4098425 1.9833765 H
OS 2.4035996 1.9821347
OS 2.3983071 1.9785984
OS 2.3947708 1.9733059
OS 2.393529 1.967063
OS 2.3947708 1.9608201
OS 2.3961401 1.9587707
OS 2.3925353 1.9551659
OS 2.3910854 1.9561347
OS 2.3848425 1.9573765
OS 2.3785996 1.9561347
OS 2.3733071 1.9525984
OS 2.3697708 1.9473059
OS 2.368529 1.941063
OS 2.3697708 1.9348201
OS 2.3733071 1.9295276
OS 2.3785996 1.9259913
OS 2.3848425 1.9247495
OS 2.3910854 1.9259913
OS 2.3963779 1.9295276
OS 2.3999142 1.9348201
OS 2.401156 1.941063
OS 2.3999142 1.9473059
OS 2.3985449 1.9493553
OS 2.4021497 1.9529601
OS 2.4035996 1.9519913
OS 2.4098425 1.9507495
OS 2.4160854 1.9519913
OS 2.4213779 1.9555276
OS 2.4249142 1.9608201
OS 2.426156 1.967063
OS 2.4249142 1.9733059
OS 2.4213779 1.9785984
OS 2.4160854 1.9821347
OS 2.4098425 1.9833765
OE
OB 3.2988425 1.9873765 H
OS 3.2925996 1.9861347
OS 3.2873071 1.9825984
OS 3.2837708 1.9773059
OS 3.282529 1.971063
OS 3.2837708 1.9648201
OS 3.2873071 1.9595276
OS 3.2925996 1.9559913
OS 3.2988425 1.9547495
OS 3.3050854 1.9559913
OS 3.3103779 1.9595276
OS 3.3139142 1.9648201
OS 3.315156 1.971063
OS 3.3139142 1.9773059
OS 3.3103779 1.9825984
OS 3.3050854 1.9861347
OS 3.2988425 1.9873765
OE
OB 1.0098425 1.9723765 H
OS 1.0035996 1.9711347
OS 0.9983071 1.9675984
OS 0.9947708 1.9623059
OS 0.993529 1.956063
OS 0.9947708 1.9498201
OS 0.9983071 1.9445276
OS 1.0035996 1.9409913
OS 1.0098425 1.9397495
OS 1.0160854 1.9409913
OS 1.0213779 1.9445276
OS 1.0249142 1.9498201
OS 1.026156 1.956063
OS 1.0249142 1.9623059
OS 1.0213779 1.9675984
OS 1.0160854 1.9711347
OS 1.0098425 1.9723765
OE
OB 2.2998425 1.9323765 H
OS 2.2935996 1.9311347
OS 2.2883071 1.9275984
OS 2.2847708 1.9223059
OS 2.283529 1.916063
OS 2.2847708 1.9098201
OS 2.2883071 1.9045276
OS 2.2935996 1.9009913
OS 2.2998425 1.8997495
OS 2.3060854 1.9009913
OS 2.3113779 1.9045276
OS 2.3149142 1.9098201
OS 2.316156 1.916063
OS 2.3149142 1.9223059
OS 2.3113779 1.9275984
OS 2.3060854 1.9311347
OS 2.2998425 1.9323765
OE
OB 0.1998425 2.0203727 H
OS 0.1872963 2.019137
OS 0.1752322 2.0154774
OS 0.1641139 2.0095346
OS 0.1543687 2.0015368
OS 0.1463709 1.9917916
OS 0.1404281 1.9806733
OS 0.1367685 1.9686092
OS 0.1355328 1.956063
OS 0.1367685 1.9435168
OS 0.1404281 1.9314527
OS 0.1463709 1.9203344
OS 0.1543687 1.9105892
OS 0.1641139 1.9025914
OS 0.1752322 1.8966486
OS 0.1872963 1.892989
OS 0.1998425 1.8917533
OS 0.2123887 1.892989
OS 0.2244528 1.8966486
OS 0.2355711 1.9025914
OS 0.2453163 1.9105892
OS 0.2533141 1.9203344
OS 0.2592569 1.9314527
OS 0.2629165 1.9435168
OS 0.2641522 1.956063
OS 0.2629165 1.9686092
OS 0.2592569 1.9806733
OS 0.2533141 1.9917916
OS 0.2453163 2.0015368
OS 0.2355711 2.0095346
OS 0.2244528 2.0154774
OS 0.2123887 2.019137
OS 0.1998425 2.0203727
OE
OB 3.5548425 1.9073765 H
OS 3.5485996 1.9061347
OS 3.5433071 1.9025984
OS 3.5397708 1.8973059
OS 3.538529 1.891063
OS 3.5397708 1.8848201
OS 3.5433071 1.8795276
OS 3.5485996 1.8759913
OS 3.5548425 1.8747495
OS 3.5610854 1.8759913
OS 3.5663779 1.8795276
OS 3.5699142 1.8848201
OS 3.571156 1.891063
OS 3.5699142 1.8973059
OS 3.5663779 1.9025984
OS 3.5610854 1.9061347
OS 3.5548425 1.9073765
OE
OB 3.3928425 1.8873765 H
OS 3.3865996 1.8861347
OS 3.3813071 1.8825984
OS 3.3777708 1.8773059
OS 3.376529 1.871063
OS 3.3777708 1.8648201
OS 3.3813071 1.8595276
OS 3.3865996 1.8559913
OS 3.3928425 1.8547495
OS 3.3990854 1.8559913
OS 3.4043779 1.8595276
OS 3.4079142 1.8648201
OS 3.409156 1.871063
OS 3.4079142 1.8773059
OS 3.4043779 1.8825984
OS 3.3990854 1.8861347
OS 3.3928425 1.8873765
OE
OB 3.4392507 1.8872515 H
OS 3.4330078 1.8860097
OS 3.4277153 1.8824734
OS 3.424179 1.8771809
OS 3.4229372 1.870938
OS 3.424179 1.8646951
OS 3.4277153 1.8594026
OS 3.4330078 1.8558663
OS 3.4392507 1.8546245
OS 3.4454936 1.8558663
OS 3.4507861 1.8594026
OS 3.4543224 1.8646951
OS 3.4555642 1.870938
OS 3.4543224 1.8771809
OS 3.4507861 1.8824734
OS 3.4454936 1.8860097
OS 3.4392507 1.8872515
OE
OB 3.8048425 1.8563765 H
OS 3.7985996 1.8551347
OS 3.7933071 1.8515984
OS 3.7897708 1.8463059
OS 3.788529 1.840063
OS 3.7897708 1.8338201
OS 3.7933071 1.8285276
OS 3.7985996 1.8249913
OS 3.8048425 1.8237495
OS 3.8110854 1.8249913
OS 3.8163779 1.8285276
OS 3.8199142 1.8338201
OS 3.821156 1.840063
OS 3.8199142 1.8463059
OS 3.8163779 1.8515984
OS 3.8110854 1.8551347
OS 3.8048425 1.8563765
OE
OB 3.3291721 1.8423765 H
OS 3.3229292 1.8411347
OS 3.3176367 1.8375984
OS 3.3141004 1.8323059
OS 3.3128586 1.826063
OS 3.3141004 1.8198201
OS 3.3176367 1.8145276
OS 3.3229292 1.8109913
OS 3.3291721 1.8097495
OS 3.335415 1.8109913
OS 3.3407075 1.8145276
OS 3.3442438 1.8198201
OS 3.3454856 1.826063
OS 3.3442438 1.8323059
OS 3.3407075 1.8375984
OS 3.335415 1.8411347
OS 3.3291721 1.8423765
OE
OB 1.3937008 1.8332426 H
OS 1.3874579 1.8320008
OS 1.3821654 1.8284645
OS 1.3786291 1.823172
OS 1.3773873 1.8169291
OS 1.3786291 1.8106862
OS 1.3821654 1.8053937
OS 1.3874579 1.8018574
OS 1.3937008 1.8006156
OS 1.3999437 1.8018574
OS 1.4052362 1.8053937
OS 1.4087725 1.8106862
OS 1.4100143 1.8169291
OS 1.4087725 1.823172
OS 1.4052362 1.8284645
OS 1.3999437 1.8320008
OS 1.3937008 1.8332426
OE
OB 3.9448425 1.8323765 H
OS 3.9385996 1.8311347
OS 3.9333071 1.8275984
OS 3.9297708 1.8223059
OS 3.928529 1.816063
OS 3.9297708 1.8098201
OS 3.9333071 1.8045276
OS 3.9385996 1.8009913
OS 3.9448425 1.7997495
OS 3.9510854 1.8009913
OS 3.9563779 1.8045276
OS 3.9599142 1.8098201
OS 3.961156 1.816063
OS 3.9599142 1.8223059
OS 3.9563779 1.8275984
OS 3.9510854 1.8311347
OS 3.9448425 1.8323765
OE
OB 3.0568817 1.8281165 H
OS 3.0506388 1.8268747
OS 3.0453463 1.8233384
OS 3.04181 1.8180459
OS 3.0405682 1.811803
OS 3.04181 1.8055601
OS 3.0453463 1.8002676
OS 3.0506388 1.7967313
OS 3.0568817 1.7954895
OS 3.0631246 1.7967313
OS 3.0684171 1.8002676
OS 3.0719534 1.8055601
OS 3.0731952 1.811803
OS 3.0719534 1.8180459
OS 3.0684171 1.8233384
OS 3.0631246 1.8268747
OS 3.0568817 1.8281165
OE
OB 1.8799377 1.8281165 H
OS 1.8736948 1.8268747
OS 1.8684023 1.8233384
OS 1.864866 1.8180459
OS 1.8636242 1.811803
OS 1.864866 1.8055601
OS 1.8684023 1.8002676
OS 1.8736948 1.7967313
OS 1.8799377 1.7954895
OS 1.8861806 1.7967313
OS 1.8914731 1.8002676
OS 1.8950094 1.8055601
OS 1.8962512 1.811803
OS 1.8950094 1.8180459
OS 1.8914731 1.8233384
OS 1.8861806 1.8268747
OS 1.8799377 1.8281165
OE
OB 4.0648425 1.8123765 H
OS 4.0585996 1.8111347
OS 4.0533071 1.8075984
OS 4.0497708 1.8023059
OS 4.048529 1.796063
OS 4.0497708 1.7898201
OS 4.0533071 1.7845276
OS 4.0585996 1.7809913
OS 4.0648425 1.7797495
OS 4.0710854 1.7809913
OS 4.0763779 1.7845276
OS 4.0799142 1.7898201
OS 4.081156 1.796063
OS 4.0799142 1.8023059
OS 4.0763779 1.8075984
OS 4.0710854 1.8111347
OS 4.0648425 1.8123765
OE
OB 2.5798425 1.8063765 H
OS 2.5735996 1.8051347
OS 2.5683071 1.8015984
OS 2.5647708 1.7963059
OS 2.563529 1.790063
OS 2.5647708 1.7838201
OS 2.5683071 1.7785276
OS 2.5735996 1.7749913
OS 2.5798425 1.7737495
OS 2.5860854 1.7749913
OS 2.5913779 1.7785276
OS 2.5949142 1.7838201
OS 2.596156 1.790063
OS 2.5949142 1.7963059
OS 2.5913779 1.8015984
OS 2.5860854 1.8051347
OS 2.5798425 1.8063765
OE
OB 2.6268425 1.7863765 H
OS 2.6205996 1.7851347
OS 2.6153071 1.7815984
OS 2.6117708 1.7763059
OS 2.610529 1.770063
OS 2.6117708 1.7638201
OS 2.6153071 1.7585276
OS 2.6205996 1.7549913
OS 2.6268425 1.7537495
OS 2.6330854 1.7549913
OS 2.6383779 1.7585276
OS 2.6419142 1.7638201
OS 2.643156 1.770063
OS 2.6419142 1.7763059
OS 2.6383779 1.7815984
OS 2.6330854 1.7851347
OS 2.6268425 1.7863765
OE
OB 3.7198425 1.7823765 H
OS 3.7135996 1.7811347
OS 3.7083071 1.7775984
OS 3.7047708 1.7723059
OS 3.703529 1.766063
OS 3.7047708 1.7598201
OS 3.7083071 1.7545276
OS 3.7135996 1.7509913
OS 3.7198425 1.7497495
OS 3.7260854 1.7509913
OS 3.7313779 1.7545276
OS 3.7349142 1.7598201
OS 3.736156 1.766063
OS 3.7349142 1.7723059
OS 3.7313779 1.7775984
OS 3.7260854 1.7811347
OS 3.7198425 1.7823765
OE
OB 2.5498425 1.7713765 H
OS 2.5435996 1.7701347
OS 2.5383071 1.7665984
OS 2.5347708 1.7613059
OS 2.533529 1.755063
OS 2.5347708 1.7488201
OS 2.5383071 1.7435276
OS 2.5435996 1.7399913
OS 2.5498425 1.7387495
OS 2.5560854 1.7399913
OS 2.5613779 1.7435276
OS 2.5649142 1.7488201
OS 2.566156 1.755063
OS 2.5649142 1.7613059
OS 2.5613779 1.7665984
OS 2.5560854 1.7701347
OS 2.5498425 1.7713765
OE
OB 4.1348425 1.7673765 H
OS 4.1285996 1.7661347
OS 4.1233071 1.7625984
OS 4.1197708 1.7573059
OS 4.118529 1.751063
OS 4.1197708 1.7448201
OS 4.1233071 1.7395276
OS 4.1285996 1.7359913
OS 4.1348425 1.7347495
OS 4.1410854 1.7359913
OS 4.1463779 1.7395276
OS 4.1499142 1.7448201
OS 4.151156 1.751063
OS 4.1499142 1.7573059
OS 4.1463779 1.7625984
OS 4.1410854 1.7661347
OS 4.1348425 1.7673765
OE
OB 2.6048425 1.7503765 H
OS 2.5985996 1.7491347
OS 2.5933071 1.7455984
OS 2.5897708 1.7403059
OS 2.588529 1.734063
OS 2.5897708 1.7278201
OS 2.5933071 1.7225276
OS 2.5985996 1.7189913
OS 2.6048425 1.7177495
OS 2.6110854 1.7189913
OS 2.6163779 1.7225276
OS 2.6199142 1.7278201
OS 2.621156 1.734063
OS 2.6199142 1.7403059
OS 2.6163779 1.7455984
OS 2.6110854 1.7491347
OS 2.6048425 1.7503765
OE
OB 0.988189 1.7338332 H
OS 0.9819461 1.7325914
OS 0.9766536 1.7290551
OS 0.9731173 1.7237626
OS 0.9718755 1.7175197
OS 0.9731173 1.7112768
OS 0.9766536 1.7059843
OS 0.9819461 1.702448
OS 0.988189 1.7012062
OS 0.9944319 1.702448
OS 0.9997244 1.7059843
OS 1.0032607 1.7112768
OS 1.0045025 1.7175197
OS 1.0032607 1.7237626
OS 0.9997244 1.7290551
OS 0.9944319 1.7325914
OS 0.988189 1.7338332
OE
OB 3.1972633 1.7303765 H
OS 3.1910204 1.7291347
OS 3.1857279 1.7255984
OS 3.1821916 1.7203059
OS 3.1809498 1.714063
OS 3.1821916 1.7078201
OS 3.1857279 1.7025276
OS 3.1910204 1.6989913
OS 3.1972633 1.6977495
OS 3.2035062 1.6989913
OS 3.2087987 1.7025276
OS 3.212335 1.7078201
OS 3.2135768 1.714063
OS 3.212335 1.7203059
OS 3.2087987 1.7255984
OS 3.2035062 1.7291347
OS 3.1972633 1.7303765
OE
OB 3.5898425 1.7273765 H
OS 3.5835996 1.7261347
OS 3.5783071 1.7225984
OS 3.5747708 1.7173059
OS 3.573529 1.711063
OS 3.5747708 1.7048201
OS 3.5783071 1.6995276
OS 3.5835996 1.6959913
OS 3.5898425 1.6947495
OS 3.5960854 1.6959913
OS 3.6013779 1.6995276
OS 3.6049142 1.7048201
OS 3.606156 1.711063
OS 3.6049142 1.7173059
OS 3.6013779 1.7225984
OS 3.5960854 1.7261347
OS 3.5898425 1.7273765
OE
OB 1.8938425 1.7093765 H
OS 1.8875996 1.7081347
OS 1.8823071 1.7045984
OS 1.8787708 1.6993059
OS 1.877529 1.693063
OS 1.8787708 1.6868201
OS 1.8823071 1.6815276
OS 1.8875996 1.6779913
OS 1.8938425 1.6767495
OS 1.9000854 1.6779913
OS 1.9053779 1.6815276
OS 1.9089142 1.6868201
OS 1.910156 1.693063
OS 1.9089142 1.6993059
OS 1.9053779 1.7045984
OS 1.9000854 1.7081347
OS 1.8938425 1.7093765
OE
OB 3.8038425 1.7073765 H
OS 3.7975996 1.7061347
OS 3.7923071 1.7025984
OS 3.7887708 1.6973059
OS 3.787529 1.691063
OS 3.7887708 1.6848201
OS 3.7923071 1.6795276
OS 3.7975996 1.6759913
OS 3.8038425 1.6747495
OS 3.8100854 1.6759913
OS 3.8153779 1.6795276
OS 3.8189142 1.6848201
OS 3.820156 1.691063
OS 3.8189142 1.6973059
OS 3.8153779 1.7025984
OS 3.8100854 1.7061347
OS 3.8038425 1.7073765
OE
OB 3.7248425 1.6913765 H
OS 3.7185996 1.6901347
OS 3.7133071 1.6865984
OS 3.7097708 1.6813059
OS 3.708529 1.675063
OS 3.7097708 1.6688201
OS 3.7133071 1.6635276
OS 3.7185996 1.6599913
OS 3.7248425 1.6587495
OS 3.7310854 1.6599913
OS 3.7363779 1.6635276
OS 3.7399142 1.6688201
OS 3.741156 1.675063
OS 3.7399142 1.6813059
OS 3.7363779 1.6865984
OS 3.7310854 1.6901347
OS 3.7248425 1.6913765
OE
OB 1.8227825 1.6903165 H
OS 1.8165396 1.6890747
OS 1.8112471 1.6855384
OS 1.8077108 1.6802459
OS 1.806469 1.674003
OS 1.8077108 1.6677601
OS 1.8112471 1.6624676
OS 1.8165396 1.6589313
OS 1.8227825 1.6576895
OS 1.8290254 1.6589313
OS 1.8343179 1.6624676
OS 1.8378542 1.6677601
OS 1.839096 1.674003
OS 1.8378542 1.6802459
OS 1.8343179 1.6855384
OS 1.8290254 1.6890747
OS 1.8227825 1.6903165
OE
OB 3.7738632 1.6824156 H
OS 3.7676203 1.6811738
OS 3.7623278 1.6776375
OS 3.7587915 1.672345
OS 3.7575497 1.6661021
OS 3.7587915 1.6598592
OS 3.7623278 1.6545667
OS 3.7676203 1.6510304
OS 3.7738632 1.6497886
OS 3.7801061 1.6510304
OS 3.7853986 1.6545667
OS 3.7889349 1.6598592
OS 3.7901767 1.6661021
OS 3.7889349 1.672345
OS 3.7853986 1.6776375
OS 3.7801061 1.6811738
OS 3.7738632 1.6824156
OE
OB 6.8448425 1.6773765 H
OS 6.8385996 1.6761347
OS 6.8333071 1.6725984
OS 6.8297708 1.6673059
OS 6.828529 1.661063
OS 6.8297708 1.6548201
OS 6.8333071 1.6495276
OS 6.8385996 1.6459913
OS 6.8448425 1.6447495
OS 6.8510854 1.6459913
OS 6.8563779 1.6495276
OS 6.8599142 1.6548201
OS 6.861156 1.661063
OS 6.8599142 1.6673059
OS 6.8563779 1.6725984
OS 6.8510854 1.6761347
OS 6.8448425 1.6773765
OE
OB 3.2248425 1.6776607 H
OS 3.2185996 1.6764189
OS 3.2133071 1.6728826
OS 3.2097708 1.6675901
OS 3.208529 1.6613472
OS 3.2097708 1.6551043
OS 3.2133071 1.6498118
OS 3.2185996 1.6462755
OS 3.2248425 1.6450337
OS 3.2310854 1.6462755
OS 3.235497 1.6492232
OS 3.2395781 1.6496996
OS 3.2419254 1.6491144
OS 3.2465996 1.6459913
OS 3.2528425 1.6447495
OS 3.2590854 1.6459913
OS 3.2643779 1.6495276
OS 3.2679142 1.6548201
OS 3.269156 1.661063
OS 3.2679142 1.6673059
OS 3.2643779 1.6725984
OS 3.2590854 1.6761347
OS 3.2528425 1.6773765
OS 3.2465996 1.6761347
OS 3.242188 1.673187
OS 3.2381069 1.6727106
OS 3.2357596 1.6732958
OS 3.2310854 1.6764189
OS 3.2248425 1.6776607
OE
OB 2.6668425 1.6563765 H
OS 2.6605996 1.6551347
OS 2.6553071 1.6515984
OS 2.6517708 1.6463059
OS 2.650529 1.640063
OS 2.6513707 1.6358317
OS 2.6479104 1.6318625
OS 2.6474924 1.6316505
OS 2.6438425 1.6323765
OS 2.6375996 1.6311347
OS 2.6323071 1.6275984
OS 2.6287708 1.6223059
OS 2.627529 1.616063
OS 2.6287708 1.6098201
OS 2.6323071 1.6045276
OS 2.6375996 1.6009913
OS 2.6438425 1.5997495
OS 2.6500854 1.6009913
OS 2.6553779 1.6045276
OS 2.6589142 1.6098201
OS 2.660156 1.616063
OS 2.6593143 1.6202943
OS 2.6627746 1.6242635
OS 2.6631926 1.6244755
OS 2.6668425 1.6237495
OS 2.6730854 1.6249913
OS 2.6783779 1.6285276
OS 2.6819142 1.6338201
OS 2.683156 1.640063
OS 2.6819142 1.6463059
OS 2.6783779 1.6515984
OS 2.6730854 1.6551347
OS 2.6668425 1.6563765
OE
OB 4.1348425 1.6673765 H
OS 4.1285996 1.6661347
OS 4.1233071 1.6625984
OS 4.1197708 1.6573059
OS 4.118529 1.651063
OS 4.1197708 1.6448201
OS 4.1233071 1.6395276
OS 4.1285996 1.6359913
OS 4.1336434 1.634988
OS 4.1357664 1.6316625
OS 4.1362826 1.629938
OS 4.1362346 1.6298661
OS 4.1349928 1.6236232
OS 4.1362346 1.6173803
OS 4.1397709 1.6120878
OS 4.1450634 1.6085515
OS 4.1513063 1.6073097
OS 4.1575492 1.6085515
OS 4.1612353 1.6110144
OS 4.1648401 1.6074096
OS 4.1647708 1.6073059
OS 4.163529 1.601063
OS 4.1647708 1.5948201
OS 4.1683071 1.5895276
OS 4.1735996 1.5859913
OS 4.1798425 1.5847495
OS 4.1860854 1.5859913
OS 4.1913779 1.5895276
OS 4.1949142 1.5948201
OS 4.196156 1.601063
OS 4.1949142 1.6073059
OS 4.1913779 1.6125984
OS 4.1860854 1.6161347
OS 4.1798425 1.6173765
OS 4.1735996 1.6161347
OS 4.1699135 1.6136718
OS 4.1663087 1.6172766
OS 4.166378 1.6173803
OS 4.1676198 1.6236232
OS 4.166378 1.6298661
OS 4.1628417 1.6351586
OS 4.1575492 1.6386949
OS 4.1525054 1.6396982
OS 4.1503824 1.6430237
OS 4.1498662 1.6447482
OS 4.1499142 1.6448201
OS 4.151156 1.651063
OS 4.1499142 1.6573059
OS 4.1463779 1.6625984
OS 4.1410854 1.6661347
OS 4.1348425 1.6673765
OE
OB 2.7198425 1.6073765 H
OS 2.7135996 1.6061347
OS 2.7083071 1.6025984
OS 2.7047708 1.5973059
OS 2.703529 1.591063
OS 2.7047708 1.5848201
OS 2.7083071 1.5795276
OS 2.7135996 1.5759913
OS 2.7198425 1.5747495
OS 2.7260854 1.5759913
OS 2.7313779 1.5795276
OS 2.7349142 1.5848201
OS 2.736156 1.591063
OS 2.7349142 1.5973059
OS 2.7313779 1.6025984
OS 2.7260854 1.6061347
OS 2.7198425 1.6073765
OE
OB 3.8948425 1.5823765 H
OS 3.8885996 1.5811347
OS 3.8833071 1.5775984
OS 3.8797708 1.5723059
OS 3.878529 1.566063
OS 3.8797708 1.5598201
OS 3.8833071 1.5545276
OS 3.8885996 1.5509913
OS 3.8948425 1.5497495
OS 3.9010854 1.5509913
OS 3.9063779 1.5545276
OS 3.9099142 1.5598201
OS 3.911156 1.566063
OS 3.9099142 1.5723059
OS 3.9063779 1.5775984
OS 3.9010854 1.5811347
OS 3.8948425 1.5823765
OE
OB 3.9698425 1.5683765 H
OS 3.9635996 1.5671347
OS 3.9583071 1.5635984
OS 3.9547708 1.5583059
OS 3.953529 1.552063
OS 3.9547708 1.5458201
OS 3.9583071 1.5405276
OS 3.9635996 1.5369913
OS 3.9698425 1.5357495
OS 3.9760854 1.5369913
OS 3.9780923 1.5383323
OS 3.9831154 1.5394836
OS 3.9856688 1.5379496
OS 3.9885996 1.5359913
OS 3.9948425 1.5347495
OS 4.0010854 1.5359913
OS 4.0063779 1.5395276
OS 4.0099142 1.5448201
OS 4.011156 1.551063
OS 4.0099142 1.5573059
OS 4.0063779 1.5625984
OS 4.0010854 1.5661347
OS 3.9948425 1.5673765
OS 3.9885996 1.5661347
OS 3.9833072 1.5625984
OS 3.982046 1.5625984
OS 3.9813779 1.5635984
OS 3.9760854 1.5671347
OS 3.9698425 1.5683765
OE
OB 4.0348425 1.5623765 H
OS 4.0285996 1.5611347
OS 4.0233071 1.5575984
OS 4.0197708 1.5523059
OS 4.018529 1.546063
OS 4.0197708 1.5398201
OS 4.0233071 1.5345276
OS 4.0285996 1.5309913
OS 4.0348425 1.5297495
OS 4.0410854 1.5309913
OS 4.0463779 1.5345276
OS 4.0499142 1.5398201
OS 4.051156 1.546063
OS 4.0499142 1.5523059
OS 4.0463779 1.5575984
OS 4.0410854 1.5611347
OS 4.0348425 1.5623765
OE
OB 3.9248425 1.5523765 H
OS 3.9185996 1.5511347
OS 3.9133071 1.5475984
OS 3.9097708 1.5423059
OS 3.908529 1.536063
OS 3.9097708 1.5298201
OS 3.9133071 1.5245276
OS 3.9185996 1.5209913
OS 3.9248425 1.5197495
OS 3.9310854 1.5209913
OS 3.9363779 1.5245276
OS 3.9399142 1.5298201
OS 3.941156 1.536063
OS 3.9399142 1.5423059
OS 3.9363779 1.5475984
OS 3.9310854 1.5511347
OS 3.9248425 1.5523765
OE
OB 2.8948425 1.5773765 H
OS 2.8885996 1.5761347
OS 2.8833071 1.5725984
OS 2.8797708 1.5673059
OS 2.878529 1.561063
OS 2.8797708 1.5548201
OS 2.8833071 1.5495276
OS 2.8885996 1.5459913
OS 2.8948425 1.5447495
OS 2.9010854 1.5459913
OS 2.9013282 1.5461536
OS 2.9049331 1.5425487
OS 2.9047708 1.5423059
OS 2.903529 1.536063
OS 2.9047708 1.5298201
OS 2.9083071 1.5245276
OS 2.9135996 1.5209913
OS 2.9198425 1.5197495
OS 2.9260854 1.5209913
OS 2.9313779 1.5245276
OS 2.9349142 1.5298201
OS 2.936156 1.536063
OS 2.9349142 1.5423059
OS 2.9313779 1.5475984
OS 2.9260854 1.5511347
OS 2.9198425 1.5523765
OS 2.9135996 1.5511347
OS 2.9133568 1.5509724
OS 2.9097519 1.5545773
OS 2.9099142 1.5548201
OS 2.911156 1.561063
OS 2.9099142 1.5673059
OS 2.9063779 1.5725984
OS 2.9010854 1.5761347
OS 2.8948425 1.5773765
OE
OB 1.7198425 1.5523765 H
OS 1.7135996 1.5511347
OS 1.7083071 1.5475984
OS 1.7047708 1.5423059
OS 1.703529 1.536063
OS 1.7047708 1.5298201
OS 1.7083071 1.5245276
OS 1.7135996 1.5209913
OS 1.7198425 1.5197495
OS 1.7260854 1.5209913
OS 1.7313779 1.5245276
OS 1.7349142 1.5298201
OS 1.736156 1.536063
OS 1.7349142 1.5423059
OS 1.7313779 1.5475984
OS 1.7260854 1.5511347
OS 1.7198425 1.5523765
OE
OB 1.8973025 1.5328365 H
OS 1.8910596 1.5315947
OS 1.8857671 1.5280584
OS 1.8822308 1.5227659
OS 1.880989 1.516523
OS 1.8822308 1.5102801
OS 1.8857671 1.5049876
OS 1.8910596 1.5014513
OS 1.8973025 1.5002095
OS 1.9035454 1.5014513
OS 1.9088379 1.5049876
OS 1.9123742 1.5102801
OS 1.913616 1.516523
OS 1.9123742 1.5227659
OS 1.9088379 1.5280584
OS 1.9035454 1.5315947
OS 1.8973025 1.5328365
OE
OB 4.0648425 1.5273765 H
OS 4.0585996 1.5261347
OS 4.0533071 1.5225984
OS 4.0497708 1.5173059
OS 4.048529 1.511063
OS 4.0497708 1.5048201
OS 4.0533071 1.4995276
OS 4.0585996 1.4959913
OS 4.0648425 1.4947495
OS 4.0710854 1.4959913
OS 4.0763779 1.4995276
OS 4.0799142 1.5048201
OS 4.081156 1.511063
OS 4.0799142 1.5173059
OS 4.0763779 1.5225984
OS 4.0710854 1.5261347
OS 4.0648425 1.5273765
OE
OB 3.8648425 1.5273765 H
OS 3.8585996 1.5261347
OS 3.8533071 1.5225984
OS 3.8497708 1.5173059
OS 3.848529 1.511063
OS 3.8497708 1.5048201
OS 3.8533071 1.4995276
OS 3.8585996 1.4959913
OS 3.8648425 1.4947495
OS 3.8710854 1.4959913
OS 3.8763779 1.4995276
OS 3.8799142 1.5048201
OS 3.881156 1.511063
OS 3.8799142 1.5173059
OS 3.8763779 1.5225984
OS 3.8710854 1.5261347
OS 3.8648425 1.5273765
OE
OB 2.2748425 1.5223765 H
OS 2.2685996 1.5211347
OS 2.2633071 1.5175984
OS 2.2597708 1.5123059
OS 2.258529 1.506063
OS 2.2597708 1.4998201
OS 2.2633071 1.4945276
OS 2.2685996 1.4909913
OS 2.2748425 1.4897495
OS 2.2810854 1.4909913
OS 2.2863779 1.4945276
OS 2.2899142 1.4998201
OS 2.291156 1.506063
OS 2.2899142 1.5123059
OS 2.2863779 1.5175984
OS 2.2810854 1.5211347
OS 2.2748425 1.5223765
OE
OB 3.8348425 1.4973765 H
OS 3.8285996 1.4961347
OS 3.8233071 1.4925984
OS 3.8197708 1.4873059
OS 3.818529 1.481063
OS 3.8197708 1.4748201
OS 3.8233071 1.4695276
OS 3.8285996 1.4659913
OS 3.8348425 1.4647495
OS 3.8410854 1.4659913
OS 3.8463779 1.4695276
OS 3.8499142 1.4748201
OS 3.851156 1.481063
OS 3.8499142 1.4873059
OS 3.8463779 1.4925984
OS 3.8410854 1.4961347
OS 3.8348425 1.4973765
OE
OB 2.6948425 1.4973765 H
OS 2.6885996 1.4961347
OS 2.6833071 1.4925984
OS 2.6797708 1.4873059
OS 2.678529 1.481063
OS 2.6797708 1.4748201
OS 2.6833071 1.4695276
OS 2.6885996 1.4659913
OS 2.6948425 1.4647495
OS 2.7010854 1.4659913
OS 2.7063779 1.4695276
OS 2.7099142 1.4748201
OS 2.711156 1.481063
OS 2.7099142 1.4873059
OS 2.7063779 1.4925984
OS 2.7010854 1.4961347
OS 2.6948425 1.4973765
OE
OB 3.5498425 1.4573765 H
OS 3.5435996 1.4561347
OS 3.5383071 1.4525984
OS 3.5347708 1.4473059
OS 3.533529 1.441063
OS 3.5347708 1.4348201
OS 3.5383071 1.4295276
OS 3.5435996 1.4259913
OS 3.5498425 1.4247495
OS 3.5560854 1.4259913
OS 3.5613779 1.4295276
OS 3.5649142 1.4348201
OS 3.566156 1.441063
OS 3.5649142 1.4473059
OS 3.5613779 1.4525984
OS 3.5560854 1.4561347
OS 3.5498425 1.4573765
OE
OB 2.4468425 1.4533765 H
OS 2.4405996 1.4521347
OS 2.4353071 1.4485984
OS 2.4317708 1.4433059
OS 2.430529 1.437063
OS 2.4317708 1.4308201
OS 2.4353071 1.4255276
OS 2.4405996 1.4219913
OS 2.4468425 1.4207495
OS 2.4530854 1.4219913
OS 2.4583779 1.4255276
OS 2.4619142 1.4308201
OS 2.463156 1.437063
OS 2.4619142 1.4433059
OS 2.4583779 1.4485984
OS 2.4530854 1.4521347
OS 2.4468425 1.4533765
OE
OB 1.0088425 1.4463765 H
OS 1.0025996 1.4451347
OS 0.9973071 1.4415984
OS 0.9937708 1.4363059
OS 0.992529 1.430063
OS 0.9937708 1.4238201
OS 0.9973071 1.4185276
OS 1.0025996 1.4149913
OS 1.0088425 1.4137495
OS 1.0150854 1.4149913
OS 1.0203779 1.4185276
OS 1.0239142 1.4238201
OS 1.025156 1.430063
OS 1.0239142 1.4363059
OS 1.0203779 1.4415984
OS 1.0150854 1.4451347
OS 1.0088425 1.4463765
OE
OB 2.0838425 1.4279765 H
OS 2.0775996 1.4267347
OS 2.0723071 1.4231984
OS 2.0687708 1.4179059
OS 2.067529 1.411663
OS 2.0687708 1.4054201
OS 2.0688553 1.4052937
OS 2.0669242 1.4023943
OS 2.0655495 1.4012413
OS 2.0598425 1.4023765
OS 2.0535996 1.4011347
OS 2.0483071 1.3975984
OS 2.0447708 1.3923059
OS 2.043529 1.386063
OS 2.0447708 1.3798201
OS 2.0483071 1.3745276
OS 2.0535996 1.3709913
OS 2.0598425 1.3697495
OS 2.0660854 1.3709913
OS 2.0713779 1.3745276
OS 2.0749142 1.3798201
OS 2.076156 1.386063
OS 2.0749142 1.3923059
OS 2.0748297 1.3924323
OS 2.0767608 1.3953317
OS 2.0781355 1.3964847
OS 2.0838425 1.3953495
OS 2.0900854 1.3965913
OS 2.0953779 1.4001276
OS 2.0989142 1.4054201
OS 2.100156 1.411663
OS 2.0989142 1.4179059
OS 2.0953779 1.4231984
OS 2.0900854 1.4267347
OS 2.0838425 1.4279765
OE
OB 3.4072822 1.4276365 H
OS 3.4010393 1.4263947
OS 3.3957468 1.4228584
OS 3.3922105 1.4175659
OS 3.3909687 1.411323
OS 3.3922105 1.4050801
OS 3.3952066 1.4005957
OS 3.3913778 1.3975986
OS 3.3860854 1.4011347
OS 3.3798425 1.4023765
OS 3.3735996 1.4011347
OS 3.3683071 1.3975984
OS 3.3647708 1.3923059
OS 3.363529 1.386063
OS 3.3647708 1.3798201
OS 3.3683071 1.3745276
OS 3.3735996 1.3709913
OS 3.3798425 1.3697495
OS 3.3850268 1.3707807
OS 3.3880585 1.3685992
OS 3.3892832 1.3671145
OS 3.388529 1.363323
OS 3.3897708 1.3570801
OS 3.3920261 1.3537048
OS 3.3926608 1.3527545
OS 3.3890562 1.3491499
OS 3.3882815 1.3496673
OS 3.3860854 1.3511347
OS 3.3798425 1.3523765
OS 3.3735996 1.3511347
OS 3.3683071 1.3475984
OS 3.3647708 1.3423059
OS 3.363529 1.336063
OS 3.3647708 1.3298201
OS 3.3683071 1.3245276
OS 3.3735996 1.3209913
OS 3.3798425 1.3197495
OS 3.3860854 1.3209913
OS 3.3913779 1.3245276
OS 3.3949142 1.3298201
OS 3.396156 1.336063
OS 3.3949142 1.3423059
OS 3.3926589 1.3456812
OS 3.3920242 1.3466315
OS 3.3956288 1.3502361
OS 3.3964035 1.3497187
OS 3.3985996 1.3482513
OS 3.4048425 1.3470095
OS 3.4110854 1.3482513
OS 3.4163779 1.3517876
OS 3.4199142 1.3570801
OS 3.421156 1.363323
OS 3.4199142 1.3695659
OS 3.4163779 1.3748584
OS 3.4110854 1.3783947
OS 3.4048425 1.3796365
OS 3.3996582 1.3786053
OS 3.3966265 1.3807868
OS 3.3954018 1.3822715
OS 3.396156 1.386063
OS 3.3949142 1.3923059
OS 3.3919181 1.3967903
OS 3.3957469 1.3997874
OS 3.4010393 1.3962513
OS 3.4072822 1.3950095
OS 3.4135251 1.3962513
OS 3.4188176 1.3997876
OS 3.4223539 1.4050801
OS 3.4235957 1.411323
OS 3.4223539 1.4175659
OS 3.4188176 1.4228584
OS 3.4135251 1.4263947
OS 3.4072822 1.4276365
OE
OB 0.1998425 1.4953727 H
OS 0.1872963 1.494137
OS 0.1752322 1.4904774
OS 0.1641139 1.4845346
OS 0.1543687 1.4765368
OS 0.1463709 1.4667916
OS 0.1404281 1.4556733
OS 0.1367685 1.4436092
OS 0.1355328 1.431063
OS 0.1367685 1.4185168
OS 0.1404281 1.4064527
OS 0.1463709 1.3953344
OS 0.1543687 1.3855892
OS 0.1641139 1.3775914
OS 0.1752322 1.3716486
OS 0.1872963 1.367989
OS 0.1998425 1.3667533
OS 0.2123887 1.367989
OS 0.2244528 1.3716486
OS 0.2355711 1.3775914
OS 0.2453163 1.3855892
OS 0.2533141 1.3953344
OS 0.2592569 1.4064527
OS 0.2629165 1.4185168
OS 0.2641522 1.431063
OS 0.2629165 1.4436092
OS 0.2592569 1.4556733
OS 0.2533141 1.4667916
OS 0.2453163 1.4765368
OS 0.2355711 1.4845346
OS 0.2244528 1.4904774
OS 0.2123887 1.494137
OS 0.1998425 1.4953727
OE
OB 2.0288425 1.3779765 H
OS 2.0225996 1.3767347
OS 2.0173071 1.3731984
OS 2.0137708 1.3679059
OS 2.012529 1.361663
OS 2.0137708 1.3554201
OS 2.0138553 1.3552937
OS 2.0119242 1.3523943
OS 2.0105495 1.3512413
OS 2.0048425 1.3523765
OS 1.9985996 1.3511347
OS 1.9933071 1.3475984
OS 1.9897708 1.3423059
OS 1.988529 1.336063
OS 1.9897708 1.3298201
OS 1.9933071 1.3245276
OS 1.9985996 1.3209913
OS 2.0048425 1.3197495
OS 2.0110854 1.3209913
OS 2.0163779 1.3245276
OS 2.0199142 1.3298201
OS 2.021156 1.336063
OS 2.0199142 1.3423059
OS 2.0198297 1.3424323
OS 2.0217608 1.3453317
OS 2.0231355 1.3464847
OS 2.0288425 1.3453495
OS 2.0350854 1.3465913
OS 2.0403779 1.3501276
OS 2.0439142 1.3554201
OS 2.045156 1.361663
OS 2.0439142 1.3679059
OS 2.0403779 1.3731984
OS 2.0350854 1.3767347
OS 2.0288425 1.3779765
OE
OB 2.5028425 1.3323765 H
OS 2.4965996 1.3311347
OS 2.4913071 1.3275984
OS 2.4877708 1.3223059
OS 2.486529 1.316063
OS 2.4877708 1.3098201
OS 2.4913071 1.3045276
OS 2.4965996 1.3009913
OS 2.5028425 1.2997495
OS 2.5090854 1.3009913
OS 2.5143779 1.3045276
OS 2.5179142 1.3098201
OS 2.519156 1.316063
OS 2.5179142 1.3223059
OS 2.5143779 1.3275984
OS 2.5090854 1.3311347
OS 2.5028425 1.3323765
OE
OB 1.6968325 1.3290319 H
OS 1.6894854 1.3275705
OS 1.6832568 1.3234087
OS 1.679095 1.3171801
OS 1.6776336 1.309833
OS 1.679095 1.3024859
OS 1.6832568 1.2962573
OS 1.6894854 1.2920955
OS 1.6968325 1.2906341
OS 1.7041796 1.2920955
OS 1.7104082 1.2962573
OS 1.71457 1.3024859
OS 1.7160314 1.309833
OS 1.71457 1.3171801
OS 1.7104082 1.3234087
OS 1.7041796 1.3275705
OS 1.6968325 1.3290319
OE
OB 3.5717425 1.3289919 H
OS 3.5643954 1.3275305
OS 3.5581668 1.3233687
OS 3.554005 1.3171401
OS 3.5525436 1.309793
OS 3.554005 1.3024459
OS 3.5581668 1.2962173
OS 3.5643954 1.2920555
OS 3.5717425 1.2905941
OS 3.5790896 1.2920555
OS 3.5853182 1.2962173
OS 3.58948 1.3024459
OS 3.5909414 1.309793
OS 3.58948 1.3171401
OS 3.5853182 1.3233687
OS 3.5790896 1.3275305
OS 3.5717425 1.3289919
OE
OB 1.7982283 1.3204474 H
OS 1.7919854 1.3192056
OS 1.7866929 1.3156693
OS 1.7831566 1.3103768
OS 1.7819148 1.3041339
OS 1.7831566 1.297891
OS 1.7866929 1.2925985
OS 1.7919854 1.2890622
OS 1.7982283 1.2878204
OS 1.8044712 1.2890622
OS 1.8097637 1.2925985
OS 1.8133 1.297891
OS 1.8145418 1.3041339
OS 1.8133 1.3103768
OS 1.8097637 1.3156693
OS 1.8044712 1.3192056
OS 1.7982283 1.3204474
OE
OB 2.2068425 1.3143765 H
OS 2.2005996 1.3131347
OS 2.1953071 1.3095984
OS 2.1917708 1.3043059
OS 2.190529 1.298063
OS 2.1917708 1.2918201
OS 2.1953071 1.2865276
OS 2.2005996 1.2829913
OS 2.2068425 1.2817495
OS 2.2130854 1.2829913
OS 2.2183779 1.2865276
OS 2.2219142 1.2918201
OS 2.223156 1.298063
OS 2.2219142 1.3043059
OS 2.2183779 1.3095984
OS 2.2130854 1.3131347
OS 2.2068425 1.3143765
OE
OB 1.5679134 1.3017466 H
OS 1.5616705 1.3005048
OS 1.556378 1.2969685
OS 1.5528417 1.291676
OS 1.5515999 1.2854331
OS 1.5528417 1.2791902
OS 1.556378 1.2738977
OS 1.5616705 1.2703614
OS 1.5679134 1.2691196
OS 1.5741563 1.2703614
OS 1.5794488 1.2738977
OS 1.5829851 1.2791902
OS 1.5842269 1.2854331
OS 1.5829851 1.291676
OS 1.5794488 1.2969685
OS 1.5741563 1.3005048
OS 1.5679134 1.3017466
OE
OB 0.996063 1.2033214 H
OS 0.9898201 1.2020796
OS 0.9845276 1.1985433
OS 0.9809913 1.1932508
OS 0.9797495 1.1870079
OS 0.9809913 1.180765
OS 0.9845276 1.1754725
OS 0.9898201 1.1719362
OS 0.996063 1.1706944
OS 1.0023059 1.1719362
OS 1.0075984 1.1754725
OS 1.0111347 1.180765
OS 1.0123765 1.1870079
OS 1.0111347 1.1932508
OS 1.0075984 1.1985433
OS 1.0023059 1.2020796
OS 0.996063 1.2033214
OE
OB 2.8267717 0.9926915 H
OS 2.8205288 0.9914497
OS 2.8152364 0.9879134
OS 2.8107479 0.9879134
OS 2.8054555 0.9914497
OS 2.7992126 0.9926915
OS 2.7929697 0.9914497
OS 2.7876772 0.9879134
OS 2.7864713 0.9861086
OS 2.7804578 0.9861086
OS 2.7792519 0.9879134
OS 2.7739594 0.9914497
OS 2.7677165 0.9926915
OS 2.7614736 0.9914497
OS 2.7561812 0.9879134
OS 2.7516928 0.9879134
OS 2.7464004 0.9914497
OS 2.7401575 0.9926915
OS 2.7339146 0.9914497
OS 2.7286221 0.9879134
OS 2.7274162 0.9861086
OS 2.7214027 0.9861086
OS 2.7201968 0.9879134
OS 2.7149043 0.9914497
OS 2.7086614 0.9926915
OS 2.7024185 0.9914497
OS 2.6971261 0.9879134
OS 2.6926377 0.9879134
OS 2.6873453 0.9914497
OS 2.6811024 0.9926915
OS 2.6748595 0.9914497
OS 2.669567 0.9879134
OS 2.6683611 0.9861086
OS 2.6623476 0.9861086
OS 2.6611417 0.9879134
OS 2.6558492 0.9914497
OS 2.6496063 0.9926915
OS 2.6433634 0.9914497
OS 2.638071 0.9879134
OS 2.6335825 0.9879134
OS 2.6282901 0.9914497
OS 2.6220472 0.9926915
OS 2.6158043 0.9914497
OS 2.6105118 0.9879134
OS 2.6069755 0.9826209
OS 2.6057337 0.976378
OS 2.6069755 0.9701351
OS 2.6105118 0.9648426
OS 2.6158043 0.9613063
OS 2.6220472 0.9600645
OS 2.6282901 0.9613063
OS 2.6335825 0.9648426
OS 2.638071 0.9648426
OS 2.6433634 0.9613063
OS 2.6496063 0.9600645
OS 2.6558492 0.9613063
OS 2.6611417 0.9648426
OS 2.6623476 0.9666474
OS 2.6683611 0.9666474
OS 2.669567 0.9648426
OS 2.6748595 0.9613063
OS 2.6811024 0.9600645
OS 2.6873453 0.9613063
OS 2.6926377 0.9648426
OS 2.6971261 0.9648426
OS 2.7024185 0.9613063
OS 2.7086614 0.9600645
OS 2.7149043 0.9613063
OS 2.7201968 0.9648426
OS 2.7214027 0.9666474
OS 2.7274162 0.9666474
OS 2.7286221 0.9648426
OS 2.7339146 0.9613063
OS 2.7401575 0.9600645
OS 2.7464004 0.9613063
OS 2.7516928 0.9648426
OS 2.7561812 0.9648426
OS 2.7614736 0.9613063
OS 2.7677165 0.9600645
OS 2.7739594 0.9613063
OS 2.7792519 0.9648426
OS 2.7804578 0.9666474
OS 2.7864713 0.9666474
OS 2.7876772 0.9648426
OS 2.7929697 0.9613063
OS 2.7992126 0.9600645
OS 2.8054555 0.9613063
OS 2.8107479 0.9648426
OS 2.8152364 0.9648426
OS 2.8205288 0.9613063
OS 2.8267717 0.9600645
OS 2.8330146 0.9613063
OS 2.8383071 0.9648426
OS 2.8418434 0.9701351
OS 2.8430852 0.976378
OS 2.8418434 0.9826209
OS 2.8383071 0.9879134
OS 2.8330146 0.9914497
OS 2.8267717 0.9926915
OE
OB 4.3662677 1.0459921 H
OS 4.2892441 1.0459921
OS 4.2892441 0.9689685
OS 4.3662677 0.9689685
OS 4.3662677 1.0459921
OE
OB 5.3277559 1.0463244 H
OS 5.3177023 1.0450008
OS 5.3083338 1.0411203
OS 5.300289 1.0349472
OS 5.2941159 1.0269023
OS 5.2902354 1.0175339
OS 5.2889118 1.0074803
OS 5.2902354 0.9974267
OS 5.2941159 0.9880583
OS 5.300289 0.9800134
OS 5.3083338 0.9738403
OS 5.3177023 0.9699598
OS 5.3277559 0.9686362
OS 5.3378095 0.9699598
OS 5.347178 0.9738403
OS 5.3552228 0.9800134
OS 5.3613959 0.9880583
OS 5.3652764 0.9974267
OS 5.3666 1.0074803
OS 5.3652764 1.0175339
OS 5.3613959 1.0269023
OS 5.3552228 1.0349472
OS 5.347178 1.0411203
OS 5.3378095 1.0450008
OS 5.3277559 1.0463244
OE
OB 5.1277559 1.0463244 H
OS 5.1177023 1.0450008
OS 5.1083338 1.0411203
OS 5.100289 1.0349472
OS 5.0941159 1.0269023
OS 5.0902354 1.0175339
OS 5.0889118 1.0074803
OS 5.0902354 0.9974267
OS 5.0941159 0.9880583
OS 5.100289 0.9800134
OS 5.1083338 0.9738403
OS 5.1177023 0.9699598
OS 5.1277559 0.9686362
OS 5.1378095 0.9699598
OS 5.147178 0.9738403
OS 5.1552228 0.9800134
OS 5.1613959 0.9880583
OS 5.1652764 0.9974267
OS 5.1666 1.0074803
OS 5.1652764 1.0175339
OS 5.1613959 1.0269023
OS 5.1552228 1.0349472
OS 5.147178 1.0411203
OS 5.1378095 1.0450008
OS 5.1277559 1.0463244
OE
OB 4.9277559 1.0463244 H
OS 4.9177023 1.0450008
OS 4.9083338 1.0411203
OS 4.900289 1.0349472
OS 4.8941159 1.0269023
OS 4.8902354 1.0175339
OS 4.8889118 1.0074803
OS 4.8902354 0.9974267
OS 4.8941159 0.9880583
OS 4.900289 0.9800134
OS 4.9083338 0.9738403
OS 4.9177023 0.9699598
OS 4.9277559 0.9686362
OS 4.9378095 0.9699598
OS 4.947178 0.9738403
OS 4.9552228 0.9800134
OS 4.9613959 0.9880583
OS 4.9652764 0.9974267
OS 4.9666 1.0074803
OS 4.9652764 1.0175339
OS 4.9613959 1.0269023
OS 4.9552228 1.0349472
OS 4.947178 1.0411203
OS 4.9378095 1.0450008
OS 4.9277559 1.0463244
OE
OB 2.9905425 0.9777919 H
OS 2.9831954 0.9763305
OS 2.9769668 0.9721687
OS 2.972805 0.9659401
OS 2.9713436 0.958593
OS 2.972805 0.9512459
OS 2.9769668 0.9450173
OS 2.9831954 0.9408555
OS 2.9905425 0.9393941
OS 2.9978896 0.9408555
OS 3.0041182 0.9450173
OS 3.00828 0.9512459
OS 3.0097414 0.958593
OS 3.00828 0.9659401
OS 3.0041182 0.9721687
OS 2.9978896 0.9763305
OS 2.9905425 0.9777919
OE
OB 2.2031425 0.9777919 H
OS 2.1957954 0.9763305
OS 2.1895668 0.9721687
OS 2.185405 0.9659401
OS 2.1839436 0.958593
OS 2.185405 0.9512459
OS 2.1895668 0.9450173
OS 2.1957954 0.9408555
OS 2.2031425 0.9393941
OS 2.2104896 0.9408555
OS 2.2167182 0.9450173
OS 2.22088 0.9512459
OS 2.2223414 0.958593
OS 2.22088 0.9659401
OS 2.2167182 0.9721687
OS 2.2104896 0.9763305
OS 2.2031425 0.9777919
OE
OB 2.4788425 0.9533765 H
OS 2.4725996 0.9521347
OS 2.4673071 0.9485984
OS 2.4637708 0.9433059
OS 2.462529 0.937063
OS 2.4637708 0.9308201
OS 2.4673071 0.9255276
OS 2.4725996 0.9219913
OS 2.4788425 0.9207495
OS 2.4850854 0.9219913
OS 2.4903779 0.9255276
OS 2.4939142 0.9308201
OS 2.495156 0.937063
OS 2.4939142 0.9433059
OS 2.4903779 0.9485984
OS 2.4850854 0.9521347
OS 2.4788425 0.9533765
OE
OB 1.0048425 0.9223765 H
OS 0.9985996 0.9211347
OS 0.9933071 0.9175984
OS 0.9897708 0.9123059
OS 0.988529 0.906063
OS 0.9897708 0.8998201
OS 0.9933071 0.8945276
OS 0.9985996 0.8909913
OS 1.0048425 0.8897495
OS 1.0110854 0.8909913
OS 1.0163779 0.8945276
OS 1.0199142 0.8998201
OS 1.021156 0.906063
OS 1.0199142 0.9123059
OS 1.0163779 0.9175984
OS 1.0110854 0.9211347
OS 1.0048425 0.9223765
OE
OB 3.6179425 0.9836725 H
OS 3.6047974 0.9823778
OS 3.5921575 0.9785435
OS 3.5805085 0.972317
OS 3.570298 0.9639375
OS 3.5619185 0.953727
OS 3.555692 0.942078
OS 3.5518577 0.9294381
OS 3.550563 0.916293
OS 3.5518577 0.9031479
OS 3.555692 0.890508
OS 3.5619185 0.878859
OS 3.570298 0.8686485
OS 3.5805085 0.860269
OS 3.5921575 0.8540425
OS 3.6047974 0.8502082
OS 3.6179425 0.8489135
OS 3.6310876 0.8502082
OS 3.6437275 0.8540425
OS 3.6553765 0.860269
OS 3.665587 0.8686485
OS 3.6739665 0.878859
OS 3.680193 0.890508
OS 3.6840273 0.9031479
OS 3.685322 0.916293
OS 3.6840273 0.9294381
OS 3.680193 0.942078
OS 3.6739665 0.953727
OS 3.665587 0.9639375
OS 3.6553765 0.972317
OS 3.6437275 0.9785435
OS 3.6310876 0.9823778
OS 3.6179425 0.9836725
OE
OB 1.6529425 0.9836725 H
OS 1.6397974 0.9823778
OS 1.6271575 0.9785435
OS 1.6155085 0.972317
OS 1.605298 0.9639375
OS 1.5969185 0.953727
OS 1.590692 0.942078
OS 1.5868577 0.9294381
OS 1.585563 0.916293
OS 1.5868577 0.9031479
OS 1.590692 0.890508
OS 1.5969185 0.878859
OS 1.605298 0.8686485
OS 1.6155085 0.860269
OS 1.6271575 0.8540425
OS 1.6397974 0.8502082
OS 1.6529425 0.8489135
OS 1.6660876 0.8502082
OS 1.6787275 0.8540425
OS 1.6903765 0.860269
OS 1.700587 0.8686485
OS 1.7089665 0.878859
OS 1.715193 0.890508
OS 1.7190273 0.9031479
OS 1.720322 0.916293
OS 1.7190273 0.9294381
OS 1.715193 0.942078
OS 1.7089665 0.953727
OS 1.700587 0.9639375
OS 1.6903765 0.972317
OS 1.6787275 0.9785435
OS 1.6660876 0.9823778
OS 1.6529425 0.9836725
OE
OB 5.5781524 0.9365112 H
OS 5.5662745 0.9349474
OS 5.5552061 0.9303628
OS 5.5457014 0.9230696
OS 5.5384082 0.9135649
OS 5.5338236 0.9024965
OS 5.5322598 0.8906186
OS 5.5338236 0.8787407
OS 5.5384082 0.8676723
OS 5.5457014 0.8581676
OS 5.5552061 0.8508744
OS 5.5662745 0.8462898
OS 5.5781524 0.844726
OS 5.5900303 0.8462898
OS 5.6010987 0.8508744
OS 5.6106034 0.8581676
OS 5.6178966 0.8676723
OS 5.6224812 0.8787407
OS 5.624045 0.8906186
OS 5.6224812 0.9024965
OS 5.6178966 0.9135649
OS 5.6106034 0.9230696
OS 5.6010987 0.9303628
OS 5.5900303 0.9349474
OS 5.5781524 0.9365112
OE
OB 3.9797272 0.9365112 H
OS 3.9678493 0.9349474
OS 3.9567809 0.9303628
OS 3.9472762 0.9230696
OS 3.939983 0.9135649
OS 3.9353984 0.9024965
OS 3.9338346 0.8906186
OS 3.9353984 0.8787407
OS 3.939983 0.8676723
OS 3.9472762 0.8581676
OS 3.9567809 0.8508744
OS 3.9678493 0.8462898
OS 3.9797272 0.844726
OS 3.9916051 0.8462898
OS 4.0026735 0.8508744
OS 4.0121782 0.8581676
OS 4.0194714 0.8676723
OS 4.024056 0.8787407
OS 4.0256198 0.8906186
OS 4.024056 0.9024965
OS 4.0194714 0.9135649
OS 4.0121782 0.9230696
OS 4.0026735 0.9303628
OS 3.9916051 0.9349474
OS 3.9797272 0.9365112
OE
OB 0.1998425 0.9703727 H
OS 0.1872963 0.969137
OS 0.1752322 0.9654774
OS 0.1641139 0.9595346
OS 0.1543687 0.9515368
OS 0.1463709 0.9417916
OS 0.1404281 0.9306733
OS 0.1367685 0.9186092
OS 0.1355328 0.906063
OS 0.1367685 0.8935168
OS 0.1404281 0.8814527
OS 0.1463709 0.8703344
OS 0.1543687 0.8605892
OS 0.1641139 0.8525914
OS 0.1752322 0.8466486
OS 0.1872963 0.842989
OS 0.1998425 0.8417533
OS 0.2123887 0.842989
OS 0.2244528 0.8466486
OS 0.2355711 0.8525914
OS 0.2453163 0.8605892
OS 0.2533141 0.8703344
OS 0.2592569 0.8814527
OS 0.2629165 0.8935168
OS 0.2641522 0.906063
OS 0.2629165 0.9186092
OS 0.2592569 0.9306733
OS 0.2533141 0.9417916
OS 0.2453163 0.9515368
OS 0.2355711 0.9595346
OS 0.2244528 0.9654774
OS 0.2123887 0.969137
OS 0.1998425 0.9703727
OE
OB 2.7598425 0.8115891 H
OS 2.7535996 0.8103473
OS 2.7483072 0.806811
OS 2.7438188 0.806811
OS 2.7385264 0.8103473
OS 2.7322835 0.8115891
OS 2.7260406 0.8103473
OS 2.7207481 0.806811
OS 2.7172118 0.8015185
OS 2.71597 0.7952756
OS 2.7172118 0.7890327
OS 2.7207481 0.7837402
OS 2.7260406 0.7802039
OS 2.7322835 0.7789621
OS 2.7385264 0.7802039
OS 2.7438188 0.7837402
OS 2.7483072 0.7837402
OS 2.7535996 0.7802039
OS 2.7598425 0.7789621
OS 2.7660854 0.7802039
OS 2.7713779 0.7837402
OS 2.7749142 0.7890327
OS 2.776156 0.7952756
OS 2.7749142 0.8015185
OS 2.7713779 0.806811
OS 2.7660854 0.8103473
OS 2.7598425 0.8115891
OE
OB 2.6929134 0.8115891 H
OS 2.6866705 0.8103473
OS 2.6813781 0.806811
OS 2.6768896 0.806811
OS 2.6715972 0.8103473
OS 2.6653543 0.8115891
OS 2.6591114 0.8103473
OS 2.6538189 0.806811
OS 2.6502826 0.8015185
OS 2.6490408 0.7952756
OS 2.6502826 0.7890327
OS 2.6538189 0.7837402
OS 2.6591114 0.7802039
OS 2.6653543 0.7789621
OS 2.6715972 0.7802039
OS 2.6768896 0.7837402
OS 2.6813781 0.7837402
OS 2.6866705 0.7802039
OS 2.6929134 0.7789621
OS 2.6991563 0.7802039
OS 2.7044488 0.7837402
OS 2.7079851 0.7890327
OS 2.7092269 0.7952756
OS 2.7079851 0.8015185
OS 2.7044488 0.806811
OS 2.6991563 0.8103473
OS 2.6929134 0.8115891
OE
OB 2.6259843 0.8115891 H
OS 2.6197414 0.8103473
OS 2.614449 0.806811
OS 2.6099605 0.806811
OS 2.6046681 0.8103473
OS 2.5984252 0.8115891
OS 2.5921823 0.8103473
OS 2.5868898 0.806811
OS 2.5833535 0.8015185
OS 2.5821117 0.7952756
OS 2.5833535 0.7890327
OS 2.5868898 0.7837402
OS 2.5921823 0.7802039
OS 2.5984252 0.7789621
OS 2.6046681 0.7802039
OS 2.6099605 0.7837402
OS 2.614449 0.7837402
OS 2.6197414 0.7802039
OS 2.6259843 0.7789621
OS 2.6322272 0.7802039
OS 2.6375197 0.7837402
OS 2.641056 0.7890327
OS 2.6422978 0.7952756
OS 2.641056 0.8015185
OS 2.6375197 0.806811
OS 2.6322272 0.8103473
OS 2.6259843 0.8115891
OE
OB 2.8937008 0.8115891 H
OS 2.8874579 0.8103473
OS 2.8821654 0.806811
OS 2.8809595 0.8050062
OS 2.874946 0.8050062
OS 2.8737401 0.806811
OS 2.8684476 0.8103473
OS 2.8622047 0.8115891
OS 2.8559618 0.8103473
OS 2.8506693 0.806811
OS 2.847133 0.8015185
OS 2.8470372 0.8010368
OS 2.8419392 0.8010368
OS 2.8418434 0.8015185
OS 2.8383071 0.806811
OS 2.8330146 0.8103473
OS 2.8267717 0.8115891
OS 2.8205288 0.8103473
OS 2.8152364 0.806811
OS 2.8107479 0.806811
OS 2.8054555 0.8103473
OS 2.7992126 0.8115891
OS 2.7929697 0.8103473
OS 2.7876772 0.806811
OS 2.7841409 0.8015185
OS 2.7828991 0.7952756
OS 2.7841409 0.7890327
OS 2.7876772 0.7837402
OS 2.7929697 0.7802039
OS 2.7992126 0.7789621
OS 2.8054555 0.7802039
OS 2.8107479 0.7837402
OS 2.8152364 0.7837402
OS 2.8205288 0.7802039
OS 2.8267717 0.7789621
OS 2.8330146 0.7802039
OS 2.8383071 0.7837402
OS 2.8418434 0.7890327
OS 2.8419392 0.7895144
OS 2.8470372 0.7895144
OS 2.847133 0.7890327
OS 2.8506693 0.7837402
OS 2.8559618 0.7802039
OS 2.8622047 0.7789621
OS 2.8684476 0.7802039
OS 2.8737401 0.7837402
OS 2.874946 0.785545
OS 2.8809595 0.785545
OS 2.8821654 0.7837402
OS 2.8874579 0.7802039
OS 2.8937008 0.7789621
OS 2.8999437 0.7802039
OS 2.9052362 0.7837402
OS 2.9087725 0.7890327
OS 2.9100143 0.7952756
OS 2.9087725 0.8015185
OS 2.9052362 0.806811
OS 2.8999437 0.8103473
OS 2.8937008 0.8115891
OE
OB 0.9901575 0.7033214 H
OS 0.9839146 0.7020796
OS 0.9786221 0.6985433
OS 0.9750858 0.6932508
OS 0.973844 0.6870079
OS 0.9750858 0.680765
OS 0.9786221 0.6754725
OS 0.9839146 0.6719362
OS 0.9901575 0.6706944
OS 0.9964004 0.6719362
OS 1.0016929 0.6754725
OS 1.0052292 0.680765
OS 1.006471 0.6870079
OS 1.0052292 0.6932508
OS 1.0016929 0.6985433
OS 0.9964004 0.7020796
OS 0.9901575 0.7033214
OE
OB 2.4698827 0.4273018 H
OS 2.4636398 0.42606
OS 2.4583473 0.4225237
OS 2.454811 0.4172312
OS 2.4535692 0.4109883
OS 2.454811 0.4047454
OS 2.4583473 0.3994529
OS 2.4636398 0.3959166
OS 2.4698827 0.3946748
OS 2.4761256 0.3959166
OS 2.4814181 0.3994529
OS 2.4849544 0.4047454
OS 2.4861962 0.4109883
OS 2.4849544 0.4172312
OS 2.4814181 0.4225237
OS 2.4761256 0.42606
OS 2.4698827 0.4273018
OE
OB 2.980457 0.4254674 H
OS 2.9742141 0.4242256
OS 2.9689216 0.4206893
OS 2.9653853 0.4153968
OS 2.9641435 0.4091539
OS 2.9653853 0.402911
OS 2.9689216 0.3976185
OS 2.9742141 0.3940822
OS 2.980457 0.3928404
OS 2.9866999 0.3940822
OS 2.9919924 0.3976185
OS 2.9955287 0.402911
OS 2.9967705 0.4091539
OS 2.9955287 0.4153968
OS 2.9919924 0.4206893
OS 2.9866999 0.4242256
OS 2.980457 0.4254674
OE
OB 3.019685 0.4218253 H
OS 3.0134421 0.4205835
OS 3.0081496 0.4170472
OS 3.0046133 0.4117547
OS 3.0033715 0.4055118
OS 3.0046133 0.3992689
OS 3.0081496 0.3939764
OS 3.0134421 0.3904401
OS 3.019685 0.3891983
OS 3.0259279 0.3904401
OS 3.0312204 0.3939764
OS 3.0347567 0.3992689
OS 3.0359985 0.4055118
OS 3.0347567 0.4117547
OS 3.0312204 0.4170472
OS 3.0259279 0.4205835
OS 3.019685 0.4218253
OE
OB 2.8219832 0.4241654 H
OS 2.8157403 0.4229236
OS 2.8104478 0.4193873
OS 2.8069115 0.4140948
OS 2.8056697 0.4078519
OS 2.8069115 0.401609
OS 2.8104478 0.3963165
OS 2.8157403 0.3927802
OS 2.8219832 0.3915384
OS 2.8282261 0.3927802
OS 2.8335186 0.3963165
OS 2.8345973 0.3979309
OS 2.8352825 0.3981275
OS 2.8403819 0.3975883
OS 2.8427953 0.3939764
OS 2.8480878 0.3904401
OS 2.8543307 0.3891983
OS 2.8605736 0.3904401
OS 2.8658661 0.3939764
OS 2.8694024 0.3992689
OS 2.8706442 0.4055118
OS 2.8694024 0.4117547
OS 2.8658661 0.4170472
OS 2.8605736 0.4205835
OS 2.8543307 0.4218253
OS 2.8480878 0.4205835
OS 2.8427953 0.4170472
OS 2.8417166 0.4154328
OS 2.8410314 0.4152362
OS 2.835932 0.4157754
OS 2.8335186 0.4193873
OS 2.8282261 0.4229236
OS 2.8219832 0.4241654
OE
OB 2.7047244 0.4218253 H
OS 2.6984815 0.4205835
OS 2.693189 0.4170472
OS 2.6896527 0.4117547
OS 2.6884109 0.4055118
OS 2.6896527 0.3992689
OS 2.693189 0.3939764
OS 2.6984815 0.3904401
OS 2.7047244 0.3891983
OS 2.7109673 0.3904401
OS 2.7162598 0.3939764
OS 2.7197961 0.3992689
OS 2.7210379 0.4055118
OS 2.7197961 0.4117547
OS 2.7162598 0.4170472
OS 2.7109673 0.4205835
OS 2.7047244 0.4218253
OE
OB 2.6653543 0.4218253 H
OS 2.6591114 0.4205835
OS 2.6538189 0.4170472
OS 2.6502826 0.4117547
OS 2.6490408 0.4055118
OS 2.6502826 0.3992689
OS 2.6538189 0.3939764
OS 2.6591114 0.3904401
OS 2.6653543 0.3891983
OS 2.6715972 0.3904401
OS 2.6768897 0.3939764
OS 2.680426 0.3992689
OS 2.6816678 0.4055118
OS 2.680426 0.4117547
OS 2.6768897 0.4170472
OS 2.6715972 0.4205835
OS 2.6653543 0.4218253
OE
OB 2.511811 0.4218253 H
OS 2.5055681 0.4205835
OS 2.5002756 0.4170472
OS 2.4967393 0.4117547
OS 2.4954975 0.4055118
OS 2.4967393 0.3992689
OS 2.5002756 0.3939764
OS 2.5055681 0.3904401
OS 2.511811 0.3891983
OS 2.5180539 0.3904401
OS 2.5233464 0.3939764
OS 2.5268827 0.3992689
OS 2.5281245 0.4055118
OS 2.5268827 0.4117547
OS 2.5233464 0.4170472
OS 2.5180539 0.4205835
OS 2.511811 0.4218253
OE
OB 2.3897638 0.4218253 H
OS 2.3835209 0.4205835
OS 2.3782284 0.4170472
OS 2.3746921 0.4117547
OS 2.3734503 0.4055118
OS 2.3746921 0.3992689
OS 2.3782284 0.3939764
OS 2.3835209 0.3904401
OS 2.3897638 0.3891983
OS 2.3960067 0.3904401
OS 2.4012992 0.3939764
OS 2.4048355 0.3992689
OS 2.4060773 0.4055118
OS 2.4048355 0.4117547
OS 2.4012992 0.4170472
OS 2.3960067 0.4205835
OS 2.3897638 0.4218253
OE
OB 2.3503937 0.4218253 H
OS 2.3441508 0.4205835
OS 2.3388583 0.4170472
OS 2.335322 0.4117547
OS 2.3340802 0.4055118
OS 2.335322 0.3992689
OS 2.3388583 0.3939764
OS 2.3441508 0.3904401
OS 2.3503937 0.3891983
OS 2.3566366 0.3904401
OS 2.3619291 0.3939764
OS 2.3654654 0.3992689
OS 2.3667072 0.4055118
OS 2.3654654 0.4117547
OS 2.3619291 0.4170472
OS 2.3566366 0.4205835
OS 2.3503937 0.4218253
OE
OB 1.8720472 0.3037151 H
OS 1.8658043 0.3024733
OS 1.8622047 0.3000681
OS 1.8586051 0.3024733
OS 1.8523622 0.3037151
OS 1.8461193 0.3024733
OS 1.8425197 0.3000681
OS 1.83892 0.3024733
OS 1.8326771 0.3037151
OS 1.8264342 0.3024733
OS 1.8211417 0.298937
OS 1.8176054 0.2936445
OS 1.8163636 0.2874016
OS 1.8176054 0.2811587
OS 1.8211417 0.2758662
OS 1.8229465 0.2746603
OS 1.8229465 0.2686468
OS 1.8211417 0.2674409
OS 1.8176054 0.2621484
OS 1.8163636 0.2559055
OS 1.8176054 0.2496626
OS 1.8211417 0.2443701
OS 1.8264342 0.2408338
OS 1.8326771 0.239592
OS 1.83892 0.2408338
OS 1.8425197 0.243239
OS 1.8461193 0.2408338
OS 1.8523622 0.239592
OS 1.8586051 0.2408338
OS 1.8622047 0.243239
OS 1.8658043 0.2408338
OS 1.8720472 0.239592
OS 1.8782901 0.2408338
OS 1.8835826 0.2443701
OS 1.8871189 0.2496626
OS 1.8883607 0.2559055
OS 1.8871189 0.2621484
OS 1.8835826 0.2674409
OS 1.8817778 0.2686468
OS 1.8817778 0.2746603
OS 1.8835826 0.2758662
OS 1.8871189 0.2811587
OS 1.8883607 0.2874016
OS 1.8871189 0.2936445
OS 1.8835826 0.298937
OS 1.8782901 0.3024733
OS 1.8720472 0.3037151
OE
OB 0.2854331 0.4390502 H
OS 0.2715934 0.4376871
OS 0.2582855 0.4336502
OS 0.2460209 0.4270947
OS 0.2352709 0.4182724
OS 0.2264486 0.4075224
OS 0.2198931 0.3952578
OS 0.2158562 0.3819499
OS 0.2144931 0.3681102
OS 0.2158562 0.3542705
OS 0.2198931 0.3409626
OS 0.2264486 0.328698
OS 0.2352709 0.317948
OS 0.2460209 0.3091257
OS 0.2582855 0.3025702
OS 0.2715934 0.2985333
OS 0.2854331 0.2971702
OS 0.2992728 0.2985333
OS 0.3125807 0.3025702
OS 0.3248453 0.3091257
OS 0.3355953 0.317948
OS 0.3444176 0.328698
OS 0.3509731 0.3409626
OS 0.35501 0.3542705
OS 0.3563731 0.3681102
OS 0.35501 0.3819499
OS 0.3509731 0.3952578
OS 0.3444176 0.4075224
OS 0.3355953 0.4182724
OS 0.3248453 0.4270947
OS 0.3125807 0.4336502
OS 0.2992728 0.4376871
OS 0.2854331 0.4390502
OE
OB 2.1122047 0.3037151 H
OS 2.1059618 0.3024733
OS 2.1006693 0.298937
OS 2.097133 0.2936445
OS 2.0970371 0.2931626
OS 2.0919392 0.2931626
OS 2.0918433 0.2936445
OS 2.088307 0.298937
OS 2.0830145 0.3024733
OS 2.0767716 0.3037151
OS 2.0705287 0.3024733
OS 2.0652362 0.298937
OS 2.0616999 0.2936445
OS 2.0604581 0.2874016
OS 2.0616999 0.2811587
OS 2.0652362 0.2758662
OS 2.067041 0.2746603
OS 2.067041 0.2686468
OS 2.0652362 0.2674409
OS 2.0616999 0.2621484
OS 2.0604581 0.2559055
OS 2.0616999 0.2496626
OS 2.0652362 0.2443701
OS 2.0705287 0.2408338
OS 2.0767716 0.239592
OS 2.0830145 0.2408338
OS 2.088307 0.2443701
OS 2.0918433 0.2496626
OS 2.0919392 0.2501445
OS 2.0970371 0.2501445
OS 2.097133 0.2496626
OS 2.1006693 0.2443701
OS 2.1059618 0.2408338
OS 2.1122047 0.239592
OS 2.1184476 0.2408338
OS 2.1237401 0.2443701
OS 2.1272764 0.2496626
OS 2.1285182 0.2559055
OS 2.1272764 0.2621484
OS 2.1237401 0.2674409
OS 2.1219353 0.2686468
OS 2.1219353 0.2746603
OS 2.1237401 0.2758662
OS 2.1272764 0.2811587
OS 2.1285182 0.2874016
OS 2.1272764 0.2936445
OS 2.1237401 0.298937
OS 2.1184476 0.3024733
OS 2.1122047 0.3037151
OE
OB 2.6102362 0.2958411 H
OS 2.6039933 0.2945993
OS 2.5987008 0.291063
OS 2.5974949 0.2892583
OS 2.5914815 0.2892583
OS 2.5902756 0.291063
OS 2.5849831 0.2945993
OS 2.5787402 0.2958411
OS 2.5724973 0.2945993
OS 2.5672048 0.291063
OS 2.5636685 0.2857705
OS 2.5624267 0.2795276
OS 2.5636685 0.2732847
OS 2.5672048 0.2679922
OS 2.5724973 0.2644559
OS 2.5787402 0.2632141
OS 2.5849831 0.2644559
OS 2.5902756 0.2679922
OS 2.5914815 0.2697969
OS 2.5974949 0.2697969
OS 2.5987008 0.2679922
OS 2.6039933 0.2644559
OS 2.6102362 0.2632141
OS 2.6164791 0.2644559
OS 2.6217716 0.2679922
OS 2.6253079 0.2732847
OS 2.6265497 0.2795276
OS 2.6253079 0.2857705
OS 2.6217716 0.291063
OS 2.6164791 0.2945993
OS 2.6102362 0.2958411
OE
OB 2.4448819 0.2958411 H
OS 2.438639 0.2945993
OS 2.4333465 0.291063
OS 2.4321406 0.2892582
OS 2.4261271 0.2892582
OS 2.4249212 0.291063
OS 2.4196287 0.2945993
OS 2.4133858 0.2958411
OS 2.4071429 0.2945993
OS 2.4018504 0.291063
OS 2.3983141 0.2857705
OS 2.3970723 0.2795276
OS 2.3983141 0.2732847
OS 2.4018504 0.2679922
OS 2.4071429 0.2644559
OS 2.4133858 0.2632141
OS 2.4196287 0.2644559
OS 2.4249212 0.2679922
OS 2.4261271 0.269797
OS 2.4321406 0.269797
OS 2.4333465 0.2679922
OS 2.438639 0.2644559
OS 2.4448819 0.2632141
OS 2.4511248 0.2644559
OS 2.4564173 0.2679922
OS 2.4599536 0.2732847
OS 2.4611954 0.2795276
OS 2.4599536 0.2857705
OS 2.4564173 0.291063
OS 2.4511248 0.2945993
OS 2.4448819 0.2958411
OE
OB 2.9370079 0.2958411 H
OS 2.930765 0.2945993
OS 2.9254725 0.291063
OS 2.9242523 0.2892367
OS 2.9182388 0.2892367
OS 2.91703 0.2910458
OS 2.9117375 0.2945821
OS 2.9054946 0.2958239
OS 2.8992517 0.2945821
OS 2.8939592 0.2910458
OS 2.8904229 0.2857533
OS 2.8891811 0.2795104
OS 2.8904229 0.2732675
OS 2.8939592 0.267975
OS 2.8992517 0.2644387
OS 2.9054946 0.2631969
OS 2.9117375 0.2644387
OS 2.91703 0.267975
OS 2.9182502 0.2698013
OS 2.9242637 0.2698013
OS 2.9254725 0.2679922
OS 2.930765 0.2644559
OS 2.9370079 0.2632141
OS 2.9432508 0.2644559
OS 2.9485433 0.2679922
OS 2.9520796 0.2732847
OS 2.9533214 0.2795276
OS 2.9520796 0.2857705
OS 2.9485433 0.291063
OS 2.9432508 0.2945993
OS 2.9370079 0.2958411
OE
OB 2.74882 0.2986255 H
OS 2.7425771 0.2973837
OS 2.7372846 0.2938474
OS 2.7337483 0.2885549
OS 2.7325065 0.282312
OS 2.7337483 0.2760691
OS 2.7372846 0.2707766
OS 2.7425771 0.2672403
OS 2.74882 0.2659985
OS 2.7550629 0.2672403
OS 2.7603553 0.2707766
OS 2.7662503 0.2705991
OS 2.7679922 0.2679922
OS 2.7732847 0.2644559
OS 2.7795276 0.2632141
OS 2.7857705 0.2644559
OS 2.791063 0.2679922
OS 2.7945993 0.2732847
OS 2.7958411 0.2795276
OS 2.7945993 0.2857705
OS 2.791063 0.291063
OS 2.7857705 0.2945993
OS 2.7795276 0.2958411
OS 2.7732847 0.2945993
OS 2.7679923 0.291063
OS 2.7620973 0.2912405
OS 2.7603554 0.2938474
OS 2.7550629 0.2973837
OS 2.74882 0.2986255
OE
OB 2.1515748 0.3037151 H
OS 2.1453319 0.3024733
OS 2.1400394 0.298937
OS 2.1365031 0.2936445
OS 2.1352613 0.2874016
OS 2.1365031 0.2811587
OS 2.1400394 0.2758662
OS 2.1418442 0.2746603
OS 2.1418442 0.2686468
OS 2.1400394 0.2674409
OS 2.1365031 0.2621484
OS 2.1352613 0.2559055
OS 2.1365031 0.2496626
OS 2.1400394 0.2443701
OS 2.1453319 0.2408338
OS 2.1515748 0.239592
OS 2.1578177 0.2408338
OS 2.1631102 0.2443701
OS 2.1666465 0.2496626
OS 2.1678883 0.2559055
OS 2.1666465 0.2621484
OS 2.1631102 0.2674409
OS 2.1613054 0.2686468
OS 2.1613054 0.2746603
OS 2.1631102 0.2758662
OS 2.1666465 0.2811587
OS 2.1678883 0.2874016
OS 2.1666465 0.2936445
OS 2.1631102 0.298937
OS 2.1578177 0.3024733
OS 2.1515748 0.3037151
OE
SE
P 0.149508 2.830047 9 P 0 0 ;0=7,1=1
P 0.149508 3.853669 9 P 0 0 ;0=7,1=1
P 0.6538425 1.551063 10 P 0 0 ;0=8,1=1
P 0.6539669 2.5938902 10 P 0 0 ;0=8,1=1
P 0.6548425 0.790063 10 P 0 0 ;0=8,1=1
P 0.6548425 1.314063 10 P 0 0 ;0=8,1=1
P 0.6548425 1.839063 10 P 0 0 ;0=8,1=1
P 0.6548425 2.073063 10 P 0 0 ;0=8,1=1
P 0.6548425 2.365063 10 P 0 0 ;0=8,1=1
P 0.6558425 1.028063 10 P 0 0 ;0=8,1=1
P 0.9370078 2.3179133 10 P 0 0 ;0=8,1=1
P 1.2428425 1.472063 10 P 0 0 ;0=8,1=1
P 1.2488425 2.000063 10 P 0 0 ;0=8,1=1
P 1.2568425 0.942063 10 P 0 0 ;0=8,1=1
P 1.2618425 2.482063 10 P 0 0 ;0=8,1=1
P 1.6708425 1.595063 10 P 0 0 ;0=8,1=1
P 1.6708425 1.694063 10 P 0 0 ;0=8,1=1
P 1.6718425 1.399063 10 P 0 0 ;0=8,1=1
P 1.6718425 1.497063 10 P 0 0 ;0=8,1=1
P 1.6718425 1.792063 10 P 0 0 ;0=8,1=1
P 1.6748425 1.989063 10 P 0 0 ;0=8,1=1
P 1.6758425 1.891063 10 P 0 0 ;0=8,1=1
P 1.6918425 4.079063 10 P 0 0 ;0=8,1=1
P 1.7148425 1.595063 10 P 0 0 ;0=8,1=1
P 1.7168425 1.399063 10 P 0 0 ;0=8,1=1
P 1.7188425 1.497063 10 P 0 0 ;0=8,1=1
P 1.7188425 1.792063 10 P 0 0 ;0=8,1=1
P 1.7218425 1.694063 10 P 0 0 ;0=8,1=1
P 1.7218425 1.890063 10 P 0 0 ;0=8,1=1
P 1.7218425 1.989063 10 P 0 0 ;0=8,1=1
P 1.7268425 4.329374 10 P 0 0 ;0=8,1=1
P 1.7498425 4.110063 10 P 0 0 ;0=8,1=1
P 1.7888425 4.329374 10 P 0 0 ;0=8,1=1
P 1.9161425 0.244763 10 P 0 0 ;0=8,1=1
P 2.0348425 0.246063 10 P 0 0 ;0=8,1=1
P 2.1398425 3.738063 10 P 0 0 ;0=8,1=1
P 2.2538425 2.279063 10 P 0 0 ;0=8,1=1
P 2.2588425 3.741063 10 P 0 0 ;0=8,1=1
P 2.2908425 4.217063 10 P 0 0 ;0=8,1=1
P 2.3098425 0.246063 10 P 0 0 ;0=8,1=1
P 2.3114125 1.0900094 10 P 0 0 ;0=8,1=1
P 2.3118425 0.934063 10 P 0 0 ;0=8,1=1
P 2.3215354 2.586063 10 P 0 0 ;0=8,1=1
P 2.3215354 3.361063 10 P 0 0 ;0=8,1=1
P 2.4048425 2.412063 10 P 0 0 ;0=8,1=1
P 2.4098325 0.932053 10 P 0 0 ;0=8,1=1
P 2.4098325 1.088053 10 P 0 0 ;0=8,1=1
P 2.4098425 2.579063 10 P 0 0 ;0=8,1=1
P 2.4138425 3.295063 10 P 0 0 ;0=8,1=1
P 2.4192759 2.7886295 10 P 0 0 ;0=8,1=1
P 2.4470546 0.2425914 10 P 0 0 ;0=8,1=1
P 2.4738425 2.980063 10 P 0 0 ;0=8,1=1
P 2.4758425 2.456063 10 P 0 0 ;0=8,1=1
P 2.4888425 2.413063 10 P 0 0 ;0=8,1=1
P 2.5082625 0.931483 10 P 0 0 ;0=8,1=1
P 2.5088425 1.090063 10 P 0 0 ;0=8,1=1
P 2.531398 2.830047 9 P 0 0 ;0=7,1=1
P 2.531398 3.853669 9 P 0 0 ;0=7,1=1
P 2.5460625 0.244843 10 P 0 0 ;0=8,1=1
P 2.5818425 2.308063 10 P 0 0 ;0=8,1=1
P 2.5868425 2.569063 10 P 0 0 ;0=8,1=1
P 2.6066825 0.931903 10 P 0 0 ;0=8,1=1
P 2.6068425 1.091063 10 P 0 0 ;0=8,1=1
P 2.6318425 2.876063 10 P 0 0 ;0=8,1=1
P 2.636874 0.2479055 10 P 0 0 ;0=8,1=1
P 2.6658425 1.092063 10 P 0 0 ;0=8,1=1
P 2.6748425 3.501063 10 P 0 0 ;0=8,1=1
P 2.6858425 2.311063 10 P 0 0 ;0=8,1=1
P 2.6858425 2.568063 10 P 0 0 ;0=8,1=1
P 2.7244825 1.093063 10 P 0 0 ;0=8,1=1
P 2.7248425 3.521063 10 P 0 0 ;0=8,1=1
P 2.7248425 3.729063 10 P 0 0 ;0=8,1=1
P 2.7838425 2.429063 10 P 0 0 ;0=8,1=1
P 2.7838425 2.568063 10 P 0 0 ;0=8,1=1
P 2.7841625 1.094063 10 P 0 0 ;0=8,1=1
P 2.7999951 0.2519685 10 P 0 0 ;0=8,1=1
P 2.8428425 1.095063 10 P 0 0 ;0=8,1=1
P 2.8608425 3.787063 10 P 0 0 ;0=8,1=1
P 2.8718425 2.297063 10 P 0 0 ;0=8,1=1
P 2.8782843 0.2495967 10 P 0 0 ;0=8,1=1
P 2.8818425 2.566063 10 P 0 0 ;0=8,1=1
P 2.8888425 4.221063 10 P 0 0 ;0=8,1=1
P 2.9018425 1.095063 10 P 0 0 ;0=8,1=1
P 2.9338425 0.953063 10 P 0 0 ;0=8,1=1
P 2.9574751 0.2519685 10 P 0 0 ;0=8,1=1
P 3.0974409 0.2519685 10 P 0 0 ;0=8,1=1
P 3.1830708 3.1358268 10 P 0 0 ;0=8,1=1
P 3.2698425 3.788063 10 P 0 0 ;0=8,1=1
P 3.277559 2.9635827 10 P 0 0 ;0=8,1=1
P 3.3308425 3.301063 10 P 0 0 ;0=8,1=1
P 3.3708425 2.888063 10 P 0 0 ;0=8,1=1
P 3.3958425 4.222063 10 P 0 0 ;0=8,1=1
P 3.4068425 1.461063 10 P 0 0 ;0=8,1=1
P 3.4108425 1.7136509 10 P 0 0 ;0=8,1=1
P 3.4138425 1.573063 10 P 0 0 ;0=8,1=1
P 3.4144661 1.805063 10 P 0 0 ;0=8,1=1
P 3.5318425 3.660063 10 P 0 0 ;0=8,1=1
P 3.5498425 1.413063 10 P 0 0 ;0=8,1=1
P 3.5548425 1.841063 10 P 0 0 ;0=8,1=1
P 3.5548425 1.941063 10 P 0 0 ;0=8,1=1
P 3.5548425 1.991063 10 P 0 0 ;0=8,1=1
P 3.5908425 1.662063 10 P 0 0 ;0=8,1=1
P 3.5948425 1.514063 10 P 0 0 ;0=8,1=1
P 3.6038425 0.682063 10 P 0 0 ;0=8,1=1
P 3.6428425 0.636063 10 P 0 0 ;0=8,1=1
P 3.7178425 3.072063 10 P 0 0 ;0=8,1=1
P 3.7188425 1.713063 10 P 0 0 ;0=8,1=1
P 3.7198425 1.921063 10 P 0 0 ;0=8,1=1
P 3.7198425 1.996063 10 P 0 0 ;0=8,1=1
P 3.7328425 1.418063 10 P 0 0 ;0=8,1=1
P 3.7448425 3.342063 10 P 0 0 ;0=8,1=1
P 3.7778425 4.023063 10 P 0 0 ;0=8,1=1
P 3.8308425 3.762063 10 P 0 0 ;0=8,1=1
P 3.8808425 3.109063 10 P 0 0 ;0=8,1=1
P 3.9608425 2.724063 10 P 0 0 ;0=8,1=1
P 3.9688425 1.671063 10 P 0 0 ;0=8,1=1
P 3.9968425 1.711063 10 P 0 0 ;0=8,1=1
P 4.0398425 3.784063 10 P 0 0 ;0=8,1=1
P 4.0648425 2.722063 10 P 0 0 ;0=8,1=1
P 4.0688425 3.135063 10 P 0 0 ;0=8,1=1
P 4.0858425 3.892063 10 P 0 0 ;0=8,1=1
P 4.1148425 3.135063 10 P 0 0 ;0=8,1=1
P 4.1203866 3.5941508 10 P 0 0 ;0=8,1=1
P 4.1318425 1.686063 10 P 0 0 ;0=8,1=1
P 4.1528425 3.135063 10 P 0 0 ;0=8,1=1
P 4.1948425 3.884063 10 P 0 0 ;0=8,1=1
P 4.2088425 3.135063 10 P 0 0 ;0=8,1=1
P 4.2348425 2.725063 10 P 0 0 ;0=8,1=1
P 4.2728425 3.135063 10 P 0 0 ;0=8,1=1
P 4.3338425 3.135063 10 P 0 0 ;0=8,1=1
P 4.3398425 2.725063 10 P 0 0 ;0=8,1=1
P 4.3878425 4.206063 10 P 0 0 ;0=8,1=1
P 4.4318425 3.135063 10 P 0 0 ;0=8,1=1
P 4.4778425 3.135063 10 P 0 0 ;0=8,1=1
P 4.9108425 4.203063 10 P 0 0 ;0=8,1=1
P 5.6768425 3.546063 10 P 0 0 ;0=8,1=1
P 5.7338425 3.556063 10 P 0 0 ;0=8,1=1
P 6.0048425 2.434063 10 P 0 0 ;0=8,1=1
P 6.0488425 2.171063 10 P 0 0 ;0=8,1=1
P 6.253937 2.9094488 10 P 0 0 ;0=8,1=1
P 6.2748425 2.391063 10 P 0 0 ;0=8,1=1
P 6.3720472 2.9094488 10 P 0 0 ;0=8,1=1
P 6.3958425 2.111063 10 P 0 0 ;0=8,1=1
P 6.3968425 2.556063 10 P 0 0 ;0=8,1=1
P 6.3978425 2.501063 10 P 0 0 ;0=8,1=1
P 6.3978425 2.610063 10 P 0 0 ;0=8,1=1
P 6.3988425 2.453063 10 P 0 0 ;0=8,1=1
P 6.3988425 2.657063 10 P 0 0 ;0=8,1=1
P 6.4568425 3.009063 10 P 0 0 ;0=8,1=1
P 6.4768425 3.231063 10 P 0 0 ;0=8,1=1
P 6.5488425 1.531063 10 P 0 0 ;0=8,1=1
P 6.6018425 1.777063 10 P 0 0 ;0=8,1=1
P 6.6028425 1.612063 10 P 0 0 ;0=8,1=1
P 6.6028425 1.672063 10 P 0 0 ;0=8,1=1
P 6.6028425 1.722063 10 P 0 0 ;0=8,1=1
P 6.6078425 2.176063 10 P 0 0 ;0=8,1=1
P 6.6268425 3.032063 10 P 0 0 ;0=8,1=1
P 6.6288425 1.372063 10 P 0 0 ;0=8,1=1
P 6.6476378 3.1299213 10 P 0 0 ;0=8,1=1
P 6.6488425 3.341063 10 P 0 0 ;0=8,1=1
P 6.6858425 1.828063 10 P 0 0 ;0=8,1=1
P 6.6998425 1.881063 10 P 0 0 ;0=8,1=1
P 6.9498425 2.095063 10 P 0 0 ;0=8,1=1
P 6.9744094 1.9399606 10 P 0 0 ;0=8,1=1

### steps/pcb/layers/top/features
#Layer_Physical_Order=1
#Layer_Color=255
#
#Feature symbol names
#
$0 r8
$1 r5
$2 r20
$3 rect61.02x9.84
$4 rect66.93x53.15
$5 rect9.84x61.02
$6 rect53.15x66.93
$7 rect28x165
$8 rect28x126
$9 rect9.8425x10.8268
$10 rect10.8268x9.8425
$11 rect28.3465x39.3701
$12 rect39.3701x33.4646
$13 rect27.5591x35.4331
$14 rect82.874x44.0945
$15 rect35.4331x27.5591
$16 rect70.8661x9.8425
$17 rect165.3543x125.9843
$18 oval78.7402x23.622
$19 rect25.5906x41.3386
$20 rect39.3701x37.4016
$21 rect64.9606x51.1811
$22 rect17.7165x54.3307
$23 rect55.9055x61.0236
$24 rect70.8661x74.8031
$25 rect39.3701x74.8031
$26 rect19.685x90.5512
$27 rect78.7402x98.4252
$28 rect86.6142x41.3386
$29 rect41.3386x39.3701
$30 rect19.685x35.4331
$31 oval57.0866x17.7165
$32 rect77.5591x22.4409
$33 rect51.1811x74.8031
$34 rect39.3701x90.5512
$35 rect39.3701x70.8661
$36 rect53.1496x27.5591
$37 rect27.5591x45.2756
$38 rect41.3386x45.2756
$39 rect50x200
$40 rect57.0866x37.4016
$41 rect31.4961x66.9291
$42 rect9.8425x22.6378
$43 rect26.5748x9.8425
$44 rect38.5827x34.252
$45 rect212.5984x114.1732
$46 rect96.4567x124.0157
$47 rect33.4646x39.3701
$48 rect57.0866x45.2756
$49 rect37.4016x39.3701
$50 rect25.1969x26.7717
$51 rect45.2756x57.0866
$52 rect26.7717x25.1969
$53 rect39.3701x28.3465
$54 rect23.622x25.5906
$55 rect25.5906x23.622
$56 r10
$57 r6
$58 r9
$59 r16
$60 rect110.4323x66.9291
$61 rect105.315x67.9134
$62 r3.937
$63 r1
$64 r21.66
$65 r250
$66 r55
$67 s55
$68 r75
$69 r61.0236
$70 s61.0236
$71 r31.4961
$72 r65.9843
$73 r98.4252
$74 oval196.8504x98.4252
$75 oval177.1654x88.5827
$76 oval88.5827x177.1654
$77 r120
$78 r112
$79 r50
$80 r200

#
#Feature attribute names
#
@0 .geometry
@1 .pad_usage
@2 .smd

#
#Feature attribute text strings
#
&0 SMD_RectX61.0200Y9.8400
&1 SMD_RectX66.9300Y53.1500
&2 SMD_RectX9.8400Y61.0200
&3 SMD_RectX53.1500Y66.9300
&4 SMD_RectX28.0000Y165.0000
&5 SMD_RectX28.0000Y126.0000
&6 SMD_RectX9.8425Y10.8268
&7 SMD_RectX10.8268Y9.8425
&8 SMD_RectX28.3465Y39.3701
&9 SMD_RectX39.3701Y33.4646
&10 SMD_RectX27.5591Y35.4331
&11 SMD_RectX82.8740Y44.0945
&12 SMD_RectX35.4331Y27.5591
&13 SMD_RectX70.8661Y9.8425
&14 SMD_RectX165.3543Y125.9843
&15 SMD_OvalX78.7402Y23.6220
&16 SMD_RectX25.5906Y41.3386
&17 SMD_RectX39.3701Y37.4016
&18 SMD_RectX64.9606Y51.1811
&19 SMD_RectX17.7165Y54.3307
&20 SMD_RectX55.9055Y61.0236
&21 SMD_RectX70.8661Y74.8031
&22 SMD_RectX39.3701Y74.8031
&23 SMD_RectX19.6850Y90.5512
&24 SMD_RectX78.7402Y98.4252
&25 SMD_RectX86.6142Y41.3386
&26 SMD_RectX41.3386Y39.3701
&27 SMD_RectX19.6850Y35.4331
&28 SMD_OvalX57.0866Y17.7165
&29 SMD_RectX77.5591Y22.4409
&30 SMD_RectX51.1811Y74.8031
&31 SMD_RectX39.3701Y90.5512
&32 SMD_RectX39.3701Y70.8661
&33 SMD_RectX53.1496Y27.5591
&34 SMD_RectX27.5591Y45.2756
&35 SMD_RectX41.3386Y45.2756
&36 SMD_RectX50.0000Y200.0000
&37 SMD_RectX57.0866Y37.4016
&38 SMD_RectX31.4961Y66.9291
&39 SMD_RectX9.8425Y22.6378
&40 SMD_RectX26.5748Y9.8425
&41 SMD_RectX38.5827Y34.2520
&42 SMD_RectX212.5984Y114.1732
&43 SMD_RectX96.4567Y124.0157
&44 SMD_RectX33.4646Y39.3701
&45 SMD_RectX57.0866Y45.2756
&46 SMD_RectX37.4016Y39.3701
&47 SMD_RectX25.1969Y26.7717
&48 SMD_RectX45.2756Y57.0866
&49 SMD_RectX26.7717Y25.1969
&50 SMD_RectX39.3701Y28.3465
&51 SMD_RectX23.6220Y25.5906
&52 SMD_RectX25.5906Y23.6220
&53 Pad_Simple_X21.6600Y21.6600H21.6600C61.6600
&54 Pad_Simple_X250.0000Y250.0000H125.1969C165.1969
&55 Pad_Simple_X55.0000Y55.0000H30.0000C70.0000
&56 Pad_Simple_X75.0000Y75.0000H50.0000C90.0000
&57 Pad_Simple_X61.0236Y61.0236H41.3386C81.3386
&58 Pad_Simple_X31.4961Y31.4961H35.4331C75.4331
&59 Pad_Simple_X65.9843Y65.9843H65.9843C105.9843
&60 Pad_Simple_X98.4252Y98.4252H64.9606C104.9606
&61 Pad_Simple_X196.8504Y98.4252H39.3701C79.3701
&62 Pad_Simple_X177.1654Y88.5827H39.3701C79.3701
&63 Pad_Simple_X88.5827Y177.1654H39.3701C79.3701
&64 Pad_Simple_X120.0000Y120.0000H68.0000C108.0000
&65 Pad_Simple_X112.0000Y112.0000H60.0000C100.0000
&66 Pad_Complex_X50.0000Y50.0000H118.1102C158.1102
&67 Pad_Simple_X98.4252Y98.4252H70.8661C110.8661
&68 Pad_Simple_X50.0000Y50.0000H118.1102C158.1102
&69 VIA_RoundD16.0000H8.0000C48.0000
&70 VIA_RoundD200.0000H125.9843C165.9843

#
#Layer features
#
A 1.7712204 0.4310709 1.6275196 0.4310709 1.69937 0.4310709 62 P 0 N
A 2.4133858 0.2795276 2.3877951 0.2177462 2.4751672 0.2177462 1 P 0 N
A 2.4188425 0.1330565 2.4279525 0.111063 2.449946 0.1330565 1 P 0 N
A 2.4448819 0.2795276 2.4271651 0.2367555 2.487654 0.2367555 1 P 0 N
A 2.4494285 2.7188785 2.4550854 2.7165354 2.4550854 2.7245354 0 P 0 N
A 2.4673225 0.2173067 2.4593435 0.2332909 2.4473222 0.2173066 2 P 0 N
A 2.5758425 0.1342153 2.5854325 0.111063 2.6085848 0.1342153 1 P 0 N
A 2.5846451 0.2652719 2.5787402 0.2795276 2.5644845 0.2652719 1 P 0 N
A 2.6067769 0.8154384 2.5984252 0.7952756 2.6269397 0.7952756 1 P 0 N
A 2.6102362 0.259167 2.6181102 0.2401575 2.6371197 0.259167 1 P 0 N
A 2.6128425 0.139937 2.6248025 0.111063 2.6536765 0.139937 1 P 0 N
A 2.6181102 0.8267717 2.6263725 0.8467187 2.5981632 0.8467187 1 P 0 N
A 2.6220472 0.976378 2.6263725 0.9807033 2.6220472 0.9807033 1 P 0 N
A 2.6240151 0.2259018 2.6181102 0.2401575 2.6038545 0.2259018 1 P 0 N
A 2.6299213 0.8188976 2.6259843 0.8093928 2.6394261 0.8093928 1 P 0 N
A 2.6299213 0.8188976 2.6460525 0.8578418 2.5909771 0.8578418 1 P 0 N
A 2.6460525 0.9799318 2.6496063 0.976378 2.6496063 0.9799318 1 P 0 N
A 2.6792645 0.8288708 2.6653543 0.7952756 2.7128781 0.7952756 1 P 0 N
A 2.6792737 0.82888 2.6792645 0.8288708 2.7128781 0.7952756 1 P 0 N
A 2.6811024 0.8307087 2.6854225 0.8411383 2.6706728 0.8411383 1 P 0 N
A 2.6811024 0.976378 2.6854225 0.9806981 2.6811024 0.9806981 1 P 0 N
A 2.6846784 2.7165354 2.6903352 2.7188785 2.6846783 2.7245357 0 P 0 N
A 2.7007874 0.8307087 2.6929134 0.8116992 2.7197969 0.8116992 1 P 0 N
A 2.7007874 0.8307087 2.7051125 0.8411504 2.6903457 0.8411504 1 P 0 N
A 2.7051125 0.9799269 2.7086614 0.976378 2.7086614 0.9799269 1 P 0 N
A 2.7401575 0.976378 2.7444825 0.980703 2.7401575 0.980703 1 P 0 N
A 2.7402781 0.8190182 2.7322834 0.7997175 2.7595787 0.7997175 1 P 0 N
A 2.7402781 0.8190182 2.7444825 0.8291685 2.7301278 0.8291685 1 P 0 N
A 2.7468579 0.2782484 2.7421251 0.2652683 2.7622908 0.2652683 1 P 0 N
A 2.7468769 0.2782709 2.7477008 0.2796783 2.7430315 0.2814668 1 P 0 N
A 2.7487121 0.2821354 2.7483623 0.2814053 2.7530315 0.2796169 1 P 0 N
A 2.7598425 0.7952756 2.7641625 0.805705 2.7494131 0.805705 1 P 0 N
A 2.7641625 0.979932 2.7677165 0.976378 2.7677165 0.979932 1 P 0 N
A 2.7728425 0.1338532 2.7822825 0.111063 2.8050727 0.1338532 1 P 0 N
A 2.7814951 0.2747776 2.7795276 0.2795276 2.7747776 0.2747776 1 P 0 N
A 2.7818425 0.1121253 2.7822825 0.111063 2.7833448 0.1121253 1 P 0 N
A 2.7992126 0.7952756 2.8035325 0.8057048 2.7887834 0.8057048 1 P 0 N
A 2.7992126 0.976378 2.8035325 0.9806979 2.7992126 0.9806979 1 P 0 N
A 2.8232225 0.8038441 2.8267717 0.7952756 2.8353402 0.8038441 1 P 0 N
A 2.8232225 0.9799272 2.8267717 0.976378 2.8267717 0.9799272 1 P 0 N
A 2.8622047 0.7952756 2.8625925 0.7962118 2.8612685 0.7962118 1 P 0 N
A 2.8822725 0.822866 2.8937008 0.7952756 2.9212912 0.822866 1 P 0 N
A 2.9054946 0.2795104 2.8996051 0.2652676 2.9197718 0.2652676 1 P 0 N
A 2.9055118 0.2795276 2.9054946 0.2795104 2.9197718 0.2652676 1 P 0 N
A 2.9289751 0.1619374 2.9389751 0.1377953 2.9631172 0.1619374 0 P 0 N
A 2.9389751 0.2747784 2.9370079 0.2795276 2.9322587 0.2747784 1 P 0 N
A 2.9746503 0.2247425 2.9697144 0.2378982 2.95465 0.2247424 2 P 0 N
L -0.0001175 0.177913 0.5908825 0.177913 63 P 0
L -0.0004331 0.1781182 0.5901181 0.1781182 62 P 0
L 0.1998425 0.906063 0.5948031 0.906063 0 P 0
L 0.1998425 1.431063 0.5948031 1.431063 0 P 0
L 0.1998425 1.956063 0.5948031 1.956063 0 P 0
L 0.1998425 2.481063 0.5948031 2.481063 0 P 0
L 0.5901181 0.1781182 0.5901181 0.5029213 62 P 0
L 0.5901181 0.5029213 1.312559 0.5029213 62 P 0
L 0.5908825 0.177913 0.5908825 0.502913 63 P 0
L 0.5948031 0.906063 0.9326378 0.906063 0 P 0
L 0.5948031 1.431063 0.9326378 1.431063 0 P 0
L 0.5948031 1.956063 0.9326378 1.956063 0 P 0
L 0.5948031 2.481063 0.9326378 2.481063 0 P 0
L 0.6389685 4.012937 0.6389685 4.0388976 0 P 0
L 0.6389685 4.012937 0.8358425 3.816063 0 P 0
L 0.6389685 4.0932283 0.6448425 4.0991023 0 P 0
L 0.6448425 4.0991023 0.6448425 4.1975197 0 P 0
L 0.6448425 4.2546063 0.8465091 4.2546063 2 P 0
L 0.6538425 1.551063 0.6548425 1.550063 56 P 0
L 0.6539669 2.5938902 0.6548425 2.5930146 56 P 0
L 0.6548425 0.790063 0.6548425 0.8479921 56 P 0
L 0.6548425 0.9641339 0.6548425 1.027063 56 P 0
L 0.6548425 1.027063 0.6558425 1.028063 56 P 0
L 0.6548425 1.314063 0.6548425 1.3729921 56 P 0
L 0.6548425 1.4891339 0.6548425 1.550063 56 P 0
L 0.6548425 1.839063 0.6548425 1.8979921 56 P 0
L 0.6548425 2.0141339 0.6548425 2.073063 56 P 0
L 0.6548425 2.365063 0.6548425 2.4229921 56 P 0
L 0.6548425 2.5391339 0.6548425 2.5930146 56 P 0
L 0.8358425 3.816063 2.0048425 3.816063 0 P 0
L 0.8406351 4.0132704 0.8406351 4.0388976 0 P 0
L 0.8406351 4.0132704 1.0178425 3.836063 0 P 0
L 0.8406351 4.0932283 0.8465091 4.0991023 0 P 0
L 0.8465091 4.0991023 0.8465091 4.1925197 0 P 0
L 0.8465091 4.2546063 1.0481757 4.2546063 2 P 0
L 0.9005905 1.7470472 0.9005905 1.9240157 0 P 0
L 0.9005905 1.9240157 0.9326378 1.956063 0 P 0
L 0.9015747 0.7185038 0.9015747 0.8749999 0 P 0
L 0.9015747 0.8749999 0.9326378 0.906063 0 P 0
L 0.9045275 1.2244094 0.9045275 1.4029527 0 P 0
L 0.9045275 1.4029527 0.9326378 1.431063 0 P 0
L 0.9084645 2.2844487 0.9084645 2.4568897 0 P 0
L 0.9084645 2.4568897 0.9326378 2.481063 0 P 0
L 0.9326378 0.906063 1.0048425 0.906063 0 P 0
L 0.9326378 1.431063 1.0078425 1.431063 0 P 0
L 0.9326378 1.956063 1.0098425 1.956063 0 P 0
L 0.9326378 2.481063 1.0208425 2.481063 0 P 0
L 0.9596456 1.7431102 0.9596456 1.7470472 0 P 0
L 0.9596456 1.7431102 0.9837054 1.7190504 0 P 0
L 0.9606298 0.7145668 0.9606298 0.7185038 0 P 0
L 0.9606298 0.7145668 0.9881887 0.6870079 0 P 0
L 0.9635826 1.2204724 0.9635826 1.2244094 0 P 0
L 0.9635826 1.2204724 0.996063 1.187992 0 P 0
L 0.9675196 2.2805117 0.9675196 2.2844487 0 P 0
L 0.9675196 2.2805117 0.9904646 2.2575667 0 P 0
L 0.9837054 1.7190504 0.9866583 1.7190504 0 P 0
L 0.9866583 1.7190504 0.988189 1.7175197 0 P 0
L 0.9881887 0.6870079 0.9901575 0.6870079 0 P 0
L 0.9904646 2.2575667 0.995305 2.2575667 0 P 0
L 0.995305 2.2575667 0.9968357 2.256036 0 P 0
L 0.996063 1.1870079 0.996063 1.187992 0 P 0
L 1.0078425 1.431063 1.0088425 1.430063 0 P 0
L 1.0178425 3.836063 2.0298425 3.836063 0 P 0
L 1.0423017 4.0146038 1.0423017 4.0388976 0 P 0
L 1.0423017 4.0146038 1.1858425 3.871063 0 P 0
L 1.0423017 4.0932283 1.0481757 4.0991023 0 P 0
L 1.0481757 4.0991023 1.0481757 4.1925197 0 P 0
L 1.0481757 4.2546063 1.2498423 4.2546063 2 P 0
L 1.1570472 0.906063 1.1930472 0.942063 56 P 0
L 1.1570472 1.431063 1.1980472 1.472063 56 P 0
L 1.1570472 1.956063 1.1570472 1.9568346 56 P 0
L 1.1570472 1.9568346 1.2002756 2.000063 56 P 0
L 1.1570472 2.481063 1.2608425 2.481063 56 P 0
L 1.1858425 3.871063 2.0598425 3.871063 0 P 0
L 1.1930472 0.942063 1.2568425 0.942063 56 P 0
L 1.1980472 1.472063 1.2428425 1.472063 56 P 0
L 1.2002756 2.000063 1.2488425 2.000063 56 P 0
L 1.2439683 4.0159372 1.2439683 4.0388976 0 P 0
L 1.2439683 4.0159372 1.3638425 3.896063 0 P 0
L 1.2439683 4.0932283 1.2498423 4.0991023 0 P 0
L 1.2498423 4.0991023 1.2498423 4.1925197 0 P 0
L 1.2498423 4.2546063 1.2933858 4.2546063 2 P 0
L 1.2608425 2.481063 1.2618425 2.482063 56 P 0
L 1.2933858 4.2546063 1.2948425 4.256063 2 P 0
L 1.312559 0.313945 1.312559 0.5029213 62 P 0
L 1.312559 0.313945 1.6275197 0.313945 62 P 0
L 1.3454724 4.1427166 1.3454724 4.1751969 0 P 0
L 1.3454724 4.1427166 1.3464567 4.1417323 0 P 0
L 1.3464567 3.9783465 1.3484252 3.980315 0 P 0
L 1.3464567 4.0374016 1.3464567 4.0826772 0 P 0
L 1.3464567 4.0374016 1.3562363 4.0471812 0 P 0
L 1.3484252 3.980315 1.4084645 3.980315 0 P 0
L 1.3562363 4.0471812 1.4509213 4.0471812 0 P 0
L 1.3638425 3.896063 2.0848425 3.896063 0 P 0
L 1.4509213 4.0471812 1.4576771 4.053937 0 P 0
L 1.4576771 4.153937 1.4870511 4.124563 0 P 0
L 1.4870511 4.124563 1.631559 4.124563 0 P 0
L 1.5578425 4.229063 1.6018425 4.273063 56 P 0
L 1.5679134 1.2854331 1.5679134 1.3100394 0 P 0
L 1.5679134 1.3100394 1.577547 1.319673 0 P 0
L 1.5682025 2.067703 1.6171125 2.067703 0 P 0
L 1.5698819 4.1712599 1.5698819 4.1732284 0 P 0
L 1.5698819 4.1712599 1.569882 4.1712599 0 P 0
L 1.5698819 4.1732284 1.5943574 4.1977039 0 P 0
L 1.577547 1.319673 1.6171125 1.319673 0 P 0
L 1.5943574 4.1977039 1.6296999 4.1977039 0 P 0
L 1.6018425 4.273063 1.6643465 4.273063 56 P 0
L 1.6171125 1.398413 1.6711925 1.398413 56 P 0
L 1.6171125 1.496843 1.6171925 1.496923 56 P 0
L 1.6171125 1.595263 1.6706425 1.595263 56 P 0
L 1.6171125 1.693693 1.6704725 1.693693 56 P 0
L 1.6171125 1.792113 1.6171625 1.792063 56 P 0
L 1.6171125 1.890543 1.6753225 1.890543 56 P 0
L 1.6171125 1.988963 1.6747425 1.988963 56 P 0
L 1.6171125 2.087393 1.6171125 2.118333 0 P 0
L 1.6171125 2.118333 1.6198425 2.121063 0 P 0
L 1.6171625 1.792063 1.6718425 1.792063 56 P 0
L 1.6171925 1.496923 1.6456646 1.496923 56 P 0
L 1.6275197 0.313945 1.6275197 0.4310709 62 P 0
L 1.6296999 4.1977039 1.631559 4.199563 0 P 0
L 1.631559 4.024563 1.6538733 4.024563 0 P 0
L 1.631559 4.099563 1.6713425 4.099563 56 P 0
L 1.631559 4.149563 1.6334181 4.1477039 0 P 0
L 1.6334181 4.1477039 1.6762016 4.1477039 0 P 0
L 1.6456646 1.496923 1.6458046 1.497063 56 P 0
L 1.6458046 1.497063 1.6718425 1.497063 56 P 0
L 1.6538733 4.024563 1.6587316 4.0197047 0 P 0
L 1.6587316 4.0197047 1.6592008 4.0197047 0 P 0
L 1.6592008 4.0197047 1.7153228 3.9635827 0 P 0
L 1.6643465 4.248559 1.6643465 4.273063 56 P 0
L 1.6643465 4.248559 1.6878425 4.225063 56 P 0
L 1.6704725 1.693693 1.6708425 1.694063 56 P 0
L 1.6706425 1.595263 1.6708425 1.595063 56 P 0
L 1.6711925 1.398413 1.6718425 1.399063 56 P 0
L 1.6713425 4.099563 1.6918425 4.079063 56 P 0
L 1.6747425 1.988963 1.6748425 1.989063 56 P 0
L 1.6753225 1.890543 1.6758425 1.891063 56 P 0
L 1.6762016 4.1477039 1.7743425 4.049563 0 P 0
L 1.6878425 4.225063 1.8538425 4.225063 56 P 0
L 1.7148425 1.595063 1.7150425 1.595263 56 P 0
L 1.7150425 1.595263 1.7765525 1.595263 56 P 0
L 1.7153228 3.9635827 2.2450787 3.9635827 0 P 0
L 1.7168425 1.399063 1.7174925 1.398413 56 P 0
L 1.7174925 1.398413 1.7765525 1.398413 56 P 0
L 1.7188425 1.497063 1.7190625 1.496843 56 P 0
L 1.7188425 1.792063 1.7188925 1.792113 56 P 0
L 1.7188925 1.792113 1.7765525 1.792113 56 P 0
L 1.7190625 1.496843 1.7765525 1.496843 56 P 0
L 1.7198425 1.536063 1.7199175 1.536138 0 P 0
L 1.7199175 1.536138 1.7764775 1.536138 0 P 0
L 1.7218425 1.694063 1.7222125 1.693693 56 P 0
L 1.7218425 1.890063 1.7223225 1.890543 56 P 0
L 1.7218425 1.989063 1.7219425 1.988963 56 P 0
L 1.7219425 1.988963 1.7765525 1.988963 56 P 0
L 1.7222125 1.693693 1.7765525 1.693693 56 P 0
L 1.7223225 1.890543 1.7765525 1.890543 56 P 0
L 1.7268425 4.329374 1.7273386 4.3288779 56 P 0
L 1.7273386 4.273063 1.7273386 4.3288779 56 P 0
L 1.7498425 4.110063 1.7643425 4.124563 56 P 0
L 1.7548425 2.088313 1.7548425 2.126063 0 P 0
L 1.7548425 2.088313 1.7557625 2.087393 0 P 0
L 1.7557625 2.087393 1.7765525 2.087393 0 P 0
L 1.7643425 4.124563 1.8461259 4.124563 56 P 0
L 1.7743425 4.049563 1.8461259 4.049563 0 P 0
L 1.7764775 1.536138 1.7765525 1.536213 0 P 0
L 1.7765525 1.319673 1.7973083 1.319673 0 P 0
L 1.7765525 1.516523 1.8973025 1.516523 0 P 0
L 1.7765525 1.614953 1.8157325 1.614953 0 P 0
L 1.7765525 1.674003 1.8227825 1.674003 0 P 0
L 1.7765525 1.811803 1.8799377 1.811803 0 P 0
L 1.7765525 2.008653 1.7768125 2.008393 57 P 0
L 1.7765525 2.028333 1.7766125 2.028393 57 P 0
L 1.7765525 2.067703 1.8814825 2.067703 0 P 0
L 1.7888425 4.2896299 1.7888425 4.329374 56 P 0
L 1.7888425 4.2896299 1.8024094 4.276063 56 P 0
L 1.7973083 1.319673 1.7982283 1.318753 0 P 0
L 1.7978425 0.355063 2.050063 0.6072835 0 P 0
L 1.7980325 0.111063 1.7980325 0.2399617 2 P 0
L 1.7980325 0.2399617 1.8150702 0.2569994 2 P 0
L 1.7982283 1.3041339 1.7982283 1.318753 0 P 0
L 1.8150702 0.2569994 1.8357789 0.2569994 2 P 0
L 1.8157325 1.614953 1.8938425 1.693063 0 P 0
L 1.8357789 0.2569994 1.8465953 0.2678158 2 P 0
L 1.8374025 0.111063 1.8374025 0.2553758 2 P 0
L 1.8374025 0.2553758 1.8498425 0.2678158 2 P 0
L 1.8461259 4.024563 1.8868543 4.024563 0 P 0
L 1.8461259 4.074563 1.9335078 4.074563 0 P 0
L 1.8461259 4.099563 1.8783425 4.099563 56 P 0
L 1.8465953 0.2678158 1.8498425 0.2678158 2 P 0
L 1.8538425 4.225063 1.8732756 4.2444961 56 P 0
L 1.8732756 4.2444961 1.8732756 4.2701575 56 P 0
L 1.8732756 4.2701575 1.8732756 4.276063 56 P 0
L 1.8732756 4.2701575 1.8732756 4.2816695 56 P 0
L 1.8732756 4.2816695 1.8909134 4.2993073 56 P 0
L 1.8767725 0.111063 1.8767725 0.2408858 2 P 0
L 1.8783425 4.099563 1.9080079 4.1292284 56 P 0
L 1.8791811 4.276063 1.9148425 4.276063 56 P 0
L 1.8799377 1.811803 1.8826777 1.809063 0 P 0
L 1.8814825 2.067703 1.8848425 2.071063 0 P 0
L 1.8868543 4.024563 1.8933543 4.018063 0 P 0
L 1.8933543 4.018063 1.9038425 4.018063 0 P 0
L 1.8973025 1.516523 2.1088425 1.728063 0 P 0
L 1.9080079 4.1292284 1.9338425 4.1292284 56 P 0
L 1.9148425 4.276063 1.9338425 4.257063 56 P 0
L 1.9154925 0.111713 1.9154925 0.244763 2 P 0
L 1.9154925 0.111713 1.9161425 0.111063 2 P 0
L 1.9335078 4.074563 1.9338425 4.0748977 0 P 0
L 1.9338424 4.2570629 1.9338425 4.2570628 56 P 0
L 1.9338425 4.1292284 1.9338425 4.2570628 56 P 0
L 2.0342525 0.111063 2.0342525 0.245473 2 P 0
L 2.0342525 0.245473 2.0348425 0.246063 2 P 0
L 2.0433071 4.057874 2.0864173 4.0147638 0 P 0
L 2.050063 0.6072835 2.503937 0.6072835 0 P 0
L 2.0728351 0.1377953 2.0728351 0.2598431 2 P 0
L 2.0728351 0.2598431 2.0846456 0.2716536 2 P 0
L 2.0736225 0.111063 2.0766957 0.1141362 2 P 0
L 2.0846456 0.2716536 2.1122047 0.2716536 2 P 0
L 2.0864173 4.0147638 2.1515748 4.0147638 0 P 0
L 2.1088425 1.728063 2.1088425 2.540063 0 P 0
L 2.1088425 2.540063 2.1468425 2.578063 0 P 0
L 2.1398425 3.611063 2.1398425 3.6633465 2 P 0
L 2.1398425 3.6633465 2.1398425 3.6641339 2 P 0
L 2.1398425 3.6633465 2.1575591 3.6456299 2 P 0
L 2.1398425 3.6641339 2.1423149 3.6666063 2 P 0
L 2.1398425 3.6979922 2.1398425 3.738063 56 P 0
L 2.1413307 2.6248976 2.1468425 2.6248976 0 P 0
L 2.1460663 4.0763747 2.1460663 4.1037909 0 P 0
L 2.1460663 4.0763747 2.1476378 4.0748032 0 P 0
L 2.1468425 2.578063 2.1468425 2.6248976 0 P 0
L 2.1468425 2.6792283 2.1468425 2.753063 0 P 0
L 2.1476378 4.0748032 2.1515748 4.0748032 0 P 0
L 2.1515748 4.0147638 2.2106299 4.0147638 0 P 0
L 2.1575591 3.6456299 2.2098425 3.6456299 2 P 0
L 2.2098425 3.6456299 2.2115158 3.6439566 2 P 0
L 2.2098425 3.7164961 2.215748 3.7164961 56 P 0
L 2.2115158 3.6439566 2.3281693 3.6439566 2 P 0
L 2.2125984 4.0748032 2.242126 4.0748032 0 P 0
L 2.215748 3.7164961 2.2333858 3.7341339 56 P 0
L 2.2298425 2.586063 2.2326625 2.583243 0 P 0
L 2.2326625 2.518253 2.2326625 2.583243 0 P 0
L 2.2333858 3.7341339 2.2333858 3.7352051 56 P 0
L 2.2333858 3.7352051 2.2392437 3.741063 56 P 0
L 2.2392437 3.741063 2.2588425 3.741063 56 P 0
L 2.242126 4.0748032 2.253937 4.0866142 0 P 0
L 2.2450787 3.9635827 2.3325669 4.0510709 0 P 0
L 2.2523425 2.518253 2.2523425 2.613563 0 P 0
L 2.2538425 2.279063 2.2917125 2.316933 56 P 0
L 2.2548425 3.536063 2.2642755 3.545496 0 P 0
L 2.2642755 3.545496 2.3117952 3.545496 0 P 0
L 2.2720325 2.463873 2.2720325 2.518253 0 P 0
L 2.2813858 4.1703386 2.2813858 4.2076063 56 P 0
L 2.2813858 4.2076063 2.2908425 4.217063 56 P 0
L 2.2917125 2.316933 2.2917125 2.358813 56 P 0
L 2.2917125 2.518253 2.2917925 2.518333 56 P 0
L 2.2917925 2.518333 2.2917925 2.5563201 56 P 0
L 2.2917925 2.5563201 2.3215354 2.586063 56 P 0
L 2.3098425 0.246063 2.3385827 0.246063 2 P 0
L 2.3114025 2.358813 2.3310825 2.358813 0 P 0
L 2.3114125 0.878873 2.3114125 0.933633 56 P 0
L 2.3114125 0.933633 2.3118425 0.934063 56 P 0
L 2.3114125 1.038313 2.3114125 1.0900094 56 P 0
L 2.3114125 1.0900094 2.3128425 1.0914394 56 P 0
L 2.3117952 3.545496 2.3298425 3.5635433 0 P 0
L 2.3215354 3.361063 2.3215354 3.3977559 2 P 0
L 2.3215354 3.3977559 2.3298425 3.406063 2 P 0
L 2.3281693 3.6439566 2.3298425 3.6422834 2 P 0
L 2.3298425 3.4848031 2.3335826 3.481063 0 P 0
L 2.3308425 2.215063 2.3310825 2.215303 0 P 0
L 2.3310825 2.215303 2.3310825 2.358813 0 P 0
L 2.3325669 4.0510709 2.3325669 4.1703386 0 P 0
L 2.3335826 3.481063 2.3898425 3.481063 0 P 0
L 2.3385827 0.246063 2.3475643 0.2370814 2 P 0
L 2.3475643 0.1127112 2.3475643 0.2370814 2 P 0
L 2.3475643 0.1127112 2.3492125 0.111063 2 P 0
L 2.3507725 2.518253 2.3507725 2.6765599 0 P 0
L 2.3507725 2.6765599 2.394685 2.7204724 0 P 0
L 2.3533464 4.0177165 2.3581575 4.0225276 0 P 0
L 2.3581575 4.0225276 2.3581575 4.1703386 0 P 0
L 2.378937 2.7893701 2.378937 2.8907479 0 P 0
L 2.378937 2.7893701 2.4494285 2.7188785 0 P 0
L 2.378937 2.8907479 2.3877954 2.8996063 0 P 0
L 2.3877951 0.1377953 2.3877951 0.2177462 1 P 0
L 2.3877954 2.9586614 2.3898425 2.9607085 0 P 0
L 2.3898425 2.9607085 2.3898425 3.481063 0 P 0
L 2.3901425 2.358813 2.3901425 2.397363 56 P 0
L 2.3901425 2.397363 2.4048425 2.412063 56 P 0
L 2.3901425 2.518253 2.3901425 2.560363 56 P 0
L 2.3901425 2.560363 2.4088425 2.579063 56 P 0
L 2.4088425 2.579063 2.4098425 2.579063 56 P 0
L 2.4098225 2.314083 2.4098225 2.358813 0 P 0
L 2.4098225 2.314083 2.4098425 2.314063 0 P 0
L 2.4098325 0.878873 2.4098325 0.932053 56 P 0
L 2.4098325 1.038313 2.4098325 1.088053 56 P 0
L 2.4098425 2.283063 2.4298425 2.303063 0 P 0
L 2.4271651 0.1377953 2.4271651 0.2367555 1 P 0
L 2.4295125 2.358813 2.4296449 2.3586806 0 P 0
L 2.4296449 2.3225448 2.4296449 2.3586806 0 P 0
L 2.4296449 2.3225448 2.4298425 2.3223472 0 P 0
L 2.4298425 2.303063 2.4298425 2.3223472 0 P 0
L 2.4348425 3.546063 2.4523228 3.5635433 0 P 0
L 2.4470546 0.2425914 2.4593435 0.2332909 2 P 0
L 2.4491925 2.2858778 2.4491925 2.358813 0 P 0
L 2.4491925 2.2858778 2.4508425 2.2842278 0 P 0
L 2.4491925 2.518253 2.4491925 2.5978146 0 P 0
L 2.4491925 2.5978146 2.4635827 2.6122048 0 P 0
L 2.4508425 2.282063 2.4508425 2.2842278 0 P 0
L 2.4523228 3.5635433 2.5048425 3.5635433 0 P 0
L 2.4550854 2.7165354 2.6846784 2.7165354 0 P 0
L 2.4635827 2.6122048 2.4635827 2.6742127 0 P 0
L 2.4635827 2.6742127 2.4839956 2.6946256 0 P 0
L 2.4673224 0.2173067 2.4673225 0.2173067 2 P 0
L 2.4673225 0.111063 2.4673225 0.2173067 2 P 0
L 2.4688825 2.2997493 2.4688825 2.358813 0 P 0
L 2.4688825 2.2997493 2.4758425 2.2927893 0 P 0
L 2.4688825 2.518253 2.4688825 2.5888506 0 P 0
L 2.4688825 2.5888506 2.4948425 2.6148106 0 P 0
L 2.4758425 2.291063 2.4758425 2.2927893 0 P 0
L 2.4758425 2.456063 2.4885625 2.468783 56 P 0
L 2.4839956 2.6946256 2.4934051 2.6946256 0 P 0
L 2.4885625 2.358813 2.4885625 2.412783 56 P 0
L 2.4885625 2.412783 2.4888425 2.413063 56 P 0
L 2.4885625 2.468783 2.4885625 2.518253 56 P 0
L 2.4934051 2.6946256 2.4948425 2.696063 0 P 0
L 2.4948425 2.6148106 2.4948425 2.661063 0 P 0
L 2.4998425 2.236063 2.5279325 2.264153 0 P 0
L 2.503937 0.464567 2.503937 0.5738189 0 P 0
L 2.503937 0.464567 2.5393701 0.4291339 0 P 0
L 2.503937 0.6072835 3.0551181 0.6072835 0 P 0
L 2.5048425 3.406063 2.6348425 3.406063 0 P 0
L 2.5048425 3.4848031 2.5785826 3.4848031 0 P 0
L 2.5048425 3.6422834 2.5981497 3.6422834 2 P 0
L 2.5059051 0.1377953 2.507874 0.1397642 0 P 0
L 2.507874 0.1397642 2.507874 0.2716535 0 P 0
L 2.507874 0.2716535 2.5393701 0.3031496 0 P 0
L 2.5082625 0.878873 2.5082625 0.931483 56 P 0
L 2.5082625 1.038313 2.5082625 1.089483 56 P 0
L 2.5082625 1.089483 2.5088425 1.090063 56 P 0
L 2.5279325 2.264153 2.5279325 2.358813 0 P 0
L 2.5279325 2.518253 2.5279325 2.5820664 0 P 0
L 2.5279325 2.5820664 2.6122047 2.6663386 0 P 0
L 2.5393701 0.3031496 2.5393701 0.4291339 0 P 0
L 2.5454525 0.111673 2.5454525 0.244233 2 P 0
L 2.5454525 0.244233 2.5460625 0.244843 2 P 0
L 2.5476225 2.313283 2.5476225 2.358813 0 P 0
L 2.5476225 2.313283 2.5798425 2.281063 0 P 0
L 2.5673025 2.358813 2.5673025 2.403523 0 P 0
L 2.5673025 2.403523 2.5758425 2.412063 0 P 0
L 2.5785826 3.4848031 2.5798425 3.486063 0 P 0
L 2.5818425 2.312063 2.5869925 2.317213 56 P 0
L 2.5846451 0.1377953 2.5846451 0.2652719 1 P 0
L 2.5868425 2.569063 2.5869925 2.568913 56 P 0
L 2.5869925 2.317213 2.5869925 2.358813 56 P 0
L 2.5869925 2.518253 2.5869925 2.568913 56 P 0
L 2.5981497 3.6422834 2.633937 3.6064961 2 P 0
L 2.5998425 2.4317334 2.5998425 2.436063 0 P 0
L 2.5998425 2.4317334 2.6066725 2.4249034 0 P 0
L 2.6066725 2.358813 2.6066725 2.4249034 0 P 0
L 2.6066825 0.878873 2.6066825 0.931903 56 P 0
L 2.6066825 0.931903 2.6088425 0.934063 56 P 0
L 2.6066825 1.038313 2.6066825 1.090903 56 P 0
L 2.6066825 1.090903 2.6068425 1.091063 56 P 0
L 2.6067769 0.8154384 2.6181102 0.8267717 1 P 0
L 2.6102362 0.259167 2.6102362 0.2795276 1 P 0
L 2.6122047 2.6663386 3.5688976 2.6663386 0 P 0
L 2.6240151 0.1377953 2.6240151 0.2259018 1 P 0
L 2.6248425 2.461063 2.6256025 2.461823 0 P 0
L 2.6248425 2.461063 2.6263625 2.459543 0 P 0
L 2.6259843 0.7952756 2.6259843 0.8093928 1 P 0
L 2.6263625 2.358813 2.6263625 2.459543 0 P 0
L 2.6263725 0.8467187 2.6263725 0.878873 1 P 0
L 2.6263725 0.9807033 2.6263725 1.038313 1 P 0
L 2.633937 3.6064961 2.6398425 3.6064961 2 P 0
L 2.636874 0.2479055 2.6377322 0.2470473 2 P 0
L 2.636874 0.2479055 2.6907891 0.2479055 2 P 0
L 2.6377322 0.2470473 2.6516693 0.2470473 2 P 0
L 2.6398425 3.5356299 2.645748 3.5356299 2 P 0
L 2.6398425 3.6064961 2.645748 3.6064961 2 P 0
L 2.645748 3.5356299 2.6748425 3.5065354 2 P 0
L 2.645748 3.6064961 2.659252 3.5929921 2 P 0
L 2.6458425 2.274063 2.6458425 2.2993472 0 P 0
L 2.6458425 2.2993472 2.6460425 2.2995472 0 P 0
L 2.6460425 2.2995472 2.6460425 2.358813 0 P 0
L 2.6460525 0.8578418 2.6460525 0.878873 1 P 0
L 2.6460525 0.9799318 2.6460525 1.038313 1 P 0
L 2.6516693 0.2470473 2.6633851 0.2353315 2 P 0
L 2.659252 3.5929921 2.7248425 3.5929921 2 P 0
L 2.6633851 0.1377953 2.6633851 0.2353315 2 P 0
L 2.6657325 2.291173 2.6657325 2.358813 0 P 0
L 2.6657325 2.291173 2.6658425 2.291063 0 P 0
L 2.6657425 1.038313 2.6657425 1.091963 56 P 0
L 2.6657425 1.091963 2.6658425 1.092063 56 P 0
L 2.6748425 3.501063 2.6748425 3.5065354 2 P 0
L 2.6792645 0.8288708 2.6792737 0.82888 1 P 0
L 2.6792737 0.82888 2.6811024 0.8307087 1 P 0
L 2.6798425 3.661063 2.6805511 3.6617716 0 P 0
L 2.6805511 3.6617716 2.7198425 3.6617716 0 P 0
L 2.6854125 2.311493 2.6854125 2.358813 56 P 0
L 2.6854125 2.311493 2.6858425 2.311063 56 P 0
L 2.6854125 2.518253 2.6854125 2.567633 56 P 0
L 2.6854125 2.567633 2.6858425 2.568063 56 P 0
L 2.6854225 0.8411383 2.6854225 0.878873 1 P 0
L 2.6854225 0.9806981 2.6854225 1.038313 1 P 0
L 2.6903352 2.7188785 2.6929134 2.7214567 0 P 0
L 2.6907891 0.2479055 2.7025049 0.2361897 2 P 0
L 2.6929134 0.7952756 2.6929134 0.8116992 1 P 0
L 2.694252 3.7503543 2.694252 3.7579135 2 P 0
L 2.694252 3.7579135 2.7224094 3.7860709 2 P 0
L 2.7025049 0.1380455 2.7025049 0.1806006 2 P 0
L 2.7025049 0.1380455 2.7027551 0.1377953 2 P 0
L 2.7025049 0.1806006 2.7025049 0.2361897 2 P 0
L 2.7025049 0.1806006 2.7035425 0.179563 2 P 0
L 2.7028425 2.293063 2.7028425 2.2952278 0 P 0
L 2.7028425 2.2952278 2.7058425 2.2982278 0 P 0
L 2.7035425 0.111063 2.7035425 0.179563 2 P 0
L 2.7051025 2.3200872 2.7051025 2.358813 0 P 0
L 2.7051025 2.3200872 2.7058425 2.3193472 0 P 0
L 2.7051125 0.8411504 2.7051125 0.878873 1 P 0
L 2.7051125 0.9799269 2.7051125 1.038313 1 P 0
L 2.7058425 2.2982278 2.7058425 2.3193472 0 P 0
L 2.7198425 3.6617716 2.7582283 3.6617716 0 P 0
L 2.7224094 3.7860709 2.7810946 3.7860709 2 P 0
L 2.7244825 1.093063 2.7247925 1.0905923 56 P 0
L 2.7247825 2.2972878 2.7247825 2.358813 0 P 0
L 2.7247825 2.2972878 2.7268425 2.2952278 0 P 0
L 2.7247925 1.038313 2.7247925 1.0905923 56 P 0
L 2.7248425 3.521063 2.7248425 3.5591338 2 P 0
L 2.7248425 3.5929921 2.7273149 3.5905197 2 P 0
L 2.7248425 3.729063 2.7248425 3.7297637 56 P 0
L 2.7248425 3.7297637 2.7327165 3.7376377 56 P 0
L 2.7268425 2.293063 2.7268425 2.2952278 0 P 0
L 2.7273149 3.5905197 2.7503858 3.5905197 2 P 0
L 2.7322834 0.7997175 2.7322835 0.7996858 1 P 0
L 2.7322835 0.7952756 2.7322835 0.7996858 1 P 0
L 2.7327165 3.7376377 2.7405906 3.7376377 56 P 0
L 2.7405906 3.7376377 2.7454331 3.7424802 56 P 0
L 2.7408425 0.113133 2.7429125 0.111063 1 P 0
L 2.7421251 0.1377953 2.7421251 0.2652683 1 P 0
L 2.7429125 0.111063 2.7458425 0.113993 1 P 0
L 2.7444825 0.8291685 2.7444825 0.878873 1 P 0
L 2.7444825 0.980703 2.7444825 1.038313 1 P 0
L 2.7454331 3.7424802 2.7454331 3.7503543 56 P 0
L 2.7468579 0.2782484 2.7468769 0.2782709 1 P 0
L 2.7477008 0.2796783 2.7483622 0.2814053 1 P 0
L 2.7487121 0.2821354 2.7488082 0.2823002 1 P 0
L 2.7488082 0.2823002 2.74882 0.282312 1 P 0
L 2.7503858 3.5905197 2.7748425 3.566063 2 P 0
L 2.7568898 3.1872047 2.840748 3.1872047 0 P 0
L 2.7582283 3.6617716 2.7975197 3.701063 0 P 0
L 2.7641625 0.805705 2.7641625 0.878873 1 P 0
L 2.7641625 0.979932 2.7641625 1.038313 1 P 0
L 2.7810946 3.7860709 2.809252 3.7579135 2 P 0
L 2.7814951 0.1377953 2.7814951 0.2747776 1 P 0
L 2.7838425 2.358813 2.7838425 2.429063 56 P 0
L 2.7838425 2.518253 2.7838425 2.568063 56 P 0
L 2.7838525 1.038313 2.7838525 1.0915923 56 P 0
L 2.7838525 1.0915923 2.7841625 1.094063 56 P 0
L 2.7975197 3.701063 3.0006299 3.701063 0 P 0
L 2.7992126 0.2519685 2.8176623 0.2335188 2 P 0
L 2.7992126 0.2519685 2.8375984 0.2519685 2 P 0
L 2.7998425 3.616063 2.829 3.6452205 0 P 0
L 2.8035225 2.358813 2.8038425 2.358493 0 P 0
L 2.8035325 0.8057048 2.8035325 0.878873 1 P 0
L 2.8035325 0.9806979 2.8035325 1.038313 1 P 0
L 2.8035325 1.038313 2.8038425 1.038003 1 P 0
L 2.8038425 2.307063 2.8038425 2.358493 0 P 0
L 2.809252 3.7503543 2.809252 3.7579135 2 P 0
L 2.8176623 0.1409981 2.8176623 0.2335188 2 P 0
L 2.8176623 0.1409981 2.8208651 0.1377953 2 P 0
L 2.8218425 2.601063 2.8232125 2.599693 0 P 0
L 2.8232125 2.518253 2.8232125 2.599693 0 P 0
L 2.8232225 0.8038441 2.8232225 0.878873 1 P 0
L 2.8232225 0.9799272 2.8232225 1.038313 1 P 0
L 2.829 3.6452205 2.829 3.6559291 0 P 0
L 2.829 3.6559291 2.8348425 3.6617716 0 P 0
L 2.8348425 3.6617716 2.8397638 3.6666929 0 P 0
L 2.8375984 0.2519685 2.8565402 0.2330267 2 P 0
L 2.8397638 3.6666929 2.9448425 3.6666929 0 P 0
L 2.840748 3.1872047 3.0488976 3.3953543 0 P 0
L 2.8418425 2.263063 2.8418425 2.299063 0 P 0
L 2.8418425 2.299063 2.8625825 2.319803 0 P 0
L 2.8428425 1.095063 2.8429025 1.095003 56 P 0
L 2.8429025 1.038313 2.8429025 1.095003 56 P 0
L 2.8565402 0.1414902 2.8565402 0.2330267 2 P 0
L 2.8565402 0.1414902 2.8570225 0.1410079 2 P 0
L 2.8570225 0.1410079 2.8602351 0.1377953 2 P 0
L 2.8604331 3.7503543 2.8604331 3.7846536 56 P 0
L 2.8604331 3.7846536 2.8608425 3.785063 56 P 0
L 2.8625825 2.319803 2.8625825 2.358813 0 P 0
L 2.8625925 0.7962118 2.8625925 0.878873 1 P 0
L 2.8718425 2.297063 2.8822625 2.307483 56 P 0
L 2.8818425 2.566063 2.8822625 2.565643 56 P 0
L 2.8822625 2.307483 2.8822625 2.358813 56 P 0
L 2.8822625 2.518253 2.8822625 2.565643 56 P 0
L 2.8822725 0.822866 2.8822725 0.878873 1 P 0
L 2.8888425 4.221063 2.8889212 4.2211417 56 P 0
L 2.8889212 4.2211417 2.9448425 4.2211417 56 P 0
L 2.8948425 2.431063 2.8948425 2.4650041 0 P 0
L 2.8948425 2.4650041 2.9019525 2.4721141 0 P 0
L 2.8996051 0.1377951 2.8996051 0.1377953 1 P 0
L 2.8996051 0.1377953 2.8996051 0.2652676 1 P 0
L 2.9003925 0.111063 2.9078425 0.118513 1 P 0
L 2.9018425 1.095063 2.9019625 1.094943 56 P 0
L 2.9019525 2.304953 2.9019525 2.358813 0 P 0
L 2.9019525 2.304953 2.9208425 2.286063 0 P 0
L 2.9019525 2.4721141 2.9019525 2.518253 0 P 0
L 2.9019625 0.878873 2.9019625 0.921183 56 P 0
L 2.9019625 0.921183 2.9338425 0.953063 56 P 0
L 2.9019625 1.038313 2.9019625 1.094943 56 P 0
L 2.9054946 0.2795104 2.9055118 0.2795276 1 P 0
L 2.9207375 2.428168 2.9207375 2.517358 0 P 0
L 2.9207375 2.428168 2.9208425 2.428063 0 P 0
L 2.9207375 2.517358 2.9216325 2.518253 0 P 0
L 2.9208425 2.286063 2.9428425 2.286063 0 P 0
L 2.9318425 0.118983 2.9397625 0.111063 1 P 0
L 2.9389751 0.1377953 2.9389751 0.2747784 1 P 0
L 2.9448425 3.7454331 2.9448425 3.951063 0 P 0
L 2.9488425 2.428063 2.9488425 2.456063 0 P 0
L 2.9488425 2.428063 2.9806925 2.396213 0 P 0
L 2.9574751 0.2519685 2.9697144 0.2378982 2 P 0
L 2.9588425 2.621063 2.9806925 2.599213 0 P 0
L 2.9610025 2.311903 2.9610025 2.358813 0 P 0
L 2.9610025 2.311903 2.9858425 2.287063 0 P 0
L 2.9746502 0.2247425 2.9746503 0.2247425 2 P 0
L 2.9746503 0.1414901 2.9746503 0.2247425 2 P 0
L 2.9746503 0.1414901 2.9751325 0.1410079 2 P 0
L 2.9751325 0.1410079 2.9783451 0.1377953 2 P 0
L 2.9806925 2.358813 2.9806925 2.396213 0 P 0
L 2.9806925 2.518253 2.9806925 2.599213 0 P 0
L 3.0006299 3.701063 3.035 3.6666929 0 P 0
L 3.035 3.6666929 3.0448425 3.6666929 0 P 0
L 3.0448425 3.7454331 3.0448425 3.951063 0 P 0
L 3.0448425 4.2211417 3.1448425 4.2211417 2 P 0
L 3.0488976 3.3953543 3.0685826 3.3953543 0 P 0
L 3.0531481 0.5718489 3.0551181 0.5738189 0 P 0
L 3.0551181 0.1592623 3.0551181 0.5738189 0 P 0
L 3.0551181 0.1592623 3.0570851 0.1572953 0 P 0
L 3.0578725 0.130563 3.0598425 0.132533 0 P 0
L 3.0685826 3.3953543 3.0688976 3.3956693 0 P 0
L 3.0972425 0.111063 3.0974409 0.1112614 2 P 0
L 3.0974409 0.1112614 3.0974409 0.2519685 2 P 0
L 3.1112205 3.1372047 3.1125984 3.1358268 0 P 0
L 3.1112205 3.1872047 3.1113189 3.1871063 0 P 0
L 3.1112205 3.2372047 3.172244 3.2372047 0 P 0
L 3.1112205 3.2872047 3.1275632 3.2872047 0 P 0
L 3.1113189 3.1871063 3.188878 3.1871063 0 P 0
L 3.1125984 3.1358268 3.1830708 3.1358268 0 P 0
L 3.1275632 3.2872047 3.1347796 3.2944211 0 P 0
L 3.1347796 3.2944211 3.1347796 3.3444253 0 P 0
L 3.1347796 3.3444253 3.2470472 3.4566929 0 P 0
L 3.1448425 3.6666929 3.2399212 3.6666929 0 P 0
L 3.1448425 3.7454331 3.1448425 3.951063 0 P 0
L 3.1448425 4.1461417 3.1448425 4.2211417 2 P 0
L 3.1448425 4.1461417 3.1895472 4.101437 2 P 0
L 3.172244 3.2372047 3.2057086 3.2706693 0 P 0
L 3.188878 3.1871063 3.1889764 3.1870079 0 P 0
L 3.1895472 3.8559025 3.1895472 4.101437 2 P 0
L 3.1895472 3.8559025 3.219252 3.8261977 2 P 0
L 3.1917598 2.8247538 3.1917598 2.9240433 0 P 0
L 3.1917598 2.8247538 3.2006317 2.8158819 0 P 0
L 3.1917598 2.9240433 3.2509842 2.9832677 0 P 0
L 3.1972633 1.714063 3.1972633 1.7154838 0 P 0
L 3.1972633 1.7154838 3.2344825 1.752703 0 P 0
L 3.2006317 2.8158819 3.2082519 2.8158819 0 P 0
L 3.2057086 3.2706693 3.3287401 3.2706693 0 P 0
L 3.2082519 2.8158819 3.2091732 2.8149606 0 P 0
L 3.2091732 2.8346456 3.2091732 2.8961811 0 P 0
L 3.2091732 2.8961811 3.2716535 2.9586614 0 P 0
L 3.219252 3.7503543 3.219252 3.8261977 2 P 0
L 3.2248425 1.6613472 3.2445583 1.681063 0 P 0
L 3.2293307 2.845 3.2293307 2.8805512 0 P 0
L 3.2293307 2.8805512 3.3448425 2.996063 0 P 0
L 3.2344825 1.752703 3.4920225 1.752703 0 P 0
L 3.2398425 3.596063 3.2423425 3.598563 0 P 0
L 3.2399212 3.6666929 3.2448425 3.6617716 0 P 0
L 3.2423425 3.598563 3.2423425 3.6592716 0 P 0
L 3.2423425 3.6592716 3.2448425 3.6617716 0 P 0
L 3.2445583 1.681063 3.271693 1.681063 0 P 0
L 3.2470472 3.4566929 3.2975474 3.4566929 0 P 0
L 3.2509842 2.9832677 3.2509842 3.0423228 0 P 0
L 3.2509842 3.0423228 3.3100381 3.1013767 0 P 0
L 3.2528425 1.661063 3.2658701 1.661063 0 P 0
L 3.2658701 1.661063 3.2726501 1.654283 0 P 0
L 3.2691732 2.7952756 3.2691732 2.8149606 0 P 0
L 3.2691732 2.8149606 3.2977401 2.8149606 0 P 0
L 3.2698425 3.785063 3.2704331 3.7844724 56 P 0
L 3.2704331 3.7503543 3.2704331 3.7844724 56 P 0
L 3.271693 1.681063 3.278793 1.673963 0 P 0
L 3.2726501 1.654283 3.4920225 1.654283 0 P 0
L 3.2755905 3.1417323 3.2771212 3.143263 0 P 0
L 3.2771212 3.143263 3.2859008 3.143263 0 P 0
L 3.278793 1.673963 3.4920225 1.673963 0 P 0
L 3.2859008 3.143263 3.3331103 3.1904725 0 P 0
L 3.2975474 3.4566929 3.3061773 3.448063 0 P 0
L 3.2977401 2.8149606 3.3708425 2.888063 0 P 0
L 3.2988425 1.971063 3.3784821 1.971063 0 P 0
L 3.3061773 3.448063 3.3588425 3.448063 0 P 0
L 3.3100381 3.1013767 3.4879914 3.1013767 0 P 0
L 3.3287401 3.2706693 3.390748 3.3326772 0 P 0
L 3.3291721 1.826063 3.4058425 1.826063 0 P 0
L 3.3308425 3.301063 3.3308425 3.3929291 56 P 0
L 3.3308425 3.3929291 3.3331103 3.3951969 56 P 0
L 3.3331103 3.1904725 3.3331103 3.2062205 0 P 0
L 3.3448425 2.996063 3.3452205 2.995685 0 P 0
L 3.3448425 3.951063 3.3498425 3.946063 0 P 0
L 3.3448425 4.2211417 3.3949212 4.2211417 56 P 0
L 3.3452205 2.995685 3.4444882 2.995685 0 P 0
L 3.3498425 3.6666929 3.4251968 3.6666929 0 P 0
L 3.3498425 3.7454331 3.3498425 3.946063 0 P 0
L 3.3588425 3.448063 3.3778425 3.467063 0 P 0
L 3.3688425 3.050063 3.3710073 3.050063 0 P 0
L 3.3708425 2.888063 3.4343071 2.888063 56 P 0
L 3.3710073 3.050063 3.3727317 3.0517874 0 P 0
L 3.3727317 3.0517874 3.4385827 3.0517874 0 P 0
L 3.3778425 3.467063 3.4031267 3.467063 0 P 0
L 3.3784821 1.971063 3.4590421 1.890503 0 P 0
L 3.3798425 1.336063 3.3831025 1.339323 0 P 0
L 3.3798425 1.386063 3.3811025 1.387323 0 P 0
L 3.3811025 1.387323 3.422518 1.387323 0 P 0
L 3.3831025 1.339323 3.4920225 1.339323 0 P 0
L 3.3921654 3.3951969 3.3934554 3.3939069 0 P 0
L 3.3928425 1.871063 3.4129675 1.850938 0 P 0
L 3.3934554 3.3334794 3.3934554 3.335458 0 P 0
L 3.3934554 3.335458 3.3934554 3.3939069 0 P 0
L 3.3934554 3.335458 3.4318504 3.297063 0 P 0
L 3.3949212 4.2211417 3.3958425 4.222063 56 P 0
L 3.4031267 3.467063 3.4148425 3.4553472 0 P 0
L 3.4048425 1.363323 3.4091721 1.363323 0 P 0
L 3.4058425 1.826063 3.4112225 1.831443 0 P 0
L 3.4068425 1.461063 3.4068425 1.4626866 56 P 0
L 3.4068425 1.4626866 3.4098425 1.4656866 56 P 0
L 3.4072822 1.411323 3.4318577 1.411323 57 P 0
L 3.4091721 1.363323 3.4134921 1.359003 0 P 0
L 3.4098425 1.4656866 3.4098425 1.468063 56 P 0
L 3.4098425 1.468063 3.4485125 1.506733 56 P 0
L 3.4108425 1.7136509 3.4632325 1.7136509 56 P 0
L 3.4112225 1.831443 3.4920225 1.831443 0 P 0
L 3.4129675 1.850938 3.4918275 1.850938 0 P 0
L 3.4134921 1.359003 3.4920225 1.359003 0 P 0
L 3.4138425 1.573063 3.4138425 1.593063 56 P 0
L 3.4138425 1.593063 3.4356925 1.614913 56 P 0
L 3.4144661 1.805063 3.4211661 1.811763 56 P 0
L 3.4148425 3.4446085 3.4148425 3.4553472 0 P 0
L 3.4148425 3.4446085 3.4238505 3.4356005 0 P 0
L 3.4211661 1.811763 3.4920225 1.811763 56 P 0
L 3.422518 1.387323 3.431148 1.378693 0 P 0
L 3.4238505 3.4313163 3.4238505 3.4356005 0 P 0
L 3.4238505 3.4313163 3.4285368 3.42663 0 P 0
L 3.4248425 3.636063 3.4251968 3.6364173 0 P 0
L 3.4251968 3.6364173 3.4251968 3.6666929 0 P 0
L 3.4251968 3.6666929 3.4649212 3.6666929 0 P 0
L 3.4285368 3.42663 3.4355354 3.42663 0 P 0
L 3.431148 1.378693 3.4920225 1.378693 0 P 0
L 3.4318504 3.297063 3.4918425 3.297063 0 P 0
L 3.4318577 1.411323 3.4448077 1.398373 57 P 0
L 3.4343071 2.888063 3.4385827 2.8923386 56 P 0
L 3.4355354 3.42663 3.4512205 3.4109449 0 P 0
L 3.4356925 1.614913 3.4920225 1.614913 56 P 0
L 3.4392507 1.870938 3.4918975 1.870938 0 P 0
L 3.444252 3.7503543 3.444252 3.783819 2 P 0
L 3.444252 3.783819 3.466496 3.806063 2 P 0
L 3.4448077 1.398373 3.4920225 1.398373 57 P 0
L 3.4485125 1.506733 3.4485125 1.5071077 56 P 0
L 3.4485125 1.5071077 3.4578878 1.516483 56 P 0
L 3.4512205 3.3951969 3.4512205 3.4109449 0 P 0
L 3.4578878 1.516483 3.4920225 1.516483 56 P 0
L 3.4590421 1.890503 3.4920225 1.890503 0 P 0
L 3.4632325 1.7136509 3.4634704 1.713413 56 P 0
L 3.4634704 1.713413 3.4919425 1.713413 56 P 0
L 3.464 3.648055 3.4698425 3.6538975 0 P 0
L 3.4649212 3.6666929 3.4698425 3.6617716 0 P 0
L 3.466496 3.806063 3.5398425 3.806063 2 P 0
L 3.4698425 3.6538975 3.4698425 3.6617716 0 P 0
L 3.4776771 2.797063 3.4848425 2.8042284 56 P 0
L 3.4848425 2.8042284 3.4848425 2.8923386 56 P 0
L 3.4848425 3.0517874 3.4848425 3.0943767 0 P 0
L 3.4848425 3.0943767 3.4918425 3.1013767 0 P 0
L 3.4879914 3.1013767 3.488147 3.1015323 0 P 0
L 3.488147 3.1015323 3.4916869 3.1015323 0 P 0
L 3.4915425 1.397893 3.4920225 1.398373 57 P 0
L 3.4916869 3.1015323 3.4918425 3.1013767 0 P 0
L 3.4918275 1.850938 3.4920225 1.851133 0 P 0
L 3.4918975 1.870938 3.4920225 1.870813 0 P 0
L 3.4919425 1.713413 3.4920225 1.713333 56 P 0
L 3.4920225 1.418063 3.5432189 1.418063 56 P 0
L 3.4920225 1.437743 3.4929425 1.438663 0 P 0
L 3.4920225 1.910183 3.5289625 1.910183 0 P 0
L 3.4920225 2.008613 3.5372925 2.008613 0 P 0
L 3.4920225 2.028293 3.5500725 2.028293 56 P 0
L 3.4920225 2.047983 3.5569225 2.047983 56 P 0
L 3.4920225 2.067663 3.5622425 2.067663 56 P 0
L 3.4920225 2.087353 3.5425525 2.087353 56 P 0
L 3.4929425 1.438663 3.5474425 1.438663 0 P 0
L 3.4954331 3.6974724 3.4954331 3.7503543 56 P 0
L 3.4954331 3.6974724 3.5318425 3.661063 56 P 0
L 3.5102756 3.3951969 3.5187232 3.4036445 0 P 0
L 3.5187232 3.4036445 3.5187232 3.4379437 0 P 0
L 3.5187232 3.4379437 3.5668425 3.486063 0 P 0
L 3.5289625 1.910183 3.5548425 1.936063 0 P 0
L 3.5298425 3.481063 3.5309449 3.4799606 0 P 0
L 3.5311023 2.8923386 3.5344602 2.8889807 0 P 0
L 3.5318425 3.660063 3.5318425 3.661063 56 P 0
L 3.5344602 2.8889807 3.5696807 2.8889807 0 P 0
L 3.5372925 2.008613 3.5548425 1.991063 0 P 0
L 3.5373384 2.9963386 3.5477716 2.9859054 0 P 0
L 3.5398425 3.806063 3.5403543 3.8065748 2 P 0
L 3.5403543 3.7151347 3.5403543 3.8065748 2 P 0
L 3.5403543 3.7151347 3.654111 3.601378 2 P 0
L 3.5403543 3.8065748 3.5406078 3.8068283 2 P 0
L 3.5406078 3.8068283 3.5696236 3.8068283 2 P 0
L 3.5425525 2.087353 3.5622425 2.067663 56 P 0
L 3.5432189 1.418063 3.5482189 1.413063 56 P 0
L 3.5474425 1.438663 3.5498425 1.441063 0 P 0
L 3.5482189 1.413063 3.5498425 1.413063 56 P 0
L 3.5500725 2.028293 3.5548425 2.033063 56 P 0
L 3.5548425 1.841063 3.5841425 1.811763 0 P 0
L 3.5548425 1.891063 3.5551225 1.890783 0 P 0
L 3.5548425 2.033063 3.5718425 2.033063 56 P 0
L 3.5551225 1.890783 3.6511825 1.890783 0 P 0
L 3.5569225 2.047983 3.5718425 2.033063 56 P 0
L 3.5622425 2.067663 3.5718425 2.058063 56 P 0
L 3.5668425 3.486063 3.6228425 3.486063 0 P 0
L 3.5688976 2.6663386 3.5885827 2.6860237 0 P 0
L 3.5696236 3.8068283 3.5898425 3.8270472 2 P 0
L 3.5696807 2.8889807 3.5885827 2.8700787 0 P 0
L 3.5718425 2.033063 3.5867625 2.047983 56 P 0
L 3.5718425 2.033063 3.5948425 2.033063 56 P 0
L 3.5718425 2.058063 3.5814425 2.067663 56 P 0
L 3.5814425 2.067663 3.6011325 2.087353 56 P 0
L 3.5814425 2.067663 3.6514625 2.067663 56 P 0
L 3.5841425 1.811763 3.6514625 1.811763 0 P 0
L 3.5867625 2.047983 3.6514625 2.047983 56 P 0
L 3.5885827 2.6860237 3.5885827 2.8700787 0 P 0
L 3.5898425 1.711063 3.5915425 1.711063 0 P 0
L 3.5898425 3.7275197 3.6085826 3.7275197 0 P 0
L 3.5898425 3.7846063 3.5898425 3.8270472 2 P 0
L 3.5898425 3.8270472 3.5898425 3.8525197 2 P 0
L 3.5898425 3.9096063 3.6185826 3.9096063 0 P 0
L 3.5908425 1.634063 3.5908425 1.662063 56 P 0
L 3.5908425 1.634063 3.6099925 1.614913 56 P 0
L 3.5948425 1.514063 3.5964661 1.514063 56 P 0
L 3.5948425 2.033063 3.5996125 2.028293 56 P 0
L 3.5964661 1.514063 3.5988861 1.516483 56 P 0
L 3.5988861 1.516483 3.6514625 1.516483 56 P 0
L 3.5996125 2.028293 3.6514625 2.028293 56 P 0
L 3.6011325 2.087353 3.6514625 2.087353 56 P 0
L 3.6038425 0.682063 3.6038425 0.7042362 56 P 0
L 3.6038425 0.7042362 3.6256693 0.726063 56 P 0
L 3.6085826 3.7275197 3.6671259 3.786063 0 P 0
L 3.6099925 1.614913 3.6514625 1.614913 56 P 0
L 3.6185826 3.9096063 3.6671259 3.861063 0 P 0
L 3.6256693 0.726063 3.6594094 0.726063 56 P 0
L 3.6428425 0.636063 3.6829133 0.636063 56 P 0
L 3.6511825 1.890783 3.6514625 1.890503 0 P 0
L 3.6514625 1.418063 3.7328425 1.418063 56 P 0
L 3.6514625 1.477113 3.6523825 1.478033 0 P 0
L 3.6514625 1.496803 3.7616527 1.496803 0 P 0
L 3.6514625 1.555853 3.7761054 1.555853 0 P 0
L 3.6514625 1.575543 3.7790428 1.575543 0 P 0
L 3.6514625 1.634593 3.6962587 1.634593 0 P 0
L 3.6514625 1.654283 3.6991961 1.654283 0 P 0
L 3.6514625 1.713333 3.7185725 1.713333 56 P 0
L 3.6514625 1.772393 3.7151562 1.772393 0 P 0
L 3.6514625 1.792073 3.7608525 1.792073 0 P 0
L 3.6514625 1.910183 3.7089625 1.910183 0 P 0
L 3.6514625 2.008613 3.7072925 2.008613 0 P 0
L 3.6523825 1.478033 3.8318125 1.478033 0 P 0
L 3.654111 3.601378 4.0570867 3.601378 2 P 0
L 3.6594094 0.7234878 3.6594094 0.726063 56 P 0
L 3.6671259 3.786063 3.6681102 3.786063 0 P 0
L 3.6671259 3.861063 3.6681102 3.861063 0 P 0
L 3.6888425 3.3295591 3.7013464 3.342063 56 P 0
L 3.6938425 3.1176299 3.699748 3.1176299 56 P 0
L 3.6962587 1.634593 3.7057887 1.625063 0 P 0
L 3.6991961 1.654283 3.7124161 1.641063 0 P 0
L 3.699748 3.1176299 3.7173858 3.0999921 56 P 0
L 3.6998425 3.751063 3.7015748 3.7527953 0 P 0
L 3.6998425 3.836063 3.7015748 3.8377953 0 P 0
L 3.7013464 3.342063 3.7448425 3.342063 56 P 0
L 3.7015748 3.7527953 3.7015748 3.786063 0 P 0
L 3.7015748 3.786063 3.7028248 3.784813 0 P 0
L 3.7015748 3.8377953 3.7015748 3.861063 0 P 0
L 3.7015748 3.861063 3.7028248 3.859813 0 P 0
L 3.702441 3.2610879 3.7324161 3.291063 2 P 0
L 3.7028248 3.784813 3.771309 3.784813 0 P 0
L 3.7028248 3.859813 3.771309 3.859813 0 P 0
L 3.7057887 1.625063 3.770612 1.625063 0 P 0
L 3.7072925 2.008613 3.7198425 1.996063 0 P 0
L 3.7089625 1.910183 3.7198425 1.921063 0 P 0
L 3.7124161 1.641063 3.7498425 1.641063 0 P 0
L 3.7151562 1.772393 3.7198425 1.7677067 0 P 0
L 3.7167716 0.636063 3.7167716 0.712559 0 P 0
L 3.7167716 0.712559 3.7302756 0.726063 0 P 0
L 3.7173858 3.0940866 3.7173858 3.0999921 56 P 0
L 3.7173858 3.0940866 3.7178425 3.0936299 56 P 0
L 3.7178425 3.072063 3.7178425 3.0936299 56 P 0
L 3.7185725 1.713333 3.7188425 1.713063 56 P 0
L 3.7198425 1.766063 3.7198425 1.7677067 0 P 0
L 3.7242925 1.674513 3.7248425 1.675063 0 P 0
L 3.7302756 0.726063 3.7302756 0.7319685 0 P 0
L 3.7302756 0.7319685 3.7378346 0.7244095 0 P 0
L 3.7324161 3.291063 3.8122689 3.291063 2 P 0
L 3.7378346 0.7244095 3.8956693 0.7244095 0 P 0
L 3.7498425 1.641063 3.7738632 1.6650837 0 P 0
L 3.7608525 1.792073 3.8048425 1.836063 0 P 0
L 3.7616527 1.496803 3.7759127 1.511063 0 P 0
L 3.7698425 3.2003465 3.7698425 3.2011339 56 P 0
L 3.7698425 3.2003465 3.777441 3.192748 56 P 0
L 3.770612 1.625063 3.8048425 1.6592935 0 P 0
L 3.771309 3.784813 3.772559 3.783563 0 P 0
L 3.771309 3.859813 3.772559 3.858563 0 P 0
L 3.772559 3.683563 3.7948733 3.683563 0 P 0
L 3.772559 3.758563 3.8257189 3.758563 56 P 0
L 3.772559 3.808563 3.8273425 3.808563 0 P 0
L 3.7738632 1.6650837 3.7738632 1.6661021 0 P 0
L 3.7759127 1.511063 3.8648425 1.511063 0 P 0
L 3.7761054 1.555853 3.7958955 1.5360629 0 P 0
L 3.777441 3.192748 3.7782284 3.192748 56 P 0
L 3.7778425 4.023063 3.7788425 4.023063 56 P 0
L 3.7782284 3.192748 3.8619134 3.109063 56 P 0
L 3.7788425 4.023063 3.7794803 4.0237008 56 P 0
L 3.7790428 1.575543 3.7885228 1.566063 0 P 0
L 3.7794803 4.0237008 3.8084646 4.0237008 56 P 0
L 3.7885228 1.566063 3.8948425 1.566063 0 P 0
L 3.7948733 3.683563 3.799015 3.6877047 0 P 0
L 3.7958955 1.5360629 3.9248424 1.5360629 0 P 0
L 3.799015 3.6877047 3.8008837 3.6877047 0 P 0
L 3.8008837 3.6877047 3.8714567 3.7582777 0 P 0
L 3.8038425 1.691063 3.8048425 1.690063 0 P 0
L 3.8048425 1.6592935 3.8048425 1.690063 0 P 0
L 3.8048425 1.836063 3.8048425 1.840063 0 P 0
L 3.8122689 3.291063 3.9698425 3.1334894 2 P 0
L 3.8257189 3.758563 3.8292189 3.762063 56 P 0
L 3.8273425 3.808563 3.8298425 3.806063 0 P 0
L 3.8292189 3.762063 3.8308425 3.762063 56 P 0
L 3.8318125 1.478033 3.8348425 1.481063 0 P 0
L 3.8619134 3.109063 3.8808425 3.109063 56 P 0
L 3.8714567 3.7582777 3.8714567 4.0237008 0 P 0
L 3.8956693 0.7244095 3.9797272 0.8084674 0 P 0
L 3.9029528 3.7435531 3.9029528 4.0237008 0 P 0
L 3.9029528 3.7435531 3.9588012 3.6877047 0 P 0
L 3.9114214 1.5996232 3.9254848 1.5996232 56 P 0
L 3.9114214 1.6196232 3.9115001 1.6195445 56 P 0
L 3.9114214 1.6396232 3.9115001 1.6395445 56 P 0
L 3.9114214 1.6596232 3.9574027 1.6596232 56 P 0
L 3.9114214 1.7796232 3.9197164 1.7796232 0 P 0
L 3.9115001 1.6195445 3.964361 1.6195445 56 P 0
L 3.9115001 1.6395445 3.969361 1.6395445 56 P 0
L 3.9197164 1.7796232 3.9206377 1.7805445 0 P 0
L 3.9206377 1.7805445 3.9206377 1.7918582 0 P 0
L 3.9206377 1.7918582 3.9448425 1.816063 0 P 0
L 3.9248424 1.5360629 3.9248425 1.536063 0 P 0
L 3.9254848 1.5996232 3.9255635 1.5995445 56 P 0
L 3.9255635 1.5995445 3.951361 1.5995445 56 P 0
L 3.951361 1.5995445 3.9698425 1.581063 56 P 0
L 3.9574027 1.6596232 3.9688425 1.671063 56 P 0
L 3.9588012 3.6877047 3.9606699 3.6877047 0 P 0
L 3.9598425 2.725063 3.9598425 2.7806299 56 P 0
L 3.9598425 2.725063 3.9608425 2.724063 56 P 0
L 3.9598425 2.8514961 3.9598425 2.9485827 2 P 0
L 3.9598425 2.8514961 4.0648425 2.8514961 2 P 0
L 3.9598425 2.9485827 4.0398425 3.0285827 2 P 0
L 3.9606699 3.6877047 3.9648116 3.683563 0 P 0
L 3.964361 1.6195445 3.9948425 1.589063 56 P 0
L 3.9648116 3.683563 3.9871259 3.683563 0 P 0
L 3.969361 1.6395445 4.0336945 1.575211 56 P 0
L 3.9698425 1.552063 3.9698425 1.581063 56 P 0
L 3.9698425 3.0987174 3.9698425 3.1334894 2 P 0
L 3.9698425 3.0987174 4.0293078 3.0392521 2 P 0
L 3.9797272 0.8084674 3.9797272 0.8906186 0 P 0
L 3.9871259 3.708563 4.0358481 3.708563 0 P 0
L 3.9871259 3.733563 4.085689 3.733563 0 P 0
L 3.9871259 3.758563 3.9872676 3.7587047 59 P 0
L 3.9871259 3.783563 4.0393425 3.783563 56 P 0
L 3.9872676 3.7587047 4.0929173 3.7587047 59 P 0
L 3.9948425 1.551063 3.9948425 1.589063 56 P 0
L 3.9968425 1.711063 4.0254027 1.7396232 56 P 0
L 4.0254027 1.7396232 4.0689017 1.7396232 56 P 0
L 4.0293078 3.0392521 4.0311417 3.0392521 2 P 0
L 4.0311417 3.0392521 4.0398425 3.0305513 2 P 0
L 4.0336945 1.547211 4.0336945 1.575211 56 P 0
L 4.0336945 1.547211 4.0348425 1.546063 56 P 0
L 4.0358481 3.708563 4.0498425 3.6945686 0 P 0
L 4.0393425 3.783563 4.0398425 3.784063 56 P 0
L 4.0398425 3.0285827 4.0398425 3.029567 2 P 0
L 4.0398425 3.029567 4.0398425 3.0305513 2 P 0
L 4.0398425 3.029567 4.0960631 3.029567 2 P 0
L 4.0398425 3.0925591 4.0528901 3.1056067 56 P 0
L 4.0498425 3.665063 4.0498425 3.6945686 0 P 0
L 4.0528901 3.1056067 4.0528901 3.1191106 56 P 0
L 4.0528901 3.1191106 4.0688425 3.135063 56 P 0
L 4.0570867 3.601378 4.109252 3.6535433 2 P 0
L 4.0624043 2.595343 4.1878784 2.4698689 0 P 0
L 4.0648425 1.511063 4.0648425 1.5987019 0 P 0
L 4.0648425 1.5987019 4.0657638 1.5996232 0 P 0
L 4.0648425 1.7805445 4.0648425 1.796063 0 P 0
L 4.0648425 1.7805445 4.0657638 1.7796232 0 P 0
L 4.0648425 2.722063 4.0648425 2.7806299 56 P 0
L 4.0648425 2.8514961 4.0740945 2.8422441 2 P 0
L 4.0657638 1.5996232 4.0689017 1.5996232 0 P 0
L 4.0657638 1.7796232 4.0689017 1.7796232 0 P 0
L 4.0689017 1.6196232 4.1172823 1.6196232 0 P 0
L 4.0689017 1.6396232 4.1179981 1.6396232 0 P 0
L 4.0689017 1.6596232 4.1261562 1.6596232 0 P 0
L 4.0689017 1.6796232 4.1237791 1.6796232 56 P 0
L 4.0689017 1.7596232 4.1134083 1.7596232 0 P 0
L 4.0740945 2.8422441 4.1498425 2.8422441 2 P 0
L 4.085689 3.733563 4.1126772 3.7065748 0 P 0
L 4.0858425 3.892063 4.1046295 3.873276 56 P 0
L 4.0929173 3.7587047 4.1048425 3.7706299 59 P 0
L 4.0960631 3.029567 4.1098425 3.0433464 2 P 0
L 4.1046295 3.8417091 4.1046295 3.873276 56 P 0
L 4.1046295 3.8417091 4.1048425 3.8414961 56 P 0
L 4.1048425 3.7706299 4.106811 3.7725984 2 P 0
L 4.106811 3.7725984 4.1928739 3.7725984 2 P 0
L 4.109252 3.6535433 4.3100394 3.6535433 2 P 0
L 4.1098425 3.0433464 4.1098425 3.0441338 2 P 0
L 4.1098425 3.0441338 4.1648425 3.0441338 2 P 0
L 4.1098425 3.0779921 4.1098425 3.126063 56 P 0
L 4.1098425 3.126063 4.1136945 3.129915 56 P 0
L 4.1126772 3.701063 4.1126772 3.7065748 0 P 0
L 4.1134083 1.7596232 4.121063 1.7519685 0 P 0
L 4.1136945 3.129915 4.1136945 3.133915 56 P 0
L 4.1136945 3.133915 4.1148425 3.135063 56 P 0
L 4.1172823 1.6196232 4.1358426 1.6010629 0 P 0
L 4.1179981 1.6396232 4.1265583 1.631063 0 P 0
L 4.1203866 3.5941508 4.1413948 3.5941508 0 P 0
L 4.121063 1.7519685 4.133937 1.7519685 0 P 0
L 4.1237791 1.6796232 4.1302189 1.686063 56 P 0
L 4.1261562 1.6596232 4.1347164 1.651063 0 P 0
L 4.1265583 1.631063 4.14262 1.631063 0 P 0
L 4.1302189 1.686063 4.1318425 1.686063 56 P 0
L 4.133937 1.7519685 4.1348425 1.751063 0 P 0
L 4.1347164 1.651063 4.1348425 1.651063 0 P 0
L 4.1348425 1.751063 4.1713386 1.751063 0 P 0
L 4.1358426 1.6010629 4.1798425 1.6010629 0 P 0
L 4.1413948 3.5941508 4.1505905 3.6033465 0 P 0
L 4.14262 1.631063 4.1500598 1.6236232 0 P 0
L 4.1498425 2.7898819 4.1500236 2.790063 2 P 0
L 4.1500236 2.790063 4.1761267 2.790063 2 P 0
L 4.1500598 1.6236232 4.2438987 1.6236232 0 P 0
L 4.1528425 3.135063 4.1539905 3.133915 56 P 0
L 4.1539905 3.127915 4.1539905 3.133915 56 P 0
L 4.1539905 3.127915 4.1648425 3.117063 56 P 0
L 4.1648425 3.0441338 4.2198425 3.0441338 2 P 0
L 4.1648425 3.0779921 4.1648425 3.117063 56 P 0
L 4.1670079 3.701063 4.1670079 3.7065748 2 P 0
L 4.1670079 3.7065748 4.1711812 3.7107481 2 P 0
L 4.1711812 3.7107481 4.176693 3.7107481 2 P 0
L 4.1713386 1.751063 4.7277559 2.3074803 0 P 0
L 4.1761267 2.790063 4.1878425 2.8017788 2 P 0
L 4.176693 3.7107481 4.1948425 3.7288976 2 P 0
L 4.1798425 1.6010629 4.1798425 1.601063 0 P 0
L 4.1805146 2.595343 4.2436362 2.6584646 0 P 0
L 4.1878425 2.8017788 4.1878425 2.820063 2 P 0
L 4.1878425 2.820063 4.2066378 2.8388583 2 P 0
L 4.1878784 2.4698689 4.9120209 2.4698689 0 P 0
L 4.1928739 3.7725984 4.1948425 3.774567 2 P 0
L 4.1948425 3.7288976 4.1948425 3.774567 2 P 0
L 4.1948425 3.774567 4.2533465 3.774567 2 P 0
L 4.1948425 3.8375591 4.1948425 3.884063 56 P 0
L 4.2049212 3.6033465 4.2755905 3.6033465 0 P 0
L 4.2066378 2.8388583 4.2222047 2.8388583 2 P 0
L 4.2088425 3.135063 4.2094094 3.1356299 56 P 0
L 4.2088425 3.135063 4.2099905 3.133915 56 P 0
L 4.2094094 3.1356299 4.2094094 3.246063 56 P 0
L 4.2099905 3.129915 4.2099905 3.133915 56 P 0
L 4.2099905 3.129915 4.2198425 3.120063 56 P 0
L 4.2198425 3.0441338 4.2748425 3.0441338 2 P 0
L 4.2198425 3.0779921 4.2198425 3.120063 56 P 0
L 4.2222047 2.8388583 4.2348425 2.8514961 2 P 0
L 4.2348425 2.725063 4.2348425 2.7806299 2 P 0
L 4.2348425 2.8514961 4.3398425 2.8514961 2 P 0
L 4.2436362 2.6584646 4.8937008 2.6584646 0 P 0
L 4.2438987 1.6236232 4.9277558 2.3074803 0 P 0
L 4.2533465 3.774567 4.2548425 3.776063 2 P 0
L 4.2728425 3.0799921 4.2728425 3.135063 56 P 0
L 4.2728425 3.0799921 4.2748425 3.0779921 56 P 0
L 4.2748425 3.0441338 4.3348425 3.0441338 2 P 0
L 4.2802756 3.246063 4.4498425 3.246063 2 P 0
L 4.2986248 2.595343 4.8731609 2.595343 0 P 0
L 4.3100394 3.6535433 4.3316929 3.6318898 2 P 0
L 4.3316929 3.6043307 4.3316929 3.6318898 2 P 0
L 4.3316929 3.6043307 4.3326771 3.6033465 2 P 0
L 4.3326771 3.6033465 4.6771653 3.6033465 2 P 0
L 4.3338425 3.135063 4.3348425 3.134063 56 P 0
L 4.3348425 3.0441338 4.3948425 3.0441338 2 P 0
L 4.3348425 3.0779921 4.3348425 3.134063 56 P 0
L 4.3398425 2.725063 4.3398425 2.7806299 2 P 0
L 4.3398425 2.8514961 4.3918425 2.8514961 2 P 0
L 4.3878425 4.206063 4.4329134 4.206063 56 P 0
L 4.3918425 2.8514961 4.4010945 2.8422441 2 P 0
L 4.3948425 3.0441338 4.4548425 3.0441338 2 P 0
L 4.3948425 3.0779921 4.3948425 3.0787795 56 P 0
L 4.3948425 3.0787795 4.402441 3.086378 56 P 0
L 4.4010945 2.8422441 4.4348425 2.8422441 2 P 0
L 4.402441 3.086378 4.4032284 3.086378 56 P 0
L 4.4032284 3.086378 4.4318425 3.1149921 56 P 0
L 4.4318425 3.1149921 4.4318425 3.135063 56 P 0
L 4.4348425 2.7898819 4.5036614 2.7898819 2 P 0
L 4.4498425 3.246063 4.5398425 3.156063 2 P 0
L 4.4548425 3.0441338 4.4573149 3.0466062 2 P 0
L 4.4548425 3.0779921 4.4548425 3.108063 56 P 0
L 4.4548425 3.108063 4.4766945 3.129915 56 P 0
L 4.4573149 3.0466062 4.4748968 3.0466062 2 P 0
L 4.4748968 3.0466062 4.5398425 3.1115519 2 P 0
L 4.4766945 3.129915 4.4766945 3.133915 56 P 0
L 4.4766945 3.133915 4.4778425 3.135063 56 P 0
L 4.5398425 2.9040551 4.5398425 3.1115519 0 P 0
L 4.5398425 2.9040551 4.7293307 2.7145669 0 P 0
L 4.5398425 3.1115519 4.5398425 3.156063 0 P 0
L 4.5667716 4.206063 4.6526771 4.206063 0 P 0
L 4.6526771 4.206063 4.6526772 4.2060629 0 P 0
L 4.6526772 4.121063 4.6526772 4.2060629 0 P 0
L 4.6771653 3.6033465 4.7686835 3.5118283 2 P 0
L 4.7070078 4.206063 4.7070078 4.2115748 2 P 0
L 4.7070078 4.2115748 4.7111811 4.2157481 2 P 0
L 4.7070079 4.121063 4.7121385 4.1159324 0 P 0
L 4.7111811 4.2157481 4.7166929 4.2157481 2 P 0
L 4.7121385 4.1159324 4.7547119 4.1159324 0 P 0
L 4.7166929 4.2157481 4.7770078 4.276063 2 P 0
L 4.7293307 2.7145669 4.9206693 2.7145669 0 P 0
L 4.7686835 3.5118283 5.2740772 3.5118283 2 P 0
L 4.7770078 4.276063 5.2468425 4.276063 2 P 0
L 4.7942913 2.8080709 4.7952755 2.8090551 0 P 0
L 4.7942913 2.8080709 4.9094487 2.8080709 0 P 0
L 4.8731609 2.595343 5.0610236 2.4074803 0 P 0
L 4.8848427 2.7893701 4.8877954 2.7864174 0 P 0
L 4.8937008 2.6584646 5.2116142 2.3405512 0 P 0
L 4.9094487 2.8080709 4.9094488 2.8080708 0 P 0
L 4.9094488 3.9616142 4.9094488 4.1181102 0 P 0
L 4.9094488 4.1181102 4.9108425 4.1195039 0 P 0
L 4.9108425 4.1195039 4.9108425 4.203063 0 P 0
L 4.9108425 4.203063 4.9549134 4.203063 56 P 0
L 4.9120209 2.4698689 4.992126 2.3897638 0 P 0
L 4.9206693 2.7145669 5.3277559 2.3074803 0 P 0
L 4.9277558 2.3074803 4.9277559 2.3074803 0 P 0
L 4.9277559 1.0074803 4.992126 1.0718504 0 P 0
L 4.9549134 4.203063 4.9579134 4.206063 56 P 0
L 4.992126 1.0718504 4.992126 2.3897638 0 P 0
L 5.0610236 1.0742126 5.0610236 2.4074803 0 P 0
L 5.0610236 1.0742126 5.1277559 1.0074803 0 P 0
L 5.0917716 4.206063 5.2126771 4.206063 0 P 0
L 5.2116142 1.1338585 5.2116142 2.3405512 0 P 0
L 5.2116142 1.1338585 5.3277559 1.0177168 0 P 0
L 5.2126771 4.1260631 5.2126771 4.206063 0 P 0
L 5.2126771 4.1260631 5.2126772 4.126063 0 P 0
L 5.2468425 4.276063 5.2670078 4.2558977 2 P 0
L 5.2670078 4.206063 5.2670078 4.2558977 2 P 0
L 5.2670078 4.206063 5.2898425 4.206063 2 P 0
L 5.2670079 4.0888976 5.2670079 4.126063 0 P 0
L 5.2740772 3.5118283 5.2748425 3.511063 2 P 0
L 5.2748425 3.511063 5.2748425 3.5121454 2 P 0
L 5.2748425 3.5121454 5.2998425 3.5371454 2 P 0
L 5.2898425 4.206063 5.2998425 4.196063 2 P 0
L 5.2998425 3.5371454 5.2998425 4.196063 2 P 0
L 5.3277559 1.0074803 5.3277559 1.0177168 0 P 0
L 5.5778425 2.214063 5.6128425 2.214063 0 P 0
L 5.6128425 2.214063 5.6348425 2.236063 0 P 0
L 5.636811 3.3572835 5.6369212 3.3571733 2 P 0
L 5.6369212 3.320756 5.6369212 3.3571733 2 P 0
L 5.6369212 3.320756 5.6555118 3.3021654 2 P 0
L 5.6555118 3.3021654 5.8120079 3.3021654 2 P 0
L 5.6767717 3.3622047 5.6767717 3.5459922 56 P 0
L 5.6767717 3.5459922 5.6768425 3.546063 56 P 0
L 5.7220472 3.7838583 5.7220472 3.8444882 2 P 0
L 5.7220472 3.7838583 5.8048425 3.701063 2 P 0
L 5.7253937 4.0334646 5.8290944 4.1371654 2 P 0
L 5.7338425 3.3612205 5.7338425 3.556063 56 P 0
L 5.8048425 3.701063 5.8801181 3.701063 2 P 0
L 5.8120079 3.3021654 5.8120079 3.3612205 0 P 0
L 5.8120079 3.3021654 5.847441 3.3021654 2 P 0
L 5.8290944 4.1371654 6.2073228 4.1371654 2 P 0
L 5.847441 3.3021654 5.9948425 3.4495669 2 P 0
L 5.8801181 3.701063 5.8879921 3.708937 2 P 0
L 5.8879921 3.701063 5.8879921 3.708937 2 P 0
L 5.9948425 3.4495669 5.9948425 3.552063 2 P 0
L 5.9948425 3.552063 5.9988425 3.556063 2 P 0
L 5.9988425 3.556063 6.0356772 3.556063 2 P 0
L 6.0048425 2.3388977 6.0103543 2.3388977 0 P 0
L 6.0048425 2.3932284 6.0048425 2.434063 56 P 0
L 6.0103543 2.3388977 6.0409764 2.3695198 0 P 0
L 6.0316929 3.701063 6.0778425 3.701063 2 P 0
L 6.0409764 2.3695198 6.0563701 2.3695198 0 P 0
L 6.0488425 2.171063 6.0933464 2.171063 56 P 0
L 6.0563701 2.3695198 6.0648425 2.3779922 0 P 0
L 6.0648425 2.3441339 6.0679134 2.341063 0 P 0
L 6.0679134 2.341063 6.1574016 2.341063 0 P 0
L 6.0778425 3.701063 6.1198425 3.743063 2 P 0
L 6.0900079 3.556063 6.0900079 3.5615748 2 P 0
L 6.0900079 3.5615748 6.0941812 3.5657481 2 P 0
L 6.0941812 3.554063 6.0941812 3.5657481 2 P 0
L 6.0941812 3.554063 6.1508425 3.554063 2 P 0
L 6.1198425 3.743063 6.1198425 3.8198425 2 P 0
L 6.1228425 2.4338976 6.1283543 2.4338976 0 P 0
L 6.1228425 2.4882283 6.1870471 2.4882283 2 P 0
L 6.1283543 2.4338976 6.1385276 2.4237243 0 P 0
L 6.1385276 2.4182125 6.1385276 2.4237243 0 P 0
L 6.1385276 2.4182125 6.1471429 2.4095972 0 P 0
L 6.1471429 2.3982835 6.1471429 2.4095972 0 P 0
L 6.1471429 2.3982835 6.1543634 2.391063 0 P 0
L 6.1508425 3.554063 6.1628425 3.566063 2 P 0
L 6.1543634 2.391063 6.1574016 2.391063 0 P 0
L 6.1563385 2.171063 6.1563385 2.2399999 0 P 0
L 6.1563385 2.2399999 6.1574016 2.241063 0 P 0
L 6.1574016 2.291063 6.1849607 2.291063 0 P 0
L 6.1574016 2.391063 6.1849607 2.391063 0 P 0
L 6.1628425 3.566063 6.2029921 3.566063 2 P 0
L 6.1849607 2.291063 6.2348425 2.2411812 0 P 0
L 6.1849607 2.391063 6.2449607 2.451063 0 P 0
L 6.1870471 2.4882283 6.1998818 2.501063 2 P 0
L 6.1979921 3.5884481 6.1979921 3.701063 2 P 0
L 6.1979921 3.5884481 6.2001968 3.5862434 2 P 0
L 6.1979921 3.701063 6.1979921 3.7058195 2 P 0
L 6.1979921 3.7058195 6.2007874 3.7086148 2 P 0
L 6.1998818 2.501063 6.2848425 2.501063 2 P 0
L 6.2001968 3.5688583 6.2001968 3.5862434 2 P 0
L 6.2001968 3.5688583 6.2029921 3.566063 2 P 0
L 6.2007874 3.7086148 6.2263313 3.7086148 2 P 0
L 6.2073228 4.1371654 6.253937 4.0905512 2 P 0
L 6.2263313 3.7086148 6.253937 3.7362205 2 P 0
L 6.2348425 2.1288977 6.2390158 2.133071 2 P 0
L 6.2348425 2.1832284 6.2348425 2.2411812 0 P 0
L 6.2390158 2.133071 6.2649607 2.133071 2 P 0
L 6.2449607 2.451063 6.3126772 2.451063 0 P 0
L 6.253937 2.6732284 6.253937 2.7559055 2 P 0
L 6.253937 2.6732284 6.2711024 2.656063 2 P 0
L 6.253937 2.7559055 6.3720472 2.7559055 2 P 0
L 6.253937 2.8267717 6.253937 2.9094488 2 P 0
L 6.253937 3.7362205 6.253937 4.0905512 2 P 0
L 6.2649607 2.133071 6.281496 2.1496063 2 P 0
L 6.2711024 2.656063 6.3279134 2.656063 2 P 0
L 6.2748425 2.391063 6.3522834 2.391063 56 P 0
L 6.281496 2.1496063 6.281496 2.1929135 2 P 0
L 6.281496 2.1929135 6.281496 2.2716535 2 P 0
L 6.281496 2.1929135 6.2931299 2.1812796 2 P 0
L 6.281496 2.2716535 6.3009055 2.291063 2 P 0
L 6.2824161 3.226063 6.3024161 3.246063 0 P 0
L 6.2848425 2.501063 6.3279134 2.501063 2 P 0
L 6.2931299 2.1812796 6.4246259 2.1812796 2 P 0
L 6.2948425 3.701063 6.3416929 3.701063 2 P 0
L 6.3009055 2.291063 6.3522834 2.291063 2 P 0
L 6.3024161 3.246063 6.3431267 3.246063 0 P 0
L 6.3048425 3.121063 6.410433 3.121063 0 P 0
L 6.3094161 3.199063 6.3114161 3.201063 0 P 0
L 6.3114161 3.201063 6.3318621 3.201063 0 P 0
L 6.3198425 1.3750394 6.3198425 1.4601181 2 P 0
L 6.3198425 1.3750394 6.3641732 1.3307087 2 P 0
L 6.3198425 1.8420079 6.3690551 1.8420079 0 P 0
L 6.3279134 2.501063 6.3279134 2.556063 2 P 0
L 6.3279134 2.556063 6.3279134 2.611063 2 P 0
L 6.3279134 2.611063 6.3279134 2.656063 2 P 0
L 6.3318621 3.201063 6.3620196 3.2312205 0 P 0
L 6.3348425 2.1106299 6.3954094 2.1106299 56 P 0
L 6.3348425 3.266063 6.3348425 3.2697769 0 P 0
L 6.3348425 3.266063 6.3363732 3.2675937 0 P 0
L 6.3363732 3.2675937 6.3363732 3.2871606 0 P 0
L 6.3363732 3.2871606 6.3594757 3.3102631 0 P 0
L 6.3398425 3.151063 6.3412598 3.1524803 0 P 0
L 6.3412598 3.1524803 6.3883268 3.1524803 0 P 0
L 6.3431267 3.246063 6.3479692 3.2509055 0 P 0
L 6.3466929 3.566063 6.3810237 3.566063 2 P 0
L 6.3479692 3.2509055 6.3883268 3.2509055 0 P 0
L 6.3522834 2.241063 6.4683464 2.241063 0 P 0
L 6.3522834 2.341063 6.3971259 2.341063 0 P 0
L 6.3547483 3.3311384 6.356241 3.3296457 0 P 0
L 6.356241 3.3296457 6.3883268 3.3296457 0 P 0
L 6.3594757 3.3102631 6.3880243 3.3102631 0 P 0
L 6.3617717 2.501063 6.3978425 2.501063 56 P 0
L 6.3617717 2.556063 6.3968425 2.556063 56 P 0
L 6.3617717 2.611063 6.3968425 2.611063 56 P 0
L 6.3617717 2.656063 6.3978425 2.656063 56 P 0
L 6.3620196 3.2312205 6.3883268 3.2312205 0 P 0
L 6.3641732 1.3307087 6.6673228 1.3307087 2 P 0
L 6.3670079 2.451063 6.3690079 2.453063 56 P 0
L 6.3690079 2.453063 6.3988425 2.453063 56 P 0
L 6.3690551 1.8420079 6.4816142 1.954567 0 P 0
L 6.3720472 2.7559055 6.4547244 2.7559055 2 P 0
L 6.3720472 2.8267717 6.3720472 2.9094488 2 P 0
L 6.3799607 3.3099606 6.3883268 3.3099606 0 P 0
L 6.3810237 3.566063 6.4143701 3.5994094 2 P 0
L 6.3880243 3.3102631 6.3883268 3.3099606 0 P 0
L 6.3954094 2.1106299 6.3958425 2.111063 56 P 0
L 6.3968425 2.611063 6.3978425 2.610063 56 P 0
L 6.3971259 2.341063 6.4356299 2.302559 0 P 0
L 6.3978425 2.656063 6.3988425 2.657063 56 P 0
L 6.4098425 3.371063 6.4248425 3.371063 0 P 0
L 6.410433 3.121063 6.4203149 3.1309449 0 P 0
L 6.4143701 3.5994094 6.4143701 3.726378 2 P 0
L 6.4143701 3.726378 6.4902756 3.8022835 2 P 0
L 6.4203149 3.1309449 6.4203149 3.1500197 0 P 0
L 6.4203149 3.3321063 6.4212362 3.331185 0 P 0
L 6.4212362 3.3146693 6.4212362 3.331185 0 P 0
L 6.4212362 3.3146693 6.4448425 3.291063 0 P 0
L 6.4246259 2.1812796 6.4248425 2.181063 2 P 0
L 6.4248425 2.181063 6.5478478 2.181063 2 P 0
L 6.4248425 3.371063 6.44 3.3559055 0 P 0
L 6.4356299 2.302559 6.4698425 2.302559 0 P 0
L 6.4394094 3.0264961 6.4394094 3.071063 56 P 0
L 6.4394094 3.0264961 6.4568425 3.009063 56 P 0
L 6.4398425 3.191063 6.44 3.1909055 0 P 0
L 6.44 3.1500197 6.44 3.1909055 0 P 0
L 6.44 3.3321063 6.44 3.3559055 0 P 0
L 6.4475772 3.396063 6.459685 3.3839552 0 P 0
L 6.4547244 2.7559055 6.4901575 2.7913386 2 P 0
L 6.459685 3.3321063 6.459685 3.3839552 0 P 0
L 6.4598425 3.1500197 6.4605433 3.1493189 0 P 0
L 6.4598425 3.1500197 6.4607638 3.150941 0 P 0
L 6.4605433 3.1267008 6.4605433 3.1493189 0 P 0
L 6.4605433 3.1267008 6.5102756 3.0769685 0 P 0
L 6.4607638 3.150941 6.4607638 3.1646241 0 P 0
L 6.4607638 3.1646241 6.4694783 3.1733386 0 P 0
L 6.4683464 2.241063 6.4698425 2.2395669 0 P 0
L 6.4694783 3.1733386 6.4892619 3.1733386 0 P 0
L 6.4698425 2.302559 6.6431101 2.302559 0 P 0
L 6.4768425 3.231063 6.477 3.2312205 56 P 0
L 6.477 3.2312205 6.5113582 3.2312205 56 P 0
L 6.4793701 3.1437794 6.4794488 3.1437007 58 P 0
L 6.4793701 3.3321063 6.4793701 3.4255906 0 P 0
L 6.4793701 3.4255906 6.4798425 3.426063 0 P 0
L 6.4794488 3.1327559 6.4794488 3.1437007 58 P 0
L 6.4794488 3.1327559 6.4871417 3.125063 58 P 0
L 6.4816142 1.954567 6.5198425 1.954567 0 P 0
L 6.4871417 3.125063 6.5514661 3.125063 58 P 0
L 6.4892619 3.1733386 6.4904351 3.1721654 0 P 0
L 6.4901575 2.7913386 6.6691732 2.7913386 2 P 0
L 6.4902756 3.8022835 6.5657087 3.8022835 2 P 0
L 6.4904351 3.1721654 6.5113582 3.1721654 0 P 0
L 6.5098425 3.456063 6.5113582 3.4545473 0 P 0
L 6.5102756 2.9680709 6.5102756 3.071063 2 P 0
L 6.5102756 2.9680709 6.5492126 2.9291339 2 P 0
L 6.5102756 3.071063 6.5102756 3.0769685 0 P 0
L 6.5102756 3.071063 6.5122047 3.0729921 0 P 0
L 6.5113582 3.1918504 6.6041339 3.1918504 0 P 0
L 6.5113582 3.2115354 6.5527952 3.2115354 0 P 0
L 6.5113582 3.3296457 6.5113582 3.4545473 0 P 0
L 6.5122047 3.0729921 6.5848425 3.0729921 0 P 0
L 6.5198425 1.9535827 6.5198425 1.954567 0 P 0
L 6.5198425 1.9535827 6.5423622 1.931063 0 P 0
L 6.5198425 2.0175591 6.5333464 2.031063 0 P 0
L 6.5333464 2.031063 6.6374016 2.031063 0 P 0
L 6.5423622 1.931063 6.6374016 1.931063 0 P 0
L 6.5478478 2.181063 6.5872572 2.2204724 2 P 0
L 6.5488425 1.531063 6.6294094 1.531063 56 P 0
L 6.5492126 2.9291339 6.6397637 2.9291339 2 P 0
L 6.5514661 3.125063 6.55597 3.1295669 58 P 0
L 6.5527952 3.2115354 6.6048425 3.2635827 0 P 0
L 6.55597 3.1295669 6.6048425 3.1295669 58 P 0
L 6.5657087 3.8022835 6.5694882 3.806063 2 P 0
L 6.5694882 3.806063 6.7348425 3.806063 2 P 0
L 6.5848425 3.0391338 6.6197717 3.0391338 56 P 0
L 6.5872572 2.2204724 6.7106299 2.2204724 2 P 0
L 6.6018425 1.777063 6.6028425 1.776063 56 P 0
L 6.6028425 1.612063 6.6038425 1.611063 56 P 0
L 6.6028425 1.672063 6.6038425 1.671063 56 P 0
L 6.6028425 1.722063 6.6038425 1.721063 56 P 0
L 6.6028425 1.776063 6.6429133 1.776063 56 P 0
L 6.6038425 1.611063 6.6429133 1.611063 56 P 0
L 6.6038425 1.671063 6.6429133 1.671063 56 P 0
L 6.6038425 1.721063 6.6429133 1.721063 56 P 0
L 6.6041339 3.1918504 6.6048425 3.192559 0 P 0
L 6.6048425 3.1295669 6.6051969 3.1299213 58 P 0
L 6.6048425 3.192559 6.7049842 3.192559 0 P 0
L 6.6048425 3.2635827 6.6048425 3.264567 0 P 0
L 6.6048425 3.264567 6.7049842 3.264567 0 P 0
L 6.6048425 3.3275591 6.6183464 3.341063 56 P 0
L 6.6051969 3.1299213 6.6476378 3.1299213 58 P 0
L 6.6078425 2.176063 6.6502756 2.176063 56 P 0
L 6.6183464 3.341063 6.6488425 3.341063 56 P 0
L 6.6197717 3.0391338 6.6268425 3.032063 56 P 0
L 6.6288425 1.372063 6.6294094 1.3726299 56 P 0
L 6.6294094 1.3726299 6.6294094 1.421063 56 P 0
L 6.6374016 1.881063 6.6998425 1.881063 56 P 0
L 6.6374016 1.981063 6.6916929 1.981063 2 P 0
L 6.6397637 2.9291339 6.6798425 2.8890551 2 P 0
L 6.6431101 2.302559 6.6798425 2.3392914 0 P 0
L 6.6502756 2.176063 6.6598425 2.1664961 56 P 0
L 6.6598425 2.0956299 6.6665519 2.1023393 2 P 0
L 6.6665519 2.1023393 6.7004416 2.1023393 2 P 0
L 6.6673228 1.3307087 6.7002756 1.3636615 2 P 0
L 6.6691732 2.7913386 6.6798425 2.8020079 2 P 0
L 6.6767716 1.5604725 6.6767716 1.611063 2 P 0
L 6.6767716 1.5604725 6.7002756 1.5369685 2 P 0
L 6.6767716 1.611063 6.6767716 1.671063 2 P 0
L 6.6767716 1.671063 6.6767716 1.721063 2 P 0
L 6.6767716 1.721063 6.6767716 1.776063 2 P 0
L 6.6767716 1.776063 6.8081889 1.776063 2 P 0
L 6.6798425 2.3392914 6.6798425 2.4201181 0 P 0
L 6.6798425 2.8020079 6.6798425 2.8890551 2 P 0
L 6.6858425 1.828063 6.7185038 1.828063 56 P 0
L 6.6916929 1.981063 6.7121574 2.0015275 2 P 0
L 6.7002756 1.3636615 6.7002756 1.421063 2 P 0
L 6.7002756 1.421063 6.7002756 1.531063 2 P 0
L 6.7002756 1.531063 6.7002756 1.5369685 2 P 0
L 6.7004416 2.1023393 6.7121574 2.1140551 2 P 0
L 6.7049842 3.192559 6.7265748 3.1709684 0 P 0
L 6.7049842 3.264567 6.7265748 3.2861576 0 P 0
L 6.7106299 2.2204724 6.75 2.1811023 2 P 0
L 6.7121574 2.0015275 6.7121574 2.1140551 2 P 0
L 6.7121574 2.1140551 6.7121574 2.1353858 2 P 0
L 6.7121574 2.1353858 6.7199999 2.1432283 2 P 0
L 6.7185038 1.828063 6.7276771 1.8188897 56 P 0
L 6.7199999 2.1432283 6.7443307 2.1432283 2 P 0
L 6.7265748 3.1680709 6.7265748 3.1709684 0 P 0
L 6.7265748 3.2861576 6.7265748 3.2940551 0 P 0
L 6.7276771 1.816063 6.7276771 1.8188897 56 P 0
L 6.7348425 3.806063 6.9001969 3.806063 2 P 0
L 6.7443307 2.1432283 6.7498425 2.1432283 2 P 0
L 6.7443307 2.1432283 6.75 2.1488976 2 P 0
L 6.7498425 2.0359448 6.7498425 2.0888976 0 P 0
L 6.7498425 2.0359448 6.8047243 1.981063 0 P 0
L 6.75 2.1488976 6.75 2.1811023 2 P 0
L 6.7820077 1.8745275 6.7820078 1.816063 0 P 0
L 6.7820077 1.8745275 6.7885431 1.8810629 0 P 0
L 6.7885431 1.8810629 6.8322834 1.881063 0 P 0
L 6.8047243 1.881063 6.8322834 1.881063 0 P 0
L 6.8047243 1.981063 6.8322834 1.981063 0 P 0
L 6.8081889 1.776063 6.8426771 1.8105512 2 P 0
L 6.8322834 1.881063 6.8807481 1.881063 0 P 0
L 6.8322834 1.931063 6.9317716 1.931063 0 P 0
L 6.8322834 2.031063 6.836126 2.031063 0 P 0
L 6.836126 2.031063 6.8433465 2.0382835 0 P 0
L 6.8426771 1.6682284 6.8426771 1.8105512 2 P 0
L 6.8426771 1.6682284 6.8448425 1.666063 2 P 0
L 6.8426771 1.8105512 6.8426771 1.816063 2 P 0
L 6.8433465 2.0382835 6.8433465 2.096063 0 P 0
L 6.8448425 1.661063 6.8448425 1.666063 2 P 0
L 6.8807481 1.881063 6.8970078 1.8648033 0 P 0
L 6.8970078 1.816063 6.8970078 1.8648033 0 P 0
L 6.9063386 2.096063 6.9488425 2.096063 56 P 0
L 6.9317716 1.931063 6.9398425 1.9229921 0 P 0
L 6.9398425 1.8891338 7.0046064 1.8891338 0 P 0
L 6.9488425 2.096063 6.9498425 2.095063 56 P 0
L 6.9744094 1.9399606 7.0115747 1.9399606 56 P 0
L 7.0046064 1.8891338 7.0098425 1.8838977 0 P 0
L 7.0098425 1.9382284 7.0107086 1.9390945 56 P 0
L 7.0115747 1.9399606 7.0155043 1.9438902 56 P 0
P 0.0998425 0.806063 77 P 0 0 ;0=64,1=0
P 0.0998425 1.006063 77 P 0 0 ;0=64,1=0
P 0.0998425 1.331063 77 P 0 0 ;0=64,1=0
P 0.0998425 1.531063 77 P 0 0 ;0=64,1=0
P 0.0998425 1.856063 77 P 0 0 ;0=64,1=0
P 0.0998425 2.056063 77 P 0 0 ;0=64,1=0
P 0.0998425 2.381063 77 P 0 0 ;0=64,1=0
P 0.0998425 2.581063 77 P 0 0 ;0=64,1=0
P 0.1998425 0.906063 78 P 0 0 ;0=65,1=0
P 0.1998425 1.431063 78 P 0 0 ;0=65,1=0
P 0.1998425 1.956063 78 P 0 0 ;0=65,1=0
P 0.1998425 2.481063 78 P 0 0 ;0=65,1=0
P 0.285433 4.152063 65 P 0 0 ;0=54,1=0
P 0.2854331 0.3681102 65 P 0 0 ;0=54,1=0
P 0.2998425 0.806063 77 P 0 0 ;0=64,1=0
P 0.2998425 1.006063 77 P 0 0 ;0=64,1=0
P 0.2998425 1.331063 77 P 0 0 ;0=64,1=0
P 0.2998425 1.531063 77 P 0 0 ;0=64,1=0
P 0.2998425 1.856063 77 P 0 0 ;0=64,1=0
P 0.2998425 2.056063 77 P 0 0 ;0=64,1=0
P 0.2998425 2.381063 77 P 0 0 ;0=64,1=0
P 0.2998425 2.581063 77 P 0 0 ;0=64,1=0
P 0.5948031 0.906063 29 P 0 0 ;0=26,1=0,2
P 0.5948031 1.431063 29 P 0 0 ;0=26,1=0,2
P 0.5948031 1.956063 29 P 0 0 ;0=26,1=0,2
P 0.5948031 2.481063 29 P 0 0 ;0=26,1=0,2
P 0.6389685 4.0388976 53 P 0 0 ;0=50,1=0,2
P 0.6389685 4.0932283 53 P 0 0 ;0=50,1=0,2
P 0.6448425 4.1975197 47 P 0 0 ;0=44,1=0,2
P 0.6448425 4.2546063 47 P 0 0 ;0=44,1=0,2
P 0.6548425 0.8479921 28 P 0 0 ;0=25,1=0,2
P 0.6548425 0.9641339 28 P 0 0 ;0=25,1=0,2
P 0.6548425 1.3729921 28 P 0 0 ;0=25,1=0,2
P 0.6548425 1.4891339 28 P 0 0 ;0=25,1=0,2
P 0.6548425 1.8979921 28 P 0 0 ;0=25,1=0,2
P 0.6548425 2.0141339 28 P 0 0 ;0=25,1=0,2
P 0.6548425 2.4229921 28 P 0 0 ;0=25,1=0,2
P 0.6548425 2.5391339 28 P 0 0 ;0=25,1=0,2
P 0.8406351 4.0388976 53 P 0 0 ;0=50,1=0,2
P 0.8406351 4.0932283 53 P 0 0 ;0=50,1=0,2
P 0.8465091 4.1975197 47 P 0 0 ;0=44,1=0,2
P 0.8465091 4.2546063 47 P 0 0 ;0=44,1=0,2
P 0.9005905 1.7470472 13 P 0 0 ;0=10,1=0,2
P 0.9015747 0.7185038 13 P 0 0 ;0=10,1=0,2
P 0.9045275 1.2244094 13 P 0 0 ;0=10,1=0,2
P 0.9084645 2.2844487 13 P 0 0 ;0=10,1=0,2
P 0.9326378 0.906063 46 P 0 0 ;0=43,1=0,2
P 0.9326378 1.431063 46 P 0 0 ;0=43,1=0,2
P 0.9326378 1.956063 46 P 0 0 ;0=43,1=0,2
P 0.9326378 2.481063 46 P 0 0 ;0=43,1=0,2
P 0.9596456 1.7470472 13 P 0 0 ;0=10,1=0,2
P 0.9606298 0.7185038 13 P 0 0 ;0=10,1=0,2
P 0.9635826 1.2244094 13 P 0 0 ;0=10,1=0,2
P 0.9675196 2.2844487 13 P 0 0 ;0=10,1=0,2
P 1.0423017 4.0388976 53 P 0 0 ;0=50,1=0,2
P 1.0423017 4.0932283 53 P 0 0 ;0=50,1=0,2
P 1.0481757 4.1975197 47 P 0 0 ;0=44,1=0,2
P 1.0481757 4.2546063 47 P 0 0 ;0=44,1=0,2
P 1.1570472 0.906063 46 P 0 0 ;0=43,1=0,2
P 1.1570472 1.431063 46 P 0 0 ;0=43,1=0,2
P 1.1570472 1.956063 46 P 0 0 ;0=43,1=0,2
P 1.1570472 2.481063 46 P 0 0 ;0=43,1=0,2
P 1.2439683 4.0388976 53 P 0 0 ;0=50,1=0,2
P 1.2439683 4.0932283 53 P 0 0 ;0=50,1=0,2
P 1.2498423 4.1975197 47 P 0 0 ;0=44,1=0,2
P 1.2498423 4.2546063 47 P 0 0 ;0=44,1=0,2
P 1.3464567 3.9783465 15 P 0 0 ;0=12,1=0,2
P 1.3464567 4.0374016 15 P 0 0 ;0=12,1=0,2
P 1.3464567 4.0826772 15 P 0 0 ;0=12,1=0,2
P 1.3464567 4.1417323 15 P 0 0 ;0=12,1=0,2
P 1.4576771 4.053937 66 P 0 0 ;0=55,1=0
P 1.4576771 4.153937 66 P 0 0 ;0=55,1=0
P 1.4576771 4.253937 67 P 0 0 ;0=55,1=0
P 1.6171125 1.319673 3 P 0 0 ;0=0,1=0,2
P 1.6171125 1.339363 3 P 0 0 ;0=0,1=0,2
P 1.6171125 1.359043 3 P 0 0 ;0=0,1=0,2
P 1.6171125 1.378733 3 P 0 0 ;0=0,1=0,2
P 1.6171125 1.398413 3 P 0 0 ;0=0,1=0,2
P 1.6171125 1.418103 3 P 0 0 ;0=0,1=0,2
P 1.6171125 1.437783 3 P 0 0 ;0=0,1=0,2
P 1.6171125 1.457473 3 P 0 0 ;0=0,1=0,2
P 1.6171125 1.477153 3 P 0 0 ;0=0,1=0,2
P 1.6171125 1.496843 3 P 0 0 ;0=0,1=0,2
P 1.6171125 1.516523 3 P 0 0 ;0=0,1=0,2
P 1.6171125 1.536213 3 P 0 0 ;0=0,1=0,2
P 1.6171125 1.555893 3 P 0 0 ;0=0,1=0,2
P 1.6171125 1.575583 3 P 0 0 ;0=0,1=0,2
P 1.6171125 1.595263 3 P 0 0 ;0=0,1=0,2
P 1.6171125 1.614953 3 P 0 0 ;0=0,1=0,2
P 1.6171125 1.634633 3 P 0 0 ;0=0,1=0,2
P 1.6171125 1.654323 3 P 0 0 ;0=0,1=0,2
P 1.6171125 1.674003 3 P 0 0 ;0=0,1=0,2
P 1.6171125 1.693693 3 P 0 0 ;0=0,1=0,2
P 1.6171125 1.713373 3 P 0 0 ;0=0,1=0,2
P 1.6171125 1.733063 3 P 0 0 ;0=0,1=0,2
P 1.6171125 1.752743 3 P 0 0 ;0=0,1=0,2
P 1.6171125 1.772433 3 P 0 0 ;0=0,1=0,2
P 1.6171125 1.792113 3 P 0 0 ;0=0,1=0,2
P 1.6171125 1.811803 3 P 0 0 ;0=0,1=0,2
P 1.6171125 1.831483 3 P 0 0 ;0=0,1=0,2
P 1.6171125 1.851173 3 P 0 0 ;0=0,1=0,2
P 1.6171125 1.870853 3 P 0 0 ;0=0,1=0,2
P 1.6171125 1.890543 3 P 0 0 ;0=0,1=0,2
P 1.6171125 1.910223 3 P 0 0 ;0=0,1=0,2
P 1.6171125 1.929913 3 P 0 0 ;0=0,1=0,2
P 1.6171125 1.949593 3 P 0 0 ;0=0,1=0,2
P 1.6171125 1.969283 3 P 0 0 ;0=0,1=0,2
P 1.6171125 1.988963 3 P 0 0 ;0=0,1=0,2
P 1.6171125 2.008653 3 P 0 0 ;0=0,1=0,2
P 1.6171125 2.028333 3 P 0 0 ;0=0,1=0,2
P 1.6171125 2.048023 3 P 0 0 ;0=0,1=0,2
P 1.6171125 2.067703 3 P 0 0 ;0=0,1=0,2
P 1.6171125 2.087393 3 P 0 0 ;0=0,1=0,2
P 1.631559 4.024563 31 P 0 0 ;0=28,1=0,2
P 1.631559 4.049563 31 P 0 0 ;0=28,1=0,2
P 1.631559 4.074563 31 P 0 0 ;0=28,1=0,2
P 1.631559 4.099563 31 P 0 0 ;0=28,1=0,2
P 1.631559 4.124563 31 P 0 0 ;0=28,1=0,2
P 1.631559 4.149563 31 P 0 0 ;0=28,1=0,2
P 1.631559 4.174563 31 P 0 0 ;0=28,1=0,2
P 1.631559 4.199563 31 P 0 0 ;0=28,1=0,2
P 1.6643465 4.273063 20 P 0 0 ;0=17,1=0,2
P 1.6968325 1.275383 4 P 0 0 ;0=1,1=0,2
P 1.6968325 1.309833 64 P 0 0 ;0=53,1=0
P 1.6968325 2.097233 64 P 0 0 ;0=53,1=0
P 1.6968325 2.131683 4 P 0 0 ;0=1,1=0,2
P 1.7273386 4.273063 20 P 0 0 ;0=17,1=0,2
P 1.7765525 1.319673 3 P 0 0 ;0=0,1=0,2
P 1.7765525 1.339363 3 P 0 0 ;0=0,1=0,2
P 1.7765525 1.359043 3 P 0 0 ;0=0,1=0,2
P 1.7765525 1.378733 3 P 0 0 ;0=0,1=0,2
P 1.7765525 1.398413 3 P 0 0 ;0=0,1=0,2
P 1.7765525 1.418103 3 P 0 0 ;0=0,1=0,2
P 1.7765525 1.437783 3 P 0 0 ;0=0,1=0,2
P 1.7765525 1.457473 3 P 0 0 ;0=0,1=0,2
P 1.7765525 1.477153 3 P 0 0 ;0=0,1=0,2
P 1.7765525 1.496843 3 P 0 0 ;0=0,1=0,2
P 1.7765525 1.516523 3 P 0 0 ;0=0,1=0,2
P 1.7765525 1.536213 3 P 0 0 ;0=0,1=0,2
P 1.7765525 1.555893 3 P 0 0 ;0=0,1=0,2
P 1.7765525 1.575583 3 P 0 0 ;0=0,1=0,2
P 1.7765525 1.595263 3 P 0 0 ;0=0,1=0,2
P 1.7765525 1.614953 3 P 0 0 ;0=0,1=0,2
P 1.7765525 1.634633 3 P 0 0 ;0=0,1=0,2
P 1.7765525 1.654323 3 P 0 0 ;0=0,1=0,2
P 1.7765525 1.674003 3 P 0 0 ;0=0,1=0,2
P 1.7765525 1.693693 3 P 0 0 ;0=0,1=0,2
P 1.7765525 1.713373 3 P 0 0 ;0=0,1=0,2
P 1.7765525 1.733063 3 P 0 0 ;0=0,1=0,2
P 1.7765525 1.752743 3 P 0 0 ;0=0,1=0,2
P 1.7765525 1.772433 3 P 0 0 ;0=0,1=0,2
P 1.7765525 1.792113 3 P 0 0 ;0=0,1=0,2
P 1.7765525 1.811803 3 P 0 0 ;0=0,1=0,2
P 1.7765525 1.831483 3 P 0 0 ;0=0,1=0,2
P 1.7765525 1.851173 3 P 0 0 ;0=0,1=0,2
P 1.7765525 1.870853 3 P 0 0 ;0=0,1=0,2
P 1.7765525 1.890543 3 P 0 0 ;0=0,1=0,2
P 1.7765525 1.910223 3 P 0 0 ;0=0,1=0,2
P 1.7765525 1.929913 3 P 0 0 ;0=0,1=0,2
P 1.7765525 1.949593 3 P 0 0 ;0=0,1=0,2
P 1.7765525 1.969283 3 P 0 0 ;0=0,1=0,2
P 1.7765525 1.988963 3 P 0 0 ;0=0,1=0,2
P 1.7765525 2.008653 3 P 0 0 ;0=0,1=0,2
P 1.7765525 2.028333 3 P 0 0 ;0=0,1=0,2
P 1.7765525 2.048023 3 P 0 0 ;0=0,1=0,2
P 1.7765525 2.067703 3 P 0 0 ;0=0,1=0,2
P 1.7765525 2.087393 3 P 0 0 ;0=0,1=0,2
P 1.7972451 0.1377953 7 P 0 0 ;0=4,1=0,2
P 1.8024094 4.276063 51 P 0 0 ;0=48,1=0,2
P 1.836122 0.2691929 61 P 0 0
P 1.8366151 0.1377953 7 P 0 0 ;0=4,1=0,2
P 1.8461259 4.024563 31 P 0 0 ;0=28,1=0,2
P 1.8461259 4.049563 31 P 0 0 ;0=28,1=0,2
P 1.8461259 4.074563 31 P 0 0 ;0=28,1=0,2
P 1.8461259 4.099563 31 P 0 0 ;0=28,1=0,2
P 1.8461259 4.124563 31 P 0 0 ;0=28,1=0,2
P 1.8461259 4.149563 31 P 0 0 ;0=28,1=0,2
P 1.8461259 4.174563 31 P 0 0 ;0=28,1=0,2
P 1.8461259 4.199563 31 P 0 0 ;0=28,1=0,2
P 1.8732756 4.276063 51 P 0 0 ;0=48,1=0,2
P 1.8759851 0.1377953 7 P 0 0 ;0=4,1=0,2
P 1.9153551 0.1377953 7 P 0 0 ;0=4,1=0,2
P 1.9338425 4.0748977 53 P 0 0 ;0=50,1=0,2
P 1.9338425 4.1292284 53 P 0 0 ;0=50,1=0,2
P 1.9547251 0.1377953 7 P 0 0 ;0=4,1=0,2
P 1.9940951 0.1377953 7 P 0 0 ;0=4,1=0,2
P 2.0334651 0.1377953 7 P 0 0 ;0=4,1=0,2
P 2.0433071 4.057874 66 P 0 0 ;0=55,1=0
P 2.0433071 4.157874 66 P 0 0 ;0=55,1=0
P 2.0433071 4.257874 67 P 0 0 ;0=55,1=0
P 2.0728351 0.1377953 7 P 0 0 ;0=4,1=0,2
P 2.1122051 0.1377953 7 P 0 0 ;0=4,1=0,2
P 2.1123027 0.269685 60 P 0 0
P 2.1398425 3.6641339 50 P 0 0 ;0=47,1=0,2
P 2.1398425 3.6979922 50 P 0 0 ;0=47,1=0,2
P 2.1468425 2.6248976 53 P 0 0 ;0=50,1=0,2
P 2.1468425 2.6792283 53 P 0 0 ;0=50,1=0,2
P 2.1515748 4.0157481 15 P 0 0 ;0=12,1=0,2
P 2.1515748 4.0748032 15 P 0 0 ;0=12,1=0,2
P 2.1515751 0.1377953 7 P 0 0 ;0=4,1=0,2
P 2.1686825 2.438533 6 P 0 0 ;0=3,1=0,2
P 2.1686925 0.958593 6 P 0 0 ;0=3,1=0,2
P 2.1909451 0.1377953 7 P 0 0 ;0=4,1=0,2
P 2.1996929 4.275063 21 P 0 0 ;0=18,1=0,2
P 2.2031325 2.438533 64 P 0 0 ;0=53,1=0
P 2.2031425 0.958593 64 P 0 0 ;0=53,1=0
P 2.2098425 3.6456299 48 P 0 0 ;0=45,1=0,2
P 2.2098425 3.7164961 48 P 0 0 ;0=45,1=0,2
P 2.2125984 4.0157481 15 P 0 0 ;0=12,1=0,2
P 2.2125984 4.0748032 15 P 0 0 ;0=12,1=0,2
P 2.2129725 2.358813 5 P 0 0 ;0=2,1=0,2
P 2.2129725 2.518253 5 P 0 0 ;0=2,1=0,2
P 2.2129825 0.878873 5 P 0 0 ;0=2,1=0,2
P 2.2129825 1.038313 5 P 0 0 ;0=2,1=0,2
P 2.2326625 2.358813 5 P 0 0 ;0=2,1=0,2
P 2.2326625 2.518253 5 P 0 0 ;0=2,1=0,2
P 2.2326725 0.878873 5 P 0 0 ;0=2,1=0,2
P 2.2326725 1.038313 5 P 0 0 ;0=2,1=0,2
P 2.2341417 4.1736851 23 P 0 0 ;0=20,1=0,2
P 2.2523425 2.358813 5 P 0 0 ;0=2,1=0,2
P 2.2523425 2.518253 5 P 0 0 ;0=2,1=0,2
P 2.2523525 0.878873 5 P 0 0 ;0=2,1=0,2
P 2.2523525 1.038313 5 P 0 0 ;0=2,1=0,2
P 2.2715433 4.275063 25 P 0 0 ;0=22,1=0,2
P 2.2720325 2.358813 5 P 0 0 ;0=2,1=0,2
P 2.2720325 2.518253 5 P 0 0 ;0=2,1=0,2
P 2.2720425 0.878873 5 P 0 0 ;0=2,1=0,2
P 2.2720425 1.038313 5 P 0 0 ;0=2,1=0,2
P 2.2813858 4.1703386 22 P 0 0 ;0=19,1=0,2
P 2.2917125 2.358813 5 P 0 0 ;0=2,1=0,2
P 2.2917125 2.518253 5 P 0 0 ;0=2,1=0,2
P 2.2917225 0.878873 5 P 0 0 ;0=2,1=0,2
P 2.2917225 1.038313 5 P 0 0 ;0=2,1=0,2
P 2.3069763 4.1703386 22 P 0 0 ;0=19,1=0,2
P 2.3090551 0.1377953 7 P 0 0 ;0=4,1=0,2
P 2.3114025 2.358813 5 P 0 0 ;0=2,1=0,2
P 2.3114025 2.518253 5 P 0 0 ;0=2,1=0,2
P 2.3114125 0.878873 5 P 0 0 ;0=2,1=0,2
P 2.3114125 1.038313 5 P 0 0 ;0=2,1=0,2
P 2.3310825 2.358813 5 P 0 0 ;0=2,1=0,2
P 2.3310825 2.518253 5 P 0 0 ;0=2,1=0,2
P 2.3310925 0.878873 5 P 0 0 ;0=2,1=0,2
P 2.3310925 1.038313 5 P 0 0 ;0=2,1=0,2
P 2.3325669 4.1703386 22 P 0 0 ;0=19,1=0,2
P 2.3348425 3.4045276 14 P 0 0 ;0=11,1=0,2
P 2.3348425 3.4832677 14 P 0 0 ;0=11,1=0,2
P 2.3348425 3.5620079 14 P 0 0 ;0=11,1=0,2
P 2.3348425 3.640748 14 P 0 0 ;0=11,1=0,2
P 2.3484251 0.1377953 7 P 0 0 ;0=4,1=0,2
P 2.3507725 2.358813 5 P 0 0 ;0=2,1=0,2
P 2.3507725 2.518253 5 P 0 0 ;0=2,1=0,2
P 2.3507825 0.878873 5 P 0 0 ;0=2,1=0,2
P 2.3507825 1.038313 5 P 0 0 ;0=2,1=0,2
P 2.3581575 4.1703386 22 P 0 0 ;0=19,1=0,2
P 2.3704525 2.358813 5 P 0 0 ;0=2,1=0,2
P 2.3704525 2.518253 5 P 0 0 ;0=2,1=0,2
P 2.3704625 0.878873 5 P 0 0 ;0=2,1=0,2
P 2.3704625 1.038313 5 P 0 0 ;0=2,1=0,2
P 2.3778425 4.275063 24 P 0 0 ;0=21,1=0,2
P 2.383748 4.1703386 22 P 0 0 ;0=19,1=0,2
P 2.3877951 0.1377953 7 P 0 0 ;0=4,1=0,2
P 2.3877954 2.8996063 15 P 0 0 ;0=12,1=0,2
P 2.3877954 2.9586614 15 P 0 0 ;0=12,1=0,2
P 2.3901425 2.358813 5 P 0 0 ;0=2,1=0,2
P 2.3901425 2.518253 5 P 0 0 ;0=2,1=0,2
P 2.3901525 0.878873 5 P 0 0 ;0=2,1=0,2
P 2.3901525 1.038313 5 P 0 0 ;0=2,1=0,2
P 2.4098225 2.358813 5 P 0 0 ;0=2,1=0,2
P 2.4098225 2.518253 5 P 0 0 ;0=2,1=0,2
P 2.4098325 0.878873 5 P 0 0 ;0=2,1=0,2
P 2.4098325 1.038313 5 P 0 0 ;0=2,1=0,2
P 2.4271651 0.1377953 7 P 0 0 ;0=4,1=0,2
P 2.4295125 2.358813 5 P 0 0 ;0=2,1=0,2
P 2.4295125 2.518253 5 P 0 0 ;0=2,1=0,2
P 2.4295225 0.878873 5 P 0 0 ;0=2,1=0,2
P 2.4295225 1.038313 5 P 0 0 ;0=2,1=0,2
P 2.4309921 4.1736851 23 P 0 0 ;0=20,1=0,2
P 2.4491925 2.358813 5 P 0 0 ;0=2,1=0,2
P 2.4491925 2.518253 5 P 0 0 ;0=2,1=0,2
P 2.4492025 0.878873 5 P 0 0 ;0=2,1=0,2
P 2.4492025 1.038313 5 P 0 0 ;0=2,1=0,2
P 2.4654409 4.275063 21 P 0 0 ;0=18,1=0,2
P 2.4665351 0.1377953 7 P 0 0 ;0=4,1=0,2
P 2.4688825 2.358813 5 P 0 0 ;0=2,1=0,2
P 2.4688825 2.518253 5 P 0 0 ;0=2,1=0,2
P 2.4688925 0.878873 5 P 0 0 ;0=2,1=0,2
P 2.4688925 1.038313 5 P 0 0 ;0=2,1=0,2
P 2.4885625 2.358813 5 P 0 0 ;0=2,1=0,2
P 2.4885625 2.518253 5 P 0 0 ;0=2,1=0,2
P 2.4885725 0.878873 5 P 0 0 ;0=2,1=0,2
P 2.4885725 1.038313 5 P 0 0 ;0=2,1=0,2
P 2.503937 0.5738189 54 P 0 0 ;0=51,1=0,2
P 2.503937 0.6072835 54 P 0 0 ;0=51,1=0,2
P 2.5059051 0.1377953 7 P 0 0 ;0=4,1=0,2
P 2.5082525 2.358813 5 P 0 0 ;0=2,1=0,2
P 2.5082525 2.518253 5 P 0 0 ;0=2,1=0,2
P 2.5082625 0.878873 5 P 0 0 ;0=2,1=0,2
P 2.5082625 1.038313 5 P 0 0 ;0=2,1=0,2
P 2.5098425 3.4045276 14 P 0 0 ;0=11,1=0,2
P 2.5098425 3.4832677 14 P 0 0 ;0=11,1=0,2
P 2.5098425 3.5620079 14 P 0 0 ;0=11,1=0,2
P 2.5098425 3.640748 14 P 0 0 ;0=11,1=0,2
P 2.5279325 2.358813 5 P 0 0 ;0=2,1=0,2
P 2.5279325 2.518253 5 P 0 0 ;0=2,1=0,2
P 2.5279425 0.878873 5 P 0 0 ;0=2,1=0,2
P 2.5279425 1.038313 5 P 0 0 ;0=2,1=0,2
P 2.5452751 0.1377953 7 P 0 0 ;0=4,1=0,2
P 2.5476225 2.358813 5 P 0 0 ;0=2,1=0,2
P 2.5476225 2.518253 5 P 0 0 ;0=2,1=0,2
P 2.5476325 0.878873 5 P 0 0 ;0=2,1=0,2
P 2.5476325 1.038313 5 P 0 0 ;0=2,1=0,2
P 2.5673025 2.358813 5 P 0 0 ;0=2,1=0,2
P 2.5673025 2.518253 5 P 0 0 ;0=2,1=0,2
P 2.5673125 0.878873 5 P 0 0 ;0=2,1=0,2
P 2.5673125 1.038313 5 P 0 0 ;0=2,1=0,2
P 2.5846451 0.1377953 7 P 0 0 ;0=4,1=0,2
P 2.5869925 2.358813 5 P 0 0 ;0=2,1=0,2
P 2.5869925 2.518253 5 P 0 0 ;0=2,1=0,2
P 2.5870025 0.878873 5 P 0 0 ;0=2,1=0,2
P 2.5870025 1.038313 5 P 0 0 ;0=2,1=0,2
P 2.6066725 2.358813 5 P 0 0 ;0=2,1=0,2
P 2.6066725 2.518253 5 P 0 0 ;0=2,1=0,2
P 2.6066825 0.878873 5 P 0 0 ;0=2,1=0,2
P 2.6066825 1.038313 5 P 0 0 ;0=2,1=0,2
P 2.6240151 0.1377953 7 P 0 0 ;0=4,1=0,2
P 2.6263625 2.358813 5 P 0 0 ;0=2,1=0,2
P 2.6263625 2.518253 5 P 0 0 ;0=2,1=0,2
P 2.6263725 0.878873 5 P 0 0 ;0=2,1=0,2
P 2.6263725 1.038313 5 P 0 0 ;0=2,1=0,2
P 2.6398425 3.5356299 48 P 0 0 ;0=45,1=0,2
P 2.6398425 3.6064961 48 P 0 0 ;0=45,1=0,2
P 2.6460425 2.358813 5 P 0 0 ;0=2,1=0,2
P 2.6460425 2.518253 5 P 0 0 ;0=2,1=0,2
P 2.6460525 0.878873 5 P 0 0 ;0=2,1=0,2
P 2.6460525 1.038313 5 P 0 0 ;0=2,1=0,2
P 2.6633851 0.1377953 7 P 0 0 ;0=4,1=0,2
P 2.6657325 2.358813 5 P 0 0 ;0=2,1=0,2
P 2.6657325 2.518253 5 P 0 0 ;0=2,1=0,2
P 2.6657425 0.878873 5 P 0 0 ;0=2,1=0,2
P 2.6657425 1.038313 5 P 0 0 ;0=2,1=0,2
P 2.6854125 2.358813 5 P 0 0 ;0=2,1=0,2
P 2.6854125 2.518253 5 P 0 0 ;0=2,1=0,2
P 2.6854225 0.878873 5 P 0 0 ;0=2,1=0,2
P 2.6854225 1.038313 5 P 0 0 ;0=2,1=0,2
P 2.694252 3.7503543 30 P 0 0 ;0=27,1=0,2
P 2.7027551 0.1377953 7 P 0 0 ;0=4,1=0,2
P 2.7051025 2.358813 5 P 0 0 ;0=2,1=0,2
P 2.7051025 2.518253 5 P 0 0 ;0=2,1=0,2
P 2.7051125 0.878873 5 P 0 0 ;0=2,1=0,2
P 2.7051125 1.038313 5 P 0 0 ;0=2,1=0,2
P 2.7198425 3.6617716 30 P 0 0 ;0=27,1=0,2
P 2.7247825 2.358813 5 P 0 0 ;0=2,1=0,2
P 2.7247825 2.518253 5 P 0 0 ;0=2,1=0,2
P 2.7247925 0.878873 5 P 0 0 ;0=2,1=0,2
P 2.7247925 1.038313 5 P 0 0 ;0=2,1=0,2
P 2.7248425 3.5591338 50 P 0 0 ;0=47,1=0,2
P 2.7248425 3.5929921 50 P 0 0 ;0=47,1=0,2
P 2.7421251 0.1377953 7 P 0 0 ;0=4,1=0,2
P 2.7444725 2.358813 5 P 0 0 ;0=2,1=0,2
P 2.7444725 2.518253 5 P 0 0 ;0=2,1=0,2
P 2.7444825 0.878873 5 P 0 0 ;0=2,1=0,2
P 2.7444825 1.038313 5 P 0 0 ;0=2,1=0,2
P 2.7454331 3.7503543 30 P 0 0 ;0=27,1=0,2
P 2.7568898 2.9372047 18 P 0 0 ;0=15,1=0,2
P 2.7568898 2.9872047 18 P 0 0 ;0=15,1=0,2
P 2.7568898 3.0372047 18 P 0 0 ;0=15,1=0,2
P 2.7568898 3.0872047 18 P 0 0 ;0=15,1=0,2
P 2.7568898 3.1372047 18 P 0 0 ;0=15,1=0,2
P 2.7568898 3.1872047 18 P 0 0 ;0=15,1=0,2
P 2.7568898 3.2372047 18 P 0 0 ;0=15,1=0,2
P 2.7568898 3.2872047 18 P 0 0 ;0=15,1=0,2
P 2.7641525 2.358813 5 P 0 0 ;0=2,1=0,2
P 2.7641525 2.518253 5 P 0 0 ;0=2,1=0,2
P 2.7641625 0.878873 5 P 0 0 ;0=2,1=0,2
P 2.7641625 1.038313 5 P 0 0 ;0=2,1=0,2
P 2.7814951 0.1377953 7 P 0 0 ;0=4,1=0,2
P 2.7838425 2.358813 5 P 0 0 ;0=2,1=0,2
P 2.7838425 2.518253 5 P 0 0 ;0=2,1=0,2
P 2.7838525 0.878873 5 P 0 0 ;0=2,1=0,2
P 2.7838525 1.038313 5 P 0 0 ;0=2,1=0,2
P 2.8035225 2.358813 5 P 0 0 ;0=2,1=0,2
P 2.8035225 2.518253 5 P 0 0 ;0=2,1=0,2
P 2.8035325 0.878873 5 P 0 0 ;0=2,1=0,2
P 2.8035325 1.038313 5 P 0 0 ;0=2,1=0,2
P 2.809252 3.7503543 30 P 0 0 ;0=27,1=0,2
P 2.8208651 0.1377953 7 P 0 0 ;0=4,1=0,2
P 2.8232125 2.358813 5 P 0 0 ;0=2,1=0,2
P 2.8232125 2.518253 5 P 0 0 ;0=2,1=0,2
P 2.8232225 0.878873 5 P 0 0 ;0=2,1=0,2
P 2.8232225 1.038313 5 P 0 0 ;0=2,1=0,2
P 2.8348425 3.6617716 30 P 0 0 ;0=27,1=0,2
P 2.8428925 2.358813 5 P 0 0 ;0=2,1=0,2
P 2.8428925 2.518253 5 P 0 0 ;0=2,1=0,2
P 2.8429025 0.878873 5 P 0 0 ;0=2,1=0,2
P 2.8429025 1.038313 5 P 0 0 ;0=2,1=0,2
P 2.8602351 0.1377953 7 P 0 0 ;0=4,1=0,2
P 2.8604331 3.7503543 30 P 0 0 ;0=27,1=0,2
P 2.8625825 2.358813 5 P 0 0 ;0=2,1=0,2
P 2.8625825 2.518253 5 P 0 0 ;0=2,1=0,2
P 2.8625925 0.878873 5 P 0 0 ;0=2,1=0,2
P 2.8625925 1.038313 5 P 0 0 ;0=2,1=0,2
P 2.8822625 2.358813 5 P 0 0 ;0=2,1=0,2
P 2.8822625 2.518253 5 P 0 0 ;0=2,1=0,2
P 2.8822725 0.878873 5 P 0 0 ;0=2,1=0,2
P 2.8822725 1.038313 5 P 0 0 ;0=2,1=0,2
P 2.8996051 0.1377953 7 P 0 0 ;0=4,1=0,2
P 2.9019525 2.358813 5 P 0 0 ;0=2,1=0,2
P 2.9019525 2.518253 5 P 0 0 ;0=2,1=0,2
P 2.9019625 0.878873 5 P 0 0 ;0=2,1=0,2
P 2.9019625 1.038313 5 P 0 0 ;0=2,1=0,2
P 2.9216325 2.358813 5 P 0 0 ;0=2,1=0,2
P 2.9216325 2.518253 5 P 0 0 ;0=2,1=0,2
P 2.9216425 0.878873 5 P 0 0 ;0=2,1=0,2
P 2.9216425 1.038313 5 P 0 0 ;0=2,1=0,2
P 2.9389751 0.1377953 7 P 0 0 ;0=4,1=0,2
P 2.9413225 2.358813 5 P 0 0 ;0=2,1=0,2
P 2.9413225 2.518253 5 P 0 0 ;0=2,1=0,2
P 2.9413325 0.878873 5 P 0 0 ;0=2,1=0,2
P 2.9413325 1.038313 5 P 0 0 ;0=2,1=0,2
P 2.9448425 3.6666929 40 P 0 0 ;0=37,1=0,2
P 2.9448425 3.7454331 40 P 0 0 ;0=37,1=0,2
P 2.9448425 3.951063 39 P 0 0 ;0=36,1=0,2
P 2.9448425 4.2211417 39 P 0 0 ;0=36,1=0,2
P 2.9610025 2.358813 5 P 0 0 ;0=2,1=0,2
P 2.9610025 2.518253 5 P 0 0 ;0=2,1=0,2
P 2.9610125 0.878873 5 P 0 0 ;0=2,1=0,2
P 2.9610125 1.038313 5 P 0 0 ;0=2,1=0,2
P 2.9783451 0.1377953 7 P 0 0 ;0=4,1=0,2
P 2.9806925 2.358813 5 P 0 0 ;0=2,1=0,2
P 2.9806925 2.518253 5 P 0 0 ;0=2,1=0,2
P 2.9807025 0.878873 5 P 0 0 ;0=2,1=0,2
P 2.9807025 1.038313 5 P 0 0 ;0=2,1=0,2
P 2.9905325 2.438533 64 P 0 0 ;0=53,1=0
P 2.9905425 0.958593 64 P 0 0 ;0=53,1=0
P 2.9948425 4.0861024 72 P 0 0 ;0=59,1=0
P 3.0177151 0.1377953 7 P 0 0 ;0=4,1=0,2
P 3.0249825 2.438533 6 P 0 0 ;0=3,1=0,2
P 3.0249925 0.958593 6 P 0 0 ;0=3,1=0,2
P 3.0448425 3.6666929 40 P 0 0 ;0=37,1=0,2
P 3.0448425 3.7454331 40 P 0 0 ;0=37,1=0,2
P 3.0448425 3.951063 39 P 0 0 ;0=36,1=0,2
P 3.0448425 4.2211417 39 P 0 0 ;0=36,1=0,2
P 3.0551181 0.5738189 54 P 0 0 ;0=51,1=0,2
P 3.0551181 0.6072835 54 P 0 0 ;0=51,1=0,2
P 3.0570851 0.1572953 8 P 0 0 ;0=5,1=0,2
P 3.0964551 0.1377953 7 P 0 0 ;0=4,1=0,2
P 3.1112205 2.9372047 18 P 0 0 ;0=15,1=0,2
P 3.1112205 2.9872047 18 P 0 0 ;0=15,1=0,2
P 3.1112205 3.0372047 18 P 0 0 ;0=15,1=0,2
P 3.1112205 3.0872047 18 P 0 0 ;0=15,1=0,2
P 3.1112205 3.1372047 18 P 0 0 ;0=15,1=0,2
P 3.1112205 3.1872047 18 P 0 0 ;0=15,1=0,2
P 3.1112205 3.2372047 18 P 0 0 ;0=15,1=0,2
P 3.1112205 3.2872047 18 P 0 0 ;0=15,1=0,2
P 3.1448425 3.6666929 40 P 0 0 ;0=37,1=0,2
P 3.1448425 3.7454331 40 P 0 0 ;0=37,1=0,2
P 3.1448425 3.951063 39 P 0 0 ;0=36,1=0,2
P 3.1448425 4.2211417 39 P 0 0 ;0=36,1=0,2
P 3.2091732 2.7952756 10 P 0 0 ;0=7,1=0,2
P 3.2091732 2.8149606 10 P 0 0 ;0=7,1=0,2
P 3.2091732 2.8346456 10 P 0 0 ;0=7,1=0,2
P 3.219252 3.7503543 30 P 0 0 ;0=27,1=0,2
P 3.2293307 2.7849212 9 P 0 0 ;0=6,1=0,2
P 3.2293307 2.845 9 P 0 0 ;0=6,1=0,2
P 3.2448425 3.6617716 30 P 0 0 ;0=27,1=0,2
P 3.2448425 3.951063 39 P 0 0 ;0=36,1=0,2
P 3.2448425 4.2211417 39 P 0 0 ;0=36,1=0,2
P 3.2490157 2.7849212 9 P 0 0 ;0=6,1=0,2
P 3.2490157 2.845 9 P 0 0 ;0=6,1=0,2
P 3.2691732 2.7952756 10 P 0 0 ;0=7,1=0,2
P 3.2691732 2.8149606 10 P 0 0 ;0=7,1=0,2
P 3.2691732 2.8346456 10 P 0 0 ;0=7,1=0,2
P 3.2704331 3.7503543 30 P 0 0 ;0=27,1=0,2
P 3.2948425 4.0861024 72 P 0 0 ;0=59,1=0
P 3.3331103 3.2062205 35 P 0 0 ;0=32,1=0,2
P 3.3331103 3.3951969 35 P 0 0 ;0=32,1=0,2
P 3.3448425 3.951063 39 P 0 0 ;0=36,1=0,2
P 3.3448425 4.2211417 39 P 0 0 ;0=36,1=0,2
P 3.3498425 3.6666929 40 P 0 0 ;0=37,1=0,2
P 3.3498425 3.7454331 40 P 0 0 ;0=37,1=0,2
P 3.3921654 3.2062205 35 P 0 0 ;0=32,1=0,2
P 3.3921654 3.3951969 35 P 0 0 ;0=32,1=0,2
P 3.4385827 2.8923386 38 P 0 0 ;0=35,1=0,2
P 3.4385827 3.0517874 38 P 0 0 ;0=35,1=0,2
P 3.444252 3.7503543 30 P 0 0 ;0=27,1=0,2
P 3.4444882 2.948441 36 P 0 0 ;0=33,1=0,2
P 3.4444882 2.995685 36 P 0 0 ;0=33,1=0,2
P 3.4512205 3.2062205 35 P 0 0 ;0=32,1=0,2
P 3.4512205 3.3951969 35 P 0 0 ;0=32,1=0,2
P 3.4698425 3.6617716 30 P 0 0 ;0=27,1=0,2
P 3.4776771 2.797063 11 P 0 0 ;0=8,1=0,2
P 3.4848425 2.8923386 37 P 0 0 ;0=34,1=0,2
P 3.4848425 3.0517874 37 P 0 0 ;0=34,1=0,2
P 3.4920225 1.319633 3 P 0 0 ;0=0,1=0,2
P 3.4920225 1.339323 3 P 0 0 ;0=0,1=0,2
P 3.4920225 1.359003 3 P 0 0 ;0=0,1=0,2
P 3.4920225 1.378693 3 P 0 0 ;0=0,1=0,2
P 3.4920225 1.398373 3 P 0 0 ;0=0,1=0,2
P 3.4920225 1.418063 3 P 0 0 ;0=0,1=0,2
P 3.4920225 1.437743 3 P 0 0 ;0=0,1=0,2
P 3.4920225 1.457433 3 P 0 0 ;0=0,1=0,2
P 3.4920225 1.477113 3 P 0 0 ;0=0,1=0,2
P 3.4920225 1.496803 3 P 0 0 ;0=0,1=0,2
P 3.4920225 1.516483 3 P 0 0 ;0=0,1=0,2
P 3.4920225 1.536173 3 P 0 0 ;0=0,1=0,2
P 3.4920225 1.555853 3 P 0 0 ;0=0,1=0,2
P 3.4920225 1.575543 3 P 0 0 ;0=0,1=0,2
P 3.4920225 1.595223 3 P 0 0 ;0=0,1=0,2
P 3.4920225 1.614913 3 P 0 0 ;0=0,1=0,2
P 3.4920225 1.634593 3 P 0 0 ;0=0,1=0,2
P 3.4920225 1.654283 3 P 0 0 ;0=0,1=0,2
P 3.4920225 1.673963 3 P 0 0 ;0=0,1=0,2
P 3.4920225 1.693653 3 P 0 0 ;0=0,1=0,2
P 3.4920225 1.713333 3 P 0 0 ;0=0,1=0,2
P 3.4920225 1.733023 3 P 0 0 ;0=0,1=0,2
P 3.4920225 1.752703 3 P 0 0 ;0=0,1=0,2
P 3.4920225 1.772393 3 P 0 0 ;0=0,1=0,2
P 3.4920225 1.792073 3 P 0 0 ;0=0,1=0,2
P 3.4920225 1.811763 3 P 0 0 ;0=0,1=0,2
P 3.4920225 1.831443 3 P 0 0 ;0=0,1=0,2
P 3.4920225 1.851133 3 P 0 0 ;0=0,1=0,2
P 3.4920225 1.870813 3 P 0 0 ;0=0,1=0,2
P 3.4920225 1.890503 3 P 0 0 ;0=0,1=0,2
P 3.4920225 1.910183 3 P 0 0 ;0=0,1=0,2
P 3.4920225 1.929873 3 P 0 0 ;0=0,1=0,2
P 3.4920225 1.949553 3 P 0 0 ;0=0,1=0,2
P 3.4920225 1.969243 3 P 0 0 ;0=0,1=0,2
P 3.4920225 1.988923 3 P 0 0 ;0=0,1=0,2
P 3.4920225 2.008613 3 P 0 0 ;0=0,1=0,2
P 3.4920225 2.028293 3 P 0 0 ;0=0,1=0,2
P 3.4920225 2.047983 3 P 0 0 ;0=0,1=0,2
P 3.4920225 2.067663 3 P 0 0 ;0=0,1=0,2
P 3.4920225 2.087353 3 P 0 0 ;0=0,1=0,2
P 3.4954331 3.7503543 30 P 0 0 ;0=27,1=0,2
P 3.5102756 3.2062205 35 P 0 0 ;0=32,1=0,2
P 3.5102756 3.3951969 35 P 0 0 ;0=32,1=0,2
P 3.5251968 2.948441 36 P 0 0 ;0=33,1=0,2
P 3.5251968 2.995685 36 P 0 0 ;0=33,1=0,2
P 3.5311023 2.8923386 38 P 0 0 ;0=35,1=0,2
P 3.5311023 3.0517874 38 P 0 0 ;0=35,1=0,2
P 3.5320078 2.797063 11 P 0 0 ;0=8,1=0,2
P 3.5693307 3.2062205 35 P 0 0 ;0=32,1=0,2
P 3.5693307 3.3853543 34 P 0 0 ;0=31,1=0,2
P 3.5717425 1.275343 4 P 0 0 ;0=1,1=0,2
P 3.5717425 1.309793 64 P 0 0 ;0=53,1=0
P 3.5717425 2.097193 64 P 0 0 ;0=53,1=0
P 3.5717425 2.131643 4 P 0 0 ;0=1,1=0,2
P 3.5898425 3.7275197 47 P 0 0 ;0=44,1=0,2
P 3.5898425 3.7846063 47 P 0 0 ;0=44,1=0,2
P 3.5898425 3.8525197 47 P 0 0 ;0=44,1=0,2
P 3.5898425 3.9096063 47 P 0 0 ;0=44,1=0,2
P 3.6514625 1.319633 3 P 0 0 ;0=0,1=0,2
P 3.6514625 1.339323 3 P 0 0 ;0=0,1=0,2
P 3.6514625 1.359003 3 P 0 0 ;0=0,1=0,2
P 3.6514625 1.378693 3 P 0 0 ;0=0,1=0,2
P 3.6514625 1.398373 3 P 0 0 ;0=0,1=0,2
P 3.6514625 1.418063 3 P 0 0 ;0=0,1=0,2
P 3.6514625 1.437743 3 P 0 0 ;0=0,1=0,2
P 3.6514625 1.457433 3 P 0 0 ;0=0,1=0,2
P 3.6514625 1.477113 3 P 0 0 ;0=0,1=0,2
P 3.6514625 1.496803 3 P 0 0 ;0=0,1=0,2
P 3.6514625 1.516483 3 P 0 0 ;0=0,1=0,2
P 3.6514625 1.536173 3 P 0 0 ;0=0,1=0,2
P 3.6514625 1.555853 3 P 0 0 ;0=0,1=0,2
P 3.6514625 1.575543 3 P 0 0 ;0=0,1=0,2
P 3.6514625 1.595223 3 P 0 0 ;0=0,1=0,2
P 3.6514625 1.614913 3 P 0 0 ;0=0,1=0,2
P 3.6514625 1.634593 3 P 0 0 ;0=0,1=0,2
P 3.6514625 1.654283 3 P 0 0 ;0=0,1=0,2
P 3.6514625 1.673963 3 P 0 0 ;0=0,1=0,2
P 3.6514625 1.693653 3 P 0 0 ;0=0,1=0,2
P 3.6514625 1.713333 3 P 0 0 ;0=0,1=0,2
P 3.6514625 1.733023 3 P 0 0 ;0=0,1=0,2
P 3.6514625 1.752703 3 P 0 0 ;0=0,1=0,2
P 3.6514625 1.772393 3 P 0 0 ;0=0,1=0,2
P 3.6514625 1.792073 3 P 0 0 ;0=0,1=0,2
P 3.6514625 1.811763 3 P 0 0 ;0=0,1=0,2
P 3.6514625 1.831443 3 P 0 0 ;0=0,1=0,2
P 3.6514625 1.851133 3 P 0 0 ;0=0,1=0,2
P 3.6514625 1.870813 3 P 0 0 ;0=0,1=0,2
P 3.6514625 1.890503 3 P 0 0 ;0=0,1=0,2
P 3.6514625 1.910183 3 P 0 0 ;0=0,1=0,2
P 3.6514625 1.929873 3 P 0 0 ;0=0,1=0,2
P 3.6514625 1.949553 3 P 0 0 ;0=0,1=0,2
P 3.6514625 1.969243 3 P 0 0 ;0=0,1=0,2
P 3.6514625 1.988923 3 P 0 0 ;0=0,1=0,2
P 3.6514625 2.008613 3 P 0 0 ;0=0,1=0,2
P 3.6514625 2.028293 3 P 0 0 ;0=0,1=0,2
P 3.6514625 2.047983 3 P 0 0 ;0=0,1=0,2
P 3.6514625 2.067663 3 P 0 0 ;0=0,1=0,2
P 3.6514625 2.087353 3 P 0 0 ;0=0,1=0,2
P 3.6594094 0.726063 51 P 0 0 ;0=48,1=0,2
P 3.6681102 3.786063 55 P 0 0 ;0=52,1=0,2
P 3.6681102 3.861063 55 P 0 0 ;0=52,1=0,2
P 3.6829133 0.636063 52 P 0 0 ;0=49,1=0,2
P 3.6888425 3.266567 49 P 0 0 ;0=46,1=0,2
P 3.6888425 3.3295591 49 P 0 0 ;0=46,1=0,2
P 3.6938425 3.1176299 48 P 0 0 ;0=45,1=0,2
P 3.6938425 3.1884961 48 P 0 0 ;0=45,1=0,2
P 3.6962598 4.0276378 27 P 0 0 ;0=24,1=0,2
P 3.6962598 4.2441732 27 P 0 0 ;0=24,1=0,2
P 3.7015748 3.786063 55 P 0 0 ;0=52,1=0,2
P 3.7015748 3.861063 55 P 0 0 ;0=52,1=0,2
P 3.7167716 0.636063 52 P 0 0 ;0=49,1=0,2
P 3.7302756 0.726063 51 P 0 0 ;0=48,1=0,2
P 3.7698425 3.2011339 50 P 0 0 ;0=47,1=0,2
P 3.7698425 3.2349922 50 P 0 0 ;0=47,1=0,2
P 3.772559 3.683563 31 P 0 0 ;0=28,1=0,2
P 3.772559 3.708563 31 P 0 0 ;0=28,1=0,2
P 3.772559 3.733563 31 P 0 0 ;0=28,1=0,2
P 3.772559 3.758563 31 P 0 0 ;0=28,1=0,2
P 3.772559 3.783563 31 P 0 0 ;0=28,1=0,2
P 3.772559 3.808563 31 P 0 0 ;0=28,1=0,2
P 3.772559 3.833563 31 P 0 0 ;0=28,1=0,2
P 3.772559 3.858563 31 P 0 0 ;0=28,1=0,2
P 3.7848425 4.126063 71 P 0 0 ;0=58,1=0
P 3.8084646 4.0237008 26 P 0 0 ;0=23,1=0,2
P 3.8399606 4.0237008 26 P 0 0 ;0=23,1=0,2
P 3.8714567 4.0237008 26 P 0 0 ;0=23,1=0,2
P 3.9029528 4.0237008 26 P 0 0 ;0=23,1=0,2
P 3.9114214 1.5996232 16 P 0 0 ;0=13,1=0,2
P 3.9114214 1.6196232 16 P 0 0 ;0=13,1=0,2
P 3.9114214 1.6396232 16 P 0 0 ;0=13,1=0,2
P 3.9114214 1.6596232 16 P 0 0 ;0=13,1=0,2
P 3.9114214 1.6796232 16 P 0 0 ;0=13,1=0,2
P 3.9114214 1.6996232 16 P 0 0 ;0=13,1=0,2
P 3.9114214 1.7196232 16 P 0 0 ;0=13,1=0,2
P 3.9114214 1.7396232 16 P 0 0 ;0=13,1=0,2
P 3.9114214 1.7596232 16 P 0 0 ;0=13,1=0,2
P 3.9114214 1.7796232 16 P 0 0 ;0=13,1=0,2
P 3.9344488 4.0237008 26 P 0 0 ;0=23,1=0,2
P 3.9580709 4.126063 71 P 0 0 ;0=58,1=0
P 3.9598425 2.7806299 48 P 0 0 ;0=45,1=0,2
P 3.9598425 2.8514961 48 P 0 0 ;0=45,1=0,2
P 3.9797272 0.8906186 68 P 0 0 ;0=56,1=0
P 3.9797272 2.4890438 68 P 0 0 ;0=56,1=0
P 3.9871259 3.683563 31 P 0 0 ;0=28,1=0,2
P 3.9871259 3.708563 31 P 0 0 ;0=28,1=0,2
P 3.9871259 3.733563 31 P 0 0 ;0=28,1=0,2
P 3.9871259 3.758563 31 P 0 0 ;0=28,1=0,2
P 3.9871259 3.783563 31 P 0 0 ;0=28,1=0,2
P 3.9871259 3.808563 31 P 0 0 ;0=28,1=0,2
P 3.9871259 3.833563 31 P 0 0 ;0=28,1=0,2
P 3.9871259 3.858563 31 P 0 0 ;0=28,1=0,2
P 4.0398425 3.029567 49 P 0 0 ;0=46,1=0,2
P 4.0398425 3.0925591 49 P 0 0 ;0=46,1=0,2
P 4.0466536 4.0276378 27 P 0 0 ;0=24,1=0,2
P 4.0466536 4.2441732 27 P 0 0 ;0=24,1=0,2
P 4.0624044 2.595343 68 P 0 0 ;0=56,1=0
P 4.0648425 2.7806299 48 P 0 0 ;0=45,1=0,2
P 4.0648425 2.8514961 48 P 0 0 ;0=45,1=0,2
P 4.0689017 1.5996232 16 P 0 0 ;0=13,1=0,2
P 4.0689017 1.6196232 16 P 0 0 ;0=13,1=0,2
P 4.0689017 1.6396232 16 P 0 0 ;0=13,1=0,2
P 4.0689017 1.6596232 16 P 0 0 ;0=13,1=0,2
P 4.0689017 1.6796232 16 P 0 0 ;0=13,1=0,2
P 4.0689017 1.6996232 16 P 0 0 ;0=13,1=0,2
P 4.0689017 1.7196232 16 P 0 0 ;0=13,1=0,2
P 4.0689017 1.7396232 16 P 0 0 ;0=13,1=0,2
P 4.0689017 1.7596232 16 P 0 0 ;0=13,1=0,2
P 4.0689017 1.7796232 16 P 0 0 ;0=13,1=0,2
P 4.1048425 3.7706299 48 P 0 0 ;0=45,1=0,2
P 4.1048425 3.8414961 48 P 0 0 ;0=45,1=0,2
P 4.1098425 3.0441338 50 P 0 0 ;0=47,1=0,2
P 4.1098425 3.0779921 50 P 0 0 ;0=47,1=0,2
P 4.1126772 3.701063 11 P 0 0 ;0=8,1=0,2
P 4.1498425 2.7898819 44 P 0 0 ;0=41,1=0,2
P 4.1498425 2.8422441 44 P 0 0 ;0=41,1=0,2
P 4.1505905 3.6033465 11 P 0 0 ;0=8,1=0,2
P 4.1648425 3.0441338 50 P 0 0 ;0=47,1=0,2
P 4.1648425 3.0779921 50 P 0 0 ;0=47,1=0,2
P 4.1670079 3.701063 11 P 0 0 ;0=8,1=0,2
P 4.1805146 2.595343 68 P 0 0 ;0=56,1=0
P 4.1948425 3.774567 49 P 0 0 ;0=46,1=0,2
P 4.1948425 3.8375591 49 P 0 0 ;0=46,1=0,2
P 4.2049212 3.6033465 11 P 0 0 ;0=8,1=0,2
P 4.2094094 3.246063 51 P 0 0 ;0=48,1=0,2
P 4.2198425 3.0441338 50 P 0 0 ;0=47,1=0,2
P 4.2198425 3.0779921 50 P 0 0 ;0=47,1=0,2
P 4.2348425 2.7806299 48 P 0 0 ;0=45,1=0,2
P 4.2348425 2.8514961 48 P 0 0 ;0=45,1=0,2
P 4.2748425 3.0441338 50 P 0 0 ;0=47,1=0,2
P 4.2748425 3.0779921 50 P 0 0 ;0=47,1=0,2
P 4.2755905 3.6033465 12 P 0 0 ;0=9,1=0,2
P 4.2802756 3.246063 51 P 0 0 ;0=48,1=0,2
P 4.2986248 2.595343 68 P 0 0 ;0=56,1=0
P 4.3277559 1.0074803 70 P 0 0 ;0=57,1=0
P 4.3277559 2.3074803 69 P 0 0 ;0=57,1=0
P 4.3326771 3.6033465 12 P 0 0 ;0=9,1=0,2
P 4.3348425 3.0441338 50 P 0 0 ;0=47,1=0,2
P 4.3348425 3.0779921 50 P 0 0 ;0=47,1=0,2
P 4.3398425 2.7806299 48 P 0 0 ;0=45,1=0,2
P 4.3398425 2.8514961 48 P 0 0 ;0=45,1=0,2
P 4.3948425 3.0441338 50 P 0 0 ;0=47,1=0,2
P 4.3948425 3.0779921 50 P 0 0 ;0=47,1=0,2
P 4.4329134 4.206063 41 P 0 0 ;0=38,1=0,2
P 4.4348425 2.7898819 44 P 0 0 ;0=41,1=0,2
P 4.4348425 2.8422441 44 P 0 0 ;0=41,1=0,2
P 4.4548425 3.0441338 50 P 0 0 ;0=47,1=0,2
P 4.4548425 3.0779921 50 P 0 0 ;0=47,1=0,2
P 4.5667716 4.206063 41 P 0 0 ;0=38,1=0,2
P 4.6526771 4.206063 11 P 0 0 ;0=8,1=0,2
P 4.6526772 4.121063 11 P 0 0 ;0=8,1=0,2
P 4.7070078 4.206063 11 P 0 0 ;0=8,1=0,2
P 4.7070079 4.121063 11 P 0 0 ;0=8,1=0,2
P 4.7277559 2.3074803 69 P 0 0 ;0=57,1=0
P 4.9094488 2.8080708 17 P 0 0 ;0=14,1=0,2
P 4.9094488 3.9616142 17 P 0 0 ;0=14,1=0,2
P 4.9277559 1.0074803 69 P 0 0 ;0=57,1=0
P 4.9277559 2.3074803 69 P 0 0 ;0=57,1=0
P 4.9579134 4.206063 41 P 0 0 ;0=38,1=0,2
P 5.0917716 4.206063 41 P 0 0 ;0=38,1=0,2
P 5.1277559 1.0074803 69 P 0 0 ;0=57,1=0
P 5.1277559 2.3074803 69 P 0 0 ;0=57,1=0
P 5.2126771 4.206063 11 P 0 0 ;0=8,1=0,2
P 5.2126772 4.126063 11 P 0 0 ;0=8,1=0,2
P 5.2670078 4.206063 11 P 0 0 ;0=8,1=0,2
P 5.2670079 4.126063 11 P 0 0 ;0=8,1=0,2
P 5.3277559 1.0074803 69 P 0 0 ;0=57,1=0
P 5.3277559 2.3074803 69 P 0 0 ;0=57,1=0
P 5.5781524 0.8906186 68 P 0 0 ;0=56,1=0
P 5.5781524 1.6898312 68 P 0 0 ;0=56,1=0
P 5.5781524 2.4890438 68 P 0 0 ;0=56,1=0
P 5.6344488 3.359252 52 P 0 0 ;0=49,1=0,2
P 5.6683071 3.359252 52 P 0 0 ;0=49,1=0,2
P 5.7234252 3.8444882 73 P 0 0 ;0=60,1=0
P 5.7234252 4.0255906 73 P 0 0 ;0=60,1=0
P 5.7411417 3.3612205 51 P 0 0 ;0=48,1=0,2
P 5.8120079 3.3612205 51 P 0 0 ;0=48,1=0,2
P 5.8879921 3.701063 19 P 0 0 ;0=16,1=0,2
P 5.9348031 3.9379527 76 P 0 0 ;0=63,1=0
P 6.0048425 2.3388977 53 P 0 0 ;0=50,1=0,2
P 6.0048425 2.3932284 53 P 0 0 ;0=50,1=0,2
P 6.0316929 3.701063 19 P 0 0 ;0=16,1=0,2
P 6.0356772 3.556063 11 P 0 0 ;0=8,1=0,2
P 6.0648425 2.3441339 50 P 0 0 ;0=47,1=0,2
P 6.0648425 2.3779922 50 P 0 0 ;0=47,1=0,2
P 6.0900079 3.556063 11 P 0 0 ;0=8,1=0,2
P 6.0933464 2.171063 20 P 0 0 ;0=17,1=0,2
P 6.1198425 3.8198425 74 P 0 0 ;0=61,1=0
P 6.1198425 4.056063 75 P 0 0 ;0=62,1=0
P 6.1228425 2.4338976 53 P 0 0 ;0=50,1=0,2
P 6.1228425 2.4882283 53 P 0 0 ;0=50,1=0,2
P 6.1563385 2.171063 20 P 0 0 ;0=17,1=0,2
P 6.1574016 2.241063 32 P 0 0 ;0=29,1=0,2
P 6.1574016 2.291063 32 P 0 0 ;0=29,1=0,2
P 6.1574016 2.341063 32 P 0 0 ;0=29,1=0,2
P 6.1574016 2.391063 32 P 0 0 ;0=29,1=0,2
P 6.1979921 3.701063 19 P 0 0 ;0=16,1=0,2
P 6.2029921 3.566063 19 P 0 0 ;0=16,1=0,2
P 6.2348425 2.1288977 53 P 0 0 ;0=50,1=0,2
P 6.2348425 2.1832284 53 P 0 0 ;0=50,1=0,2
P 6.253937 2.7559055 48 P 0 0 ;0=45,1=0,2
P 6.253937 2.8267717 48 P 0 0 ;0=45,1=0,2
P 6.3126772 2.451063 11 P 0 0 ;0=8,1=0,2
P 6.3198425 1.4601181 45 P 0 0 ;0=42,1=0,2
P 6.3198425 1.8420079 45 P 0 0 ;0=42,1=0,2
P 6.3279134 2.501063 52 P 0 0 ;0=49,1=0,2
P 6.3279134 2.556063 52 P 0 0 ;0=49,1=0,2
P 6.3279134 2.611063 52 P 0 0 ;0=49,1=0,2
P 6.3279134 2.656063 52 P 0 0 ;0=49,1=0,2
P 6.3348425 2.1106299 48 P 0 0 ;0=45,1=0,2
P 6.3348425 2.1814961 48 P 0 0 ;0=45,1=0,2
P 6.3416929 3.701063 19 P 0 0 ;0=16,1=0,2
P 6.3466929 3.566063 19 P 0 0 ;0=16,1=0,2
P 6.3522834 2.241063 32 P 0 0 ;0=29,1=0,2
P 6.3522834 2.291063 32 P 0 0 ;0=29,1=0,2
P 6.3522834 2.341063 32 P 0 0 ;0=29,1=0,2
P 6.3522834 2.391063 32 P 0 0 ;0=29,1=0,2
P 6.3617717 2.501063 52 P 0 0 ;0=49,1=0,2
P 6.3617717 2.556063 52 P 0 0 ;0=49,1=0,2
P 6.3617717 2.611063 52 P 0 0 ;0=49,1=0,2
P 6.3617717 2.656063 52 P 0 0 ;0=49,1=0,2
P 6.3670079 2.451063 11 P 0 0 ;0=8,1=0,2
P 6.3720472 2.7559055 48 P 0 0 ;0=45,1=0,2
P 6.3720472 2.8267717 48 P 0 0 ;0=45,1=0,2
P 6.3883268 3.1524803 43 P 0 0 ;0=40,1=0,2
P 6.3883268 3.1721654 43 P 0 0 ;0=40,1=0,2
P 6.3883268 3.1918504 43 P 0 0 ;0=40,1=0,2
P 6.3883268 3.2115354 43 P 0 0 ;0=40,1=0,2
P 6.3883268 3.2312205 43 P 0 0 ;0=40,1=0,2
P 6.3883268 3.2509055 43 P 0 0 ;0=40,1=0,2
P 6.3883268 3.2705906 43 P 0 0 ;0=40,1=0,2
P 6.3883268 3.2902756 43 P 0 0 ;0=40,1=0,2
P 6.3883268 3.3099606 43 P 0 0 ;0=40,1=0,2
P 6.3883268 3.3296457 43 P 0 0 ;0=40,1=0,2
P 6.4203149 3.1500197 42 P 0 0 ;0=39,1=0,2
P 6.4203149 3.3321063 42 P 0 0 ;0=39,1=0,2
P 6.4394094 3.071063 51 P 0 0 ;0=48,1=0,2
P 6.44 3.1500197 42 P 0 0 ;0=39,1=0,2
P 6.44 3.3321063 42 P 0 0 ;0=39,1=0,2
P 6.459685 3.3321063 42 P 0 0 ;0=39,1=0,2
P 6.4598425 3.1500197 42 P 0 0 ;0=39,1=0,2
P 6.4698425 2.2395669 49 P 0 0 ;0=46,1=0,2
P 6.4698425 2.302559 49 P 0 0 ;0=46,1=0,2
P 6.4793701 3.1500197 42 P 0 0 ;0=39,1=0,2
P 6.4793701 3.3321063 42 P 0 0 ;0=39,1=0,2
P 6.5102756 3.071063 51 P 0 0 ;0=48,1=0,2
P 6.5113582 3.1524803 43 P 0 0 ;0=40,1=0,2
P 6.5113582 3.1721654 43 P 0 0 ;0=40,1=0,2
P 6.5113582 3.1918504 43 P 0 0 ;0=40,1=0,2
P 6.5113582 3.2115354 43 P 0 0 ;0=40,1=0,2
P 6.5113582 3.2312205 43 P 0 0 ;0=40,1=0,2
P 6.5113582 3.2509055 43 P 0 0 ;0=40,1=0,2
P 6.5113582 3.2705906 43 P 0 0 ;0=40,1=0,2
P 6.5113582 3.2902756 43 P 0 0 ;0=40,1=0,2
P 6.5113582 3.3099606 43 P 0 0 ;0=40,1=0,2
P 6.5113582 3.3296457 43 P 0 0 ;0=40,1=0,2
P 6.5198425 1.954567 49 P 0 0 ;0=46,1=0,2
P 6.5198425 2.0175591 49 P 0 0 ;0=46,1=0,2
P 6.5694882 3.5895276 73 P 0 0 ;0=67,1=0
P 6.5694882 3.806063 73 P 0 0 ;0=67,1=0
P 6.5694882 4.0934646 79 P 0 0 ;0=66,1=0
P 6.5848425 3.0391338 50 P 0 0 ;0=47,1=0,2
P 6.5848425 3.0729921 50 P 0 0 ;0=47,1=0,2
P 6.6048425 3.1295669 49 P 0 0 ;0=46,1=0,2
P 6.6048425 3.192559 49 P 0 0 ;0=46,1=0,2
P 6.6048425 3.264567 49 P 0 0 ;0=46,1=0,2
P 6.6048425 3.3275591 49 P 0 0 ;0=46,1=0,2
P 6.6294094 1.421063 51 P 0 0 ;0=48,1=0,2
P 6.6294094 1.531063 51 P 0 0 ;0=48,1=0,2
P 6.6374016 1.881063 32 P 0 0 ;0=29,1=0,2
P 6.6374016 1.931063 32 P 0 0 ;0=29,1=0,2
P 6.6374016 1.981063 32 P 0 0 ;0=29,1=0,2
P 6.6374016 2.031063 32 P 0 0 ;0=29,1=0,2
P 6.6429133 1.611063 52 P 0 0 ;0=49,1=0,2
P 6.6429133 1.671063 52 P 0 0 ;0=49,1=0,2
P 6.6429133 1.721063 52 P 0 0 ;0=49,1=0,2
P 6.6429133 1.776063 52 P 0 0 ;0=49,1=0,2
P 6.6598425 2.0956299 48 P 0 0 ;0=45,1=0,2
P 6.6598425 2.1664961 48 P 0 0 ;0=45,1=0,2
P 6.6767716 1.611063 52 P 0 0 ;0=49,1=0,2
P 6.6767716 1.671063 52 P 0 0 ;0=49,1=0,2
P 6.6767716 1.721063 52 P 0 0 ;0=49,1=0,2
P 6.6767716 1.776063 52 P 0 0 ;0=49,1=0,2
P 6.6798425 2.4201181 45 P 0 0 ;0=42,1=0,2
P 6.6798425 2.8020079 45 P 0 0 ;0=42,1=0,2
P 6.7002756 1.421063 51 P 0 0 ;0=48,1=0,2
P 6.7002756 1.531063 51 P 0 0 ;0=48,1=0,2
P 6.7265748 3.1680709 33 P 0 0 ;0=30,1=0,2
P 6.7265748 3.2940551 33 P 0 0 ;0=30,1=0,2
P 6.7276771 1.816063 11 P 0 0 ;0=8,1=0,2
P 6.7348425 3.5895276 73 P 0 0 ;0=67,1=0
P 6.7348425 3.806063 73 P 0 0 ;0=67,1=0
P 6.7498425 2.0888976 53 P 0 0 ;0=50,1=0,2
P 6.7498425 2.1432283 53 P 0 0 ;0=50,1=0,2
P 6.7820078 1.816063 11 P 0 0 ;0=8,1=0,2
P 6.8322834 1.881063 32 P 0 0 ;0=29,1=0,2
P 6.8322834 1.931063 32 P 0 0 ;0=29,1=0,2
P 6.8322834 1.981063 32 P 0 0 ;0=29,1=0,2
P 6.8322834 2.031063 32 P 0 0 ;0=29,1=0,2
P 6.8426771 1.816063 11 P 0 0 ;0=8,1=0,2
P 6.8433465 2.096063 20 P 0 0 ;0=17,1=0,2
P 6.8970078 1.816063 11 P 0 0 ;0=8,1=0,2
P 6.9001969 3.5895276 73 P 0 0 ;0=67,1=0
P 6.9001969 3.806063 73 P 0 0 ;0=67,1=0
P 6.9001969 4.0934646 79 P 0 0 ;0=68,1=0
P 6.9063386 2.096063 20 P 0 0 ;0=17,1=0,2
P 6.9398425 1.8891338 50 P 0 0 ;0=47,1=0,2
P 6.9398425 1.9229921 50 P 0 0 ;0=47,1=0,2
P 6.9431102 3.1680709 33 P 0 0 ;0=30,1=0,2
P 6.9431102 3.2940551 33 P 0 0 ;0=30,1=0,2
P 7.0098425 1.8838977 53 P 0 0 ;0=50,1=0,2
P 7.0098425 1.9382284 53 P 0 0 ;0=50,1=0,2
S P 0
OB 4.6208425 3.246063 I
OS 4.6208425 2.826063
OS 4.5028425 2.708063
OS 4.3556875 2.708063
OS 4.3546243 2.7095544
OS 4.3534727 2.713063
OS 4.3567981 2.7180398
OS 4.3581951 2.725063
OS 4.3581951 2.7499921
OS 4.3763858 2.7499921
OS 4.3763858 2.8112677
OS 4.3032992 2.8112677
OS 4.3032992 2.7499921
OS 4.3214899 2.7499921
OS 4.3214899 2.725063
OS 4.3228869 2.7180398
OS 4.3262123 2.713063
OS 4.3250607 2.7095544
OS 4.3239975 2.708063
OS 4.2506875 2.708063
OS 4.2496243 2.7095544
OS 4.2484727 2.713063
OS 4.2517981 2.7180398
OS 4.2531951 2.725063
OS 4.2531951 2.7499921
OS 4.2713858 2.7499921
OS 4.2713858 2.8112677
OS 4.2120728 2.8112677
OS 4.2100017 2.8162677
OS 4.2142397 2.8205057
OS 4.2222047 2.8205057
OS 4.2239773 2.8208583
OS 4.2713858 2.8208583
OS 4.2713858 2.8331435
OS 4.3032992 2.8331435
OS 4.3032992 2.8208583
OS 4.3763858 2.8208583
OS 4.3763858 2.8331435
OS 4.3842406 2.8331435
OS 4.3881172 2.8292669
OS 4.3940712 2.8252885
OS 4.4010945 2.8238915
OS 4.4040156 2.8238915
OS 4.4075511 2.8203559
OS 4.4075511 2.8171181
OS 4.4075512 2.812118
OS 4.4075512 2.7647559
OS 4.4621338 2.7647559
OS 4.4621338 2.7715293
OS 4.5036614 2.7715293
OS 4.5106846 2.7729263
OS 4.5166386 2.7769047
OS 4.520617 2.7828587
OS 4.522014 2.7898819
OS 4.520617 2.7969051
OS 4.5166386 2.8028591
OS 4.5106846 2.8068375
OS 4.5036614 2.8082345
OS 4.4656694 2.8082345
OS 4.4621339 2.8117701
OS 4.4621339 2.8150079
OS 4.4621338 2.820008
OS 4.4621338 2.8673701
OS 4.4075513 2.8673701
OS 4.4075513 2.8673702
OS 4.4025512 2.8659891
OS 4.3988658 2.8684517
OS 4.3918425 2.8698487
OS 4.3763858 2.8698487
OS 4.3763858 2.8821339
OS 4.3032992 2.8821339
OS 4.3032992 2.8698487
OS 4.2713858 2.8698487
OS 4.2713858 2.8821339
OS 4.1982992 2.8821339
OS 4.1982992 2.854935
OS 4.1936606 2.8518356
OS 4.1748653 2.8330402
OS 4.1708869 2.8270863
OS 4.1694899 2.820063
OS 4.1694899 2.8150079
OS 4.1225512 2.8150079
OS 4.1225512 2.7647559
OS 4.1771338 2.7647559
OS 4.1771338 2.7719107
OS 4.18315 2.7731074
OS 4.1891039 2.7770858
OS 4.1936798 2.7816616
OS 4.1982992 2.7797482
OS 4.1982992 2.7499921
OS 4.2164899 2.7499921
OS 4.2164899 2.725063
OS 4.2178869 2.7180398
OS 4.2212123 2.713063
OS 4.2200607 2.7095544
OS 4.2189975 2.708063
OS 4.0807446 2.7080629
OS 4.078072 2.713063
OS 4.0799142 2.7158201
OS 4.081156 2.722063
OS 4.0799142 2.7283059
OS 4.0780972 2.7310253
OS 4.0780972 2.7499921
OS 4.1013858 2.7499921
OS 4.1013858 2.8112677
OS 4.0282992 2.8112677
OS 4.0282992 2.7499921
OS 4.0515878 2.7499921
OS 4.0515878 2.7310253
OS 4.0497708 2.7283059
OS 4.048529 2.722063
OS 4.0497708 2.7158201
OS 4.051613 2.713063
OS 4.0489404 2.7080629
OS 3.9746959 2.7080629
OS 3.9733494 2.7106566
OS 3.9727356 2.713063
OS 3.9759142 2.7178201
OS 3.977156 2.724063
OS 3.9759142 2.7303059
OS 3.9730972 2.7345219
OS 3.9730972 2.7499921
OS 3.9963858 2.7499921
OS 3.9963858 2.8112677
OS 3.9232992 2.8112677
OS 3.9232992 2.7499921
OS 3.9465878 2.7499921
OS 3.9465878 2.7315286
OS 3.9457708 2.7303059
OS 3.944529 2.724063
OS 3.9457708 2.7178201
OS 3.9489494 2.713063
OS 3.9483356 2.7106566
OS 3.9469891 2.7080629
OS 3.6008178 2.7080629
OS 3.6008178 2.8700787
OS 3.5998865 2.8747609
OS 3.5972342 2.8787302
OS 3.5783322 2.8976322
OS 3.5743629 2.9002845
OS 3.5696807 2.9012158
OS 3.5597716 2.9012158
OS 3.5597716 2.9216614
OS 3.5597717 2.9229764
OS 3.5597717 2.9266615
OS 3.5597716 2.9279765
OS 3.5597716 2.9689054
OS 3.5597717 2.9702205
OS 3.5597717 2.9739055
OS 3.5597716 2.9752206
OS 3.5597716 2.9847234
OS 3.5600067 2.9859054
OS 3.5597716 2.9870874
OS 3.5597716 3.0174645
OS 3.5097965 3.0174645
OS 3.5066221 3.0211496
OS 3.506622 3.0224646
OS 3.506622 3.0824252
OS 3.4970776 3.0824252
OS 3.4970776 3.0877908
OS 3.4980854 3.0879913
OS 3.5033779 3.0915276
OS 3.5069142 3.0968201
OS 3.508156 3.103063
OS 3.5069142 3.1093059
OS 3.5033779 3.1145984
OS 3.4980854 3.1181347
OS 3.4918425 3.1193765
OS 3.4855996 3.1181347
OS 3.4803071 3.1145984
OS 3.4796479 3.1136118
OS 3.3100381 3.1136118
OS 3.3053559 3.1126805
OS 3.3013866 3.1100282
OS 3.2423327 3.0509743
OS 3.2396804 3.047005
OS 3.2387491 3.0423228
OS 3.2387491 2.9883357
OS 3.2189504 2.968537
OS 3.2161543 2.969427
OS 3.2140315 2.9706891
OS 3.2129142 2.9763059
OS 3.2093779 2.9815984
OS 3.2040854 2.9851347
OS 3.1978425 2.9863765
OS 3.1915996 2.9851347
OS 3.1863071 2.9815984
OS 3.1827708 2.9763059
OS 3.181529 2.970063
OS 3.1827708 2.9638201
OS 3.1863071 2.9585276
OS 3.1915996 2.9549913
OS 3.1972164 2.953874
OS 3.1984785 2.9517512
OS 3.1993685 2.9489551
OS 3.1831083 2.9326948
OS 3.180456 2.9287255
OS 3.1795247 2.9240433
OS 3.1795247 2.8247538
OS 3.180456 2.8200716
OS 3.1831083 2.8161023
OS 3.1919802 2.8072304
OS 3.1957598 2.8047049
OS 3.1957598 2.7823544
OS 3.2225866 2.7823544
OS 3.2225866 2.8315866
OS 3.2422519 2.8315866
OS 3.2422519 2.8584134
OS 3.2415658 2.8584134
OS 3.2415658 2.8754833
OS 3.3460778 2.9799952
OS 3.3510854 2.9809913
OS 3.354765 2.9834499
OS 3.4099134 2.9834499
OS 3.4099134 2.9752206
OS 3.4099133 2.9739055
OS 3.4099133 2.9702205
OS 3.4099134 2.9689054
OS 3.4099134 2.9279765
OS 3.4099133 2.9266615
OS 3.4099133 2.9229764
OS 3.4099134 2.9216614
OS 3.4099134 2.9013177
OS 3.3798048 2.9013177
OS 3.3770854 2.9031347
OS 3.3708425 2.9043765
OS 3.3645996 2.9031347
OS 3.3593071 2.8995984
OS 3.3557708 2.8943059
OS 3.3547747 2.8892982
OS 3.2926722 2.8271957
OS 3.2825866 2.8271957
OS 3.2825866 2.8278818
OS 3.2557598 2.8278818
OS 3.2557598 2.7983346
OS 3.2360945 2.7983346
OS 3.2360945 2.7715078
OS 3.2619369 2.7715078
OS 3.2619369 2.7823544
OS 3.2825866 2.7823544
OS 3.2825866 2.8027255
OS 3.2977401 2.8027255
OS 3.3024223 2.8036568
OS 3.3063916 2.8063091
OS 3.3720777 2.8719952
OS 3.3770854 2.8729913
OS 3.3798048 2.8748083
OS 3.4099134 2.8748083
OS 3.4099134 2.8617008
OS 3.4715878 2.8617008
OS 3.4715878 2.824748
OS 3.4555039 2.824748
OS 3.4555039 2.769378
OS 3.4998503 2.769378
OS 3.4998503 2.824748
OS 3.4980972 2.824748
OS 3.4980972 2.8617008
OS 3.5597716 2.8617008
OS 3.5597716 2.8763622
OS 3.5647716 2.8765868
OS 3.5763476 2.8650108
OS 3.5763476 2.7080629
OS 2.8278423 2.7080628
OS 2.6728427 2.8630632
OS 2.6728425 3.325063
OS 2.8988425 3.551063
OS 4.3158422 3.551063
OS 4.6208425 3.246063
OE
OB 3.6228425 3.5023765 H
OS 3.6165996 3.5011347
OS 3.6123543 3.4982981
OS 3.5668425 3.4982981
OS 3.5621603 3.4973668
OS 3.558191 3.4947145
OS 3.5498163 3.4863398
OS 3.5444324 3.488027
OS 3.5413779 3.4925984
OS 3.5360854 3.4961347
OS 3.5298425 3.4973765
OS 3.5235996 3.4961347
OS 3.5183071 3.4925984
OS 3.5147708 3.4873059
OS 3.513529 3.481063
OS 3.5147708 3.4748201
OS 3.5183071 3.4695276
OS 3.5228785 3.4664731
OS 3.5245657 3.4610892
OS 3.5100717 3.4465952
OS 3.5074194 3.4426259
OS 3.5066246 3.4386299
OS 3.4839056 3.4386299
OS 3.4828564 3.439502
OS 3.4813779 3.4445277
OS 3.4849142 3.4498201
OS 3.486156 3.456063
OS 3.4849142 3.4623059
OS 3.4813779 3.4675984
OS 3.4760854 3.4711347
OS 3.4698425 3.4723765
OS 3.4635996 3.4711347
OS 3.4583071 3.4675984
OS 3.4564545 3.4648257
OS 3.4560708 3.4646973
OS 3.4506698 3.4651682
OS 3.4483779 3.4685984
OS 3.4430854 3.4721347
OS 3.4368425 3.4733765
OS 3.4305996 3.4721347
OS 3.4253071 3.4685984
OS 3.4249279 3.4680309
OS 3.4199519 3.4675408
OS 3.4117782 3.4757145
OS 3.4078089 3.4783668
OS 3.4031267 3.4792981
OS 3.3778425 3.4792981
OS 3.3731603 3.4783668
OS 3.369191 3.4757146
OS 3.3576073 3.4641308
OS 3.3525996 3.4631347
OS 3.3483543 3.4602981
OS 3.3112452 3.4602981
OS 3.3061989 3.4653444
OS 3.3022296 3.4679967
OS 3.2975474 3.468928
OS 3.2470472 3.468928
OS 3.242365 3.4679967
OS 3.2383957 3.4653444
OS 3.1261281 3.3530768
OS 3.1234758 3.3491075
OS 3.1225445 3.3444253
OS 3.1225445 3.3074038
OS 3.0836614 3.3074038
OS 3.0759315 3.3058662
OS 3.0693785 3.3014876
OS 3.0649999 3.2949346
OS 3.0634623 3.2872047
OS 3.0649999 3.2794748
OS 3.0693785 3.2729218
OS 3.0759315 3.2685432
OS 3.0836614 3.2670056
OS 3.1387796 3.2670056
OS 3.1465095 3.2685432
OS 3.1530625 3.2729218
OS 3.1574411 3.2794748
OS 3.1589787 3.2872047
OS 3.1574411 3.2949346
OS 3.1530625 3.3014876
OS 3.1470147 3.3055286
OS 3.1470147 3.3393574
OS 3.2521151 3.4444578
OS 3.2924795 3.4444578
OS 3.2975258 3.4394115
OS 3.3014951 3.4367592
OS 3.3054253 3.4359775
OS 3.3054253 3.3624962
OS 3.3028424 3.3603765
OS 3.2965996 3.3591347
OS 3.2913071 3.3555984
OS 3.2877708 3.3503059
OS 3.286529 3.344063
OS 3.2877708 3.3378201
OS 3.2913071 3.3325276
OS 3.2965996 3.3289913
OS 3.3028425 3.3277495
OS 3.3090854 3.3289913
OS 3.3125878 3.3313315
OS 3.3175878 3.3290168
OS 3.3175878 3.3100253
OS 3.3157708 3.3073059
OS 3.314529 3.301063
OS 3.3157708 3.2948201
OS 3.3193071 3.2895276
OS 3.3216553 3.2879586
OS 3.3217107 3.2878198
OS 3.3202196 3.2829044
OS 3.2656991 3.2829044
OS 3.2652066 3.2879043
OS 3.2669122 3.2882437
OS 3.2699401 3.288846
OS 3.2752326 3.2923823
OS 3.2787689 3.2976748
OS 3.2800107 3.3039177
OS 3.2787689 3.3101606
OS 3.2752326 3.3154531
OS 3.2699401 3.3189894
OS 3.2636972 3.3202312
OS 3.2574543 3.3189894
OS 3.2521618 3.3154531
OS 3.2486255 3.3101606
OS 3.2473837 3.3039177
OS 3.2486255 3.2976748
OS 3.2521618 3.2923823
OS 3.2574543 3.288846
OS 3.260482 3.2882437
OS 3.2621878 3.2879043
OS 3.2616953 3.2829044
OS 3.2057086 3.2829044
OS 3.2010264 3.2819731
OS 3.1970571 3.2793208
OS 3.1671761 3.2494398
OS 3.1544308 3.2494398
OS 3.1530625 3.2514876
OS 3.1465095 3.2558662
OS 3.1387796 3.2574038
OS 3.0836614 3.2574038
OS 3.0759315 3.2558662
OS 3.0693785 3.2514876
OS 3.0649999 3.2449346
OS 3.0634623 3.2372047
OS 3.0649999 3.2294748
OS 3.0693785 3.2229218
OS 3.0759315 3.2185432
OS 3.0836614 3.2170056
OS 3.1387796 3.2170056
OS 3.1465095 3.2185432
OS 3.1530625 3.2229218
OS 3.1544308 3.2249696
OS 3.172244 3.2249696
OS 3.1769262 3.2259009
OS 3.1808955 3.2285532
OS 3.2107765 3.2584342
OS 3.3287401 3.2584342
OS 3.3334223 3.2593655
OS 3.3373916 3.2620178
OS 3.3546711 3.2792973
OS 3.3592792 3.2768342
OS 3.358529 3.273063
OS 3.3597708 3.2668201
OS 3.3633071 3.2615276
OS 3.3685996 3.2579913
OS 3.3748425 3.2567495
OS 3.3810854 3.2579913
OS 3.3863779 3.2615276
OS 3.3899142 3.2668201
OS 3.391156 3.273063
OS 3.3899142 3.2793059
OS 3.3863779 3.2845984
OS 3.3810854 3.2881347
OS 3.3748425 3.2893765
OS 3.3710713 3.2886263
OS 3.3686082 3.2932344
OS 3.3934921 3.3181183
OS 3.4231989 3.2884115
OS 3.4271682 3.2857592
OS 3.4318504 3.2848279
OS 3.4813543 3.2848279
OS 3.4855996 3.2819913
OS 3.4918425 3.2807495
OS 3.4980854 3.2819913
OS 3.5033779 3.2855276
OS 3.5069142 3.2908201
OS 3.508156 3.297063
OS 3.5069142 3.3033059
OS 3.5033779 3.3085984
OS 3.4980854 3.3121347
OS 3.4918425 3.3133765
OS 3.4855996 3.3121347
OS 3.4813543 3.3092981
OS 3.4369183 3.3092981
OS 3.4056905 3.3405259
OS 3.4056905 3.3517639
OS 3.4198502 3.3517639
OS 3.4198502 3.3517637
OS 3.4235357 3.3517637
OS 3.4235357 3.3517639
OS 3.4775905 3.3517639
OS 3.4789055 3.3517638
OS 3.4825906 3.3517638
OS 3.4839056 3.3517639
OS 3.5366456 3.3517639
OS 3.5379606 3.3517638
OS 3.5416457 3.3485894
OS 3.5416457 3.3351115
OS 3.5366221 3.3341122
OS 3.5313296 3.3305759
OS 3.5277933 3.3252834
OS 3.5265515 3.3190405
OS 3.5277933 3.3127976
OS 3.5313296 3.3075051
OS 3.5366221 3.3039688
OS 3.542865 3.302727
OS 3.5491079 3.3039688
OS 3.5544004 3.3075051
OS 3.5579367 3.3127976
OS 3.5591785 3.3190405
OS 3.5579367 3.3252834
OS 3.5567372 3.3270787
OS 3.5594098 3.3320787
OS 3.5970157 3.3320787
OS 3.5970157 3.4386299
OS 3.5437835 3.4386299
OS 3.5417124 3.4436299
OS 3.5719104 3.4738279
OS 3.6123543 3.4738279
OS 3.6165996 3.4709913
OS 3.6228425 3.4697495
OS 3.6290854 3.4709913
OS 3.6343779 3.4745276
OS 3.6379142 3.4798201
OS 3.639156 3.486063
OS 3.6379142 3.4923059
OS 3.6343779 3.4975984
OS 3.6290854 3.5011347
OS 3.6228425 3.5023765
OE
OB 3.0688976 3.4119828 H
OS 3.0626547 3.410741
OS 3.057938 3.4075894
OS 3.0488976 3.4075894
OS 3.0442154 3.4066581
OS 3.0402461 3.4040058
OS 2.8356801 3.1994398
OS 2.8001001 3.1994398
OS 2.7987318 3.2014876
OS 2.7921788 3.2058662
OS 2.7844489 3.2074038
OS 2.7293307 3.2074038
OS 2.7216008 3.2058662
OS 2.7150478 3.2014876
OS 2.7106692 3.1949346
OS 2.7091316 3.1872047
OS 2.7106692 3.1794748
OS 2.7150478 3.1729218
OS 2.7216008 3.1685432
OS 2.7293307 3.1670056
OS 2.7844489 3.1670056
OS 2.7921788 3.1685432
OS 2.7987318 3.1729218
OS 2.8001001 3.1749696
OS 2.840748 3.1749696
OS 2.8454302 3.1759009
OS 2.8493995 3.1785532
OS 3.0539655 3.3831192
OS 3.0588808 3.3831192
OS 3.0626547 3.3805976
OS 3.0688976 3.3793558
OS 3.0751405 3.3805976
OS 3.080433 3.3841339
OS 3.0839693 3.3894264
OS 3.0852111 3.3956693
OS 3.0839693 3.4019122
OS 3.080433 3.4072047
OS 3.0751405 3.410741
OS 3.0688976 3.4119828
OE
OB 3.7448425 3.3583765 H
OS 3.7385996 3.3571347
OS 3.7358802 3.3553177
OS 3.7155433 3.3553177
OS 3.7155433 3.3572441
OS 3.6621417 3.3572441
OS 3.6621417 3.3123165
OS 3.6571416 3.3087203
OS 3.6538425 3.3093765
OS 3.6475996 3.3081347
OS 3.6423071 3.3045984
OS 3.6387708 3.2993059
OS 3.637529 3.293063
OS 3.6387708 3.2868201
OS 3.6423071 3.2815276
OS 3.6475996 3.2779913
OS 3.6538425 3.2767495
OS 3.6600854 3.2779913
OS 3.6653779 3.2815276
OS 3.6689142 3.2868201
OS 3.670156 3.293063
OS 3.6693979 3.296874
OS 3.6727539 3.3018741
OS 3.7155433 3.3018741
OS 3.7155433 3.3288083
OS 3.7358802 3.3288083
OS 3.7385996 3.3269913
OS 3.7448425 3.3257495
OS 3.7510854 3.3269913
OS 3.7563779 3.3305276
OS 3.7599142 3.3358201
OS 3.761156 3.342063
OS 3.7599142 3.3483059
OS 3.7563779 3.3535984
OS 3.7510854 3.3571347
OS 3.7448425 3.3583765
OE
OB 2.7844489 3.3074038 H
OS 2.7293307 3.3074038
OS 2.7216008 3.3058662
OS 2.7150478 3.3014876
OS 2.7106692 3.2949346
OS 2.7091316 3.2872047
OS 2.7106692 3.2794748
OS 2.7150478 3.2729218
OS 2.7216008 3.2685432
OS 2.7293307 3.2670056
OS 2.7844489 3.2670056
OS 2.7921788 3.2685432
OS 2.7987318 3.2729218
OS 2.8031104 3.2794748
OS 2.804648 3.2872047
OS 2.8031104 3.2949346
OS 2.7987318 3.3014876
OS 2.7921788 3.3058662
OS 2.7844489 3.3074038
OE
OB 3.4825906 3.2496536 H
OS 3.4789055 3.2496536
OS 3.4775905 3.2496535
OS 3.4248505 3.2496535
OS 3.4235355 3.2496536
OS 3.4198504 3.2496536
OS 3.4185354 3.2496535
OS 3.3657954 3.2496535
OS 3.3644804 3.2496536
OS 3.3607953 3.2496536
OS 3.3594803 3.2496535
OS 3.3054253 3.2496535
OS 3.3054253 3.1800905
OS 3.2820165 3.1566817
OS 3.2818334 3.156804
OS 3.2755905 3.1580458
OS 3.2693476 3.156804
OS 3.2640551 3.1532677
OS 3.2605188 3.1479752
OS 3.259277 3.1417323
OS 3.2605188 3.1354894
OS 3.2640551 3.1301969
OS 3.2693476 3.1266606
OS 3.2755905 3.1254188
OS 3.2818334 3.1266606
OS 3.2871259 3.1301969
OS 3.287954 3.1314363
OS 3.290583 3.1319592
OS 3.2945523 3.1346115
OS 3.3227283 3.1627875
OS 3.3594803 3.1627875
OS 3.3607953 3.1627874
OS 3.3644804 3.1627874
OS 3.3657954 3.1627875
OS 3.4185354 3.1627875
OS 3.4198504 3.1627874
OS 3.4235355 3.1627874
OS 3.4248505 3.1627875
OS 3.4775905 3.1627875
OS 3.4789055 3.1627874
OS 3.4825906 3.1627874
OS 3.4839056 3.1627875
OS 3.5379606 3.1627875
OS 3.5379606 3.2496535
OS 3.4839056 3.2496535
OS 3.4825906 3.2496536
OE
OB 3.7448425 3.2773765 H
OS 3.7385996 3.2761347
OS 3.7333071 3.2725984
OS 3.7297708 3.2673059
OS 3.728529 3.261063
OS 3.7297708 3.2548201
OS 3.7333071 3.2495276
OS 3.7385996 3.2459913
OS 3.7448425 3.2447495
OS 3.7510854 3.2459913
OS 3.7563779 3.2495276
OS 3.7599142 3.2548201
OS 3.761156 3.261063
OS 3.7599142 3.2673059
OS 3.7563779 3.2725984
OS 3.7510854 3.2761347
OS 3.7448425 3.2773765
OE
OB 3.2308425 3.2513765 H
OS 3.2245996 3.2501347
OS 3.2193071 3.2465984
OS 3.2157708 3.2413059
OS 3.214529 3.235063
OS 3.2157708 3.2288201
OS 3.2193071 3.2235276
OS 3.2245996 3.2199913
OS 3.2308425 3.2187495
OS 3.2370854 3.2199913
OS 3.2423779 3.2235276
OS 3.2459142 3.2288201
OS 3.247156 3.235063
OS 3.2459142 3.2413059
OS 3.2423779 3.2465984
OS 3.2370854 3.2501347
OS 3.2308425 3.2513765
OE
OB 3.1387796 3.2074038 H
OS 3.0836614 3.2074038
OS 3.0759315 3.2058662
OS 3.0693785 3.2014876
OS 3.0649999 3.1949346
OS 3.0634623 3.1872047
OS 3.0649999 3.1794748
OS 3.0693785 3.1729218
OS 3.0759315 3.1685432
OS 3.0836614 3.1670056
OS 3.1387796 3.1670056
OS 3.1465095 3.1685432
OS 3.1530625 3.1729218
OS 3.1543651 3.1748712
OS 3.1783409 3.1748712
OS 3.1827335 3.1719362
OS 3.1889764 3.1706944
OS 3.1952193 3.1719362
OS 3.2005118 3.1754725
OS 3.2040481 3.180765
OS 3.2052899 3.1870079
OS 3.2040481 3.1932508
OS 3.2005118 3.1985433
OS 3.1952193 3.2020796
OS 3.1889764 3.2033214
OS 3.1827335 3.2020796
OS 3.1786355 3.1993414
OS 3.1544966 3.1993414
OS 3.1530625 3.2014876
OS 3.1465095 3.2058662
OS 3.1387796 3.2074038
OE
OB 4.4778425 3.1513765 H
OS 4.4715996 3.1501347
OS 4.4663071 3.1465984
OS 4.4627708 3.1413059
OS 4.461529 3.135063
OS 4.4617892 3.1337547
OS 4.4530065 3.124972
OS 4.4474526 3.1264892
OS 4.4468695 3.1287533
OS 4.4469142 3.1288201
OS 4.448156 3.135063
OS 4.4469142 3.1413059
OS 4.4433779 3.1465984
OS 4.4380854 3.1501347
OS 4.4318425 3.1513765
OS 4.4255996 3.1501347
OS 4.4203071 3.1465984
OS 4.4167708 3.1413059
OS 4.415529 3.135063
OS 4.4167708 3.1288201
OS 4.4185878 3.1261007
OS 4.4185878 3.1204824
OS 4.3974833 3.0993779
OS 4.3742441 3.0993779
OS 4.3742441 3.0566063
OS 4.4154409 3.0566063
OS 4.4154409 3.0798455
OS 4.4296247 3.0940293
OS 4.4342441 3.0921158
OS 4.4342441 3.0566063
OS 4.4754409 3.0566063
OS 4.4754409 3.0993779
OS 4.4719735 3.0993779
OS 4.4699024 3.1043779
OS 4.486067 3.1205425
OS 4.4869999 3.1219387
OS 4.4893779 3.1235276
OS 4.4929142 3.1288201
OS 4.494156 3.135063
OS 4.4929142 3.1413059
OS 4.4893779 3.1465984
OS 4.4840854 3.1501347
OS 4.4778425 3.1513765
OE
OB 3.1387796 3.1574038 H
OS 3.0836614 3.1574038
OS 3.0759315 3.1558662
OS 3.0693785 3.1514876
OS 3.0649999 3.1449346
OS 3.0634623 3.1372047
OS 3.0649999 3.1294748
OS 3.0693785 3.1229218
OS 3.0759315 3.1185432
OS 3.0836614 3.1170056
OS 3.1387796 3.1170056
OS 3.1465095 3.1185432
OS 3.1530625 3.1229218
OS 3.1535101 3.1235917
OS 3.1725826 3.1235917
OS 3.1768279 3.1207551
OS 3.1830708 3.1195133
OS 3.1893137 3.1207551
OS 3.1946062 3.1242914
OS 3.1981425 3.1295839
OS 3.1993843 3.1358268
OS 3.1981425 3.1420697
OS 3.1946062 3.1473622
OS 3.1893137 3.1508985
OS 3.1830708 3.1521403
OS 3.1768279 3.1508985
OS 3.1725826 3.1480619
OS 3.1553515 3.1480619
OS 3.1530625 3.1514876
OS 3.1465095 3.1558662
OS 3.1387796 3.1574038
OE
OB 2.7844489 3.1574038 H
OS 2.7293307 3.1574038
OS 2.7216008 3.1558662
OS 2.7150478 3.1514876
OS 2.7106692 3.1449346
OS 2.7091316 3.1372047
OS 2.7106692 3.1294748
OS 2.7150478 3.1229218
OS 2.7216008 3.1185432
OS 2.7293307 3.1170056
OS 2.7844489 3.1170056
OS 2.7921788 3.1185432
OS 2.7987318 3.1229218
OS 2.8031104 3.1294748
OS 2.804648 3.1372047
OS 2.8031104 3.1449346
OS 2.7987318 3.1514876
OS 2.7921788 3.1558662
OS 2.7844489 3.1574038
OE
OB 3.9398425 3.1373765 H
OS 3.9335996 3.1361347
OS 3.9283071 3.1325984
OS 3.9247708 3.1273059
OS 3.923529 3.121063
OS 3.9247708 3.1148201
OS 3.9283071 3.1095276
OS 3.9335996 3.1059913
OS 3.9398425 3.1047495
OS 3.9460854 3.1059913
OS 3.9513779 3.1095276
OS 3.9549142 3.1148201
OS 3.956156 3.121063
OS 3.9549142 3.1273059
OS 3.9513779 3.1325984
OS 3.9460854 3.1361347
OS 3.9398425 3.1373765
OE
OB 3.8068425 3.2513765 H
OS 3.8005996 3.2501347
OS 3.7953071 3.2465984
OS 3.7917708 3.2413059
OS 3.790529 3.235063
OS 3.7917708 3.2288201
OS 3.793481 3.2262604
OS 3.789967 3.2225198
OS 3.7873601 3.2225197
OS 3.7492441 3.2225197
OS 3.7492441 3.1797481
OS 3.7724833 3.1797481
OS 3.8525409 3.0996905
OS 3.8568411 3.0968172
OS 3.8619134 3.0958083
OS 3.8718802 3.0958083
OS 3.8745996 3.0939913
OS 3.8808425 3.0927495
OS 3.8870854 3.0939913
OS 3.8923779 3.0975276
OS 3.8959142 3.1028201
OS 3.897156 3.109063
OS 3.8959142 3.1153059
OS 3.8923779 3.1205984
OS 3.8870854 3.1241347
OS 3.8808425 3.1253765
OS 3.8745996 3.1241347
OS 3.8718802 3.1223177
OS 3.8674037 3.1223177
OS 3.8587005 3.1310209
OS 3.860152 3.1358056
OS 3.8610854 3.1359913
OS 3.8663779 3.1395276
OS 3.8699142 3.1448201
OS 3.871156 3.151063
OS 3.8699142 3.1573059
OS 3.8663779 3.1625984
OS 3.8610854 3.1661347
OS 3.8548425 3.1673765
OS 3.8485996 3.1661347
OS 3.8483568 3.1659724
OS 3.8447519 3.1695773
OS 3.8449142 3.1698201
OS 3.846156 3.176063
OS 3.8449142 3.1823059
OS 3.8413779 3.1875984
OS 3.8360854 3.1911347
OS 3.8298425 3.1923765
OS 3.8235996 3.1911347
OS 3.8183071 3.1875984
OS 3.8162663 3.1845441
OS 3.8106076 3.1832934
OS 3.810036 3.183429
OS 3.810498 3.1889396
OS 3.8113779 3.1895276
OS 3.8149142 3.1948201
OS 3.816156 3.201063
OS 3.8149142 3.2073059
OS 3.8113779 3.2125984
OS 3.8091229 3.2141051
OS 3.8101787 3.2194131
OS 3.8130854 3.2199913
OS 3.8183779 3.2235276
OS 3.8219142 3.2288201
OS 3.823156 3.235063
OS 3.8219142 3.2413059
OS 3.8183779 3.2465984
OS 3.8130854 3.2501347
OS 3.8068425 3.2513765
OE
OB 3.1387796 3.1074038 H
OS 3.0836614 3.1074038
OS 3.0759315 3.1058662
OS 3.0693785 3.1014876
OS 3.0649999 3.0949346
OS 3.0634623 3.0872047
OS 3.0649999 3.0794748
OS 3.0693785 3.0729218
OS 3.0759315 3.0685432
OS 3.0836614 3.0670056
OS 3.1387796 3.0670056
OS 3.1465095 3.0685432
OS 3.1530625 3.0729218
OS 3.1574411 3.0794748
OS 3.1589787 3.0872047
OS 3.1574411 3.0949346
OS 3.1530625 3.1014876
OS 3.1465095 3.1058662
OS 3.1387796 3.1074038
OE
OB 2.7844489 3.1074038 H
OS 2.7293307 3.1074038
OS 2.7216008 3.1058662
OS 2.7150478 3.1014876
OS 2.7106692 3.0949346
OS 2.7091316 3.0872047
OS 2.7106692 3.0794748
OS 2.7150478 3.0729218
OS 2.7216008 3.0685432
OS 2.7293307 3.0670056
OS 2.7844489 3.0670056
OS 2.7921788 3.0685432
OS 2.7987318 3.0729218
OS 2.8031104 3.0794748
OS 2.804648 3.0872047
OS 2.8031104 3.0949346
OS 2.7987318 3.1014876
OS 2.7921788 3.1058662
OS 2.7844489 3.1074038
OE
OB 4.0688425 3.1513765 H
OS 4.0625996 3.1501347
OS 4.0573071 3.1465984
OS 4.0537708 3.1413059
OS 4.0531328 3.1380983
OS 4.0435176 3.1284831
OS 4.0406444 3.124183
OS 4.0398609 3.1202441
OS 4.0131417 3.1202441
OS 4.0131417 3.0648741
OS 4.0665433 3.0648741
OS 4.0665433 3.1140188
OS 4.0718778 3.1193533
OS 4.0750854 3.1199913
OS 4.0803779 3.1235276
OS 4.0839142 3.1288201
OS 4.085156 3.135063
OS 4.0839142 3.1413059
OS 4.0803779 3.1465984
OS 4.0750854 3.1501347
OS 4.0688425 3.1513765
OE
OB 4.3338425 3.1513765 H
OS 4.3275996 3.1501347
OS 4.3223071 3.1465984
OS 4.3187708 3.1413059
OS 4.317529 3.135063
OS 4.3187708 3.1288201
OS 4.3215878 3.1246041
OS 4.3215878 3.0993779
OS 4.3142441 3.0993779
OS 4.3142441 3.0566063
OS 4.3554409 3.0566063
OS 4.3554409 3.0993779
OS 4.3480972 3.0993779
OS 4.3480972 3.1275974
OS 4.3489142 3.1288201
OS 4.350156 3.135063
OS 4.3489142 3.1413059
OS 4.3453779 3.1465984
OS 4.3400854 3.1501347
OS 4.3338425 3.1513765
OE
OB 4.2728425 3.1513765 H
OS 4.2665996 3.1501347
OS 4.2613071 3.1465984
OS 4.2577708 3.1413059
OS 4.256529 3.135063
OS 4.2577708 3.1288201
OS 4.2595878 3.1261007
OS 4.2595878 3.0993779
OS 4.2542441 3.0993779
OS 4.2542441 3.0566063
OS 4.2954409 3.0566063
OS 4.2954409 3.0993779
OS 4.2860972 3.0993779
OS 4.2860972 3.1261007
OS 4.2879142 3.1288201
OS 4.289156 3.135063
OS 4.2879142 3.1413059
OS 4.2843779 3.1465984
OS 4.2790854 3.1501347
OS 4.2728425 3.1513765
OE
OB 4.2400472 3.2826063 H
OS 4.1787716 3.2826063
OS 4.1787716 3.2095197
OS 4.1961547 3.2095197
OS 4.1961547 3.1448737
OS 4.1937708 3.1413059
OS 4.192529 3.135063
OS 4.1937708 3.1288201
OS 4.1973071 3.1235276
OS 4.1996851 3.1219387
OS 4.200618 3.1205425
OS 4.2065878 3.1145727
OS 4.2065878 3.0993779
OS 4.1992441 3.0993779
OS 4.1992441 3.0566063
OS 4.2404409 3.0566063
OS 4.2404409 3.0993779
OS 4.2330972 3.0993779
OS 4.2330972 3.120063
OS 4.2320882 3.1251354
OS 4.229215 3.1294355
OS 4.2248958 3.1337547
OS 4.225156 3.135063
OS 4.2239142 3.1413059
OS 4.2226641 3.1431768
OS 4.2226641 3.2095197
OS 4.2400472 3.2095197
OS 4.2400472 3.2826063
OE
OB 4.1528425 3.1513765 H
OS 4.1465996 3.1501347
OS 4.1413071 3.1465984
OS 4.1377708 3.1413059
OS 4.136529 3.135063
OS 4.1377708 3.1288201
OS 4.1413071 3.1235276
OS 4.1416547 3.1232953
OS 4.1417448 3.1228426
OS 4.144618 3.1185425
OS 4.1515878 3.1115727
OS 4.1515878 3.0993779
OS 4.1442441 3.0993779
OS 4.1442441 3.0566063
OS 4.1854409 3.0566063
OS 4.1854409 3.0993779
OS 4.1780972 3.0993779
OS 4.1780972 3.117063
OS 4.1770882 3.1221354
OS 4.174215 3.1264355
OS 4.1685639 3.1320866
OS 4.169156 3.135063
OS 4.1679142 3.1413059
OS 4.1643779 3.1465984
OS 4.1590854 3.1501347
OS 4.1528425 3.1513765
OE
OB 4.1148425 3.1513765 H
OS 4.1085996 3.1501347
OS 4.1033071 3.1465984
OS 4.0997708 3.1413059
OS 4.098529 3.135063
OS 4.0989172 3.1331115
OS 4.0975968 3.1311354
OS 4.0965878 3.126063
OS 4.0965878 3.0993779
OS 4.0892441 3.0993779
OS 4.0892441 3.0566063
OS 4.1304409 3.0566063
OS 4.1304409 3.0993779
OS 4.1230972 3.0993779
OS 4.1230972 3.1205877
OS 4.1239999 3.1219387
OS 4.1263779 3.1235276
OS 4.1299142 3.1288201
OS 4.131156 3.135063
OS 4.1299142 3.1413059
OS 4.1263779 3.1465984
OS 4.1210854 3.1501347
OS 4.1148425 3.1513765
OE
OB 3.7303858 3.1482677 H
OS 3.6572992 3.1482677
OS 3.6572992 3.0869921
OS 3.7045878 3.0869921
OS 3.7045878 3.0810253
OS 3.7027708 3.0783059
OS 3.701529 3.072063
OS 3.7027708 3.0658201
OS 3.7063071 3.0605276
OS 3.7115996 3.0569913
OS 3.7178425 3.0557495
OS 3.7240854 3.0569913
OS 3.7293779 3.0605276
OS 3.7329142 3.0658201
OS 3.734156 3.072063
OS 3.7329142 3.0783059
OS 3.7310972 3.0810253
OS 3.7310972 3.0936299
OS 3.7306405 3.095926
OS 3.7306405 3.0999921
OS 3.7303858 3.1012725
OS 3.7303858 3.1482677
OE
OB 3.1387796 3.0574038 H
OS 3.0836614 3.0574038
OS 3.0759315 3.0558662
OS 3.0693785 3.0514876
OS 3.0649999 3.0449346
OS 3.0634623 3.0372047
OS 3.0649999 3.0294748
OS 3.0693785 3.0229218
OS 3.0759315 3.0185432
OS 3.0836614 3.0170056
OS 3.1387796 3.0170056
OS 3.1465095 3.0185432
OS 3.1530625 3.0229218
OS 3.1574411 3.0294748
OS 3.1589787 3.0372047
OS 3.1574411 3.0449346
OS 3.1530625 3.0514876
OS 3.1465095 3.0558662
OS 3.1387796 3.0574038
OE
OB 2.7844489 3.0574038 H
OS 2.7293307 3.0574038
OS 2.7216008 3.0558662
OS 2.7150478 3.0514876
OS 2.7106692 3.0449346
OS 2.7091316 3.0372047
OS 2.7106692 3.0294748
OS 2.7150478 3.0229218
OS 2.7216008 3.0185432
OS 2.7293307 3.0170056
OS 2.7844489 3.0170056
OS 2.7921788 3.0185432
OS 2.7987318 3.0229218
OS 2.8031104 3.0294748
OS 2.804648 3.0372047
OS 2.8031104 3.0449346
OS 2.7987318 3.0514876
OS 2.7921788 3.0558662
OS 2.7844489 3.0574038
OE
OB 3.1387796 3.0074038 H
OS 3.0836614 3.0074038
OS 3.0759315 3.0058662
OS 3.0693785 3.0014876
OS 3.0649999 2.9949346
OS 3.0634623 2.9872047
OS 3.0649999 2.9794748
OS 3.0693785 2.9729218
OS 3.0759315 2.9685432
OS 3.0836614 2.9670056
OS 3.1387796 2.9670056
OS 3.1465095 2.9685432
OS 3.1530625 2.9729218
OS 3.1574411 2.9794748
OS 3.1589787 2.9872047
OS 3.1574411 2.9949346
OS 3.1530625 3.0014876
OS 3.1465095 3.0058662
OS 3.1387796 3.0074038
OE
OB 2.7844489 3.0074038 H
OS 2.7293307 3.0074038
OS 2.7216008 3.0058662
OS 2.7150478 3.0014876
OS 2.7106692 2.9949346
OS 2.7091316 2.9872047
OS 2.7106692 2.9794748
OS 2.7150478 2.9729218
OS 2.7216008 2.9685432
OS 2.7293307 2.9670056
OS 2.7844489 2.9670056
OS 2.7921788 2.9685432
OS 2.7987318 2.9729218
OS 2.8031104 2.9794748
OS 2.804648 2.9872047
OS 2.8031104 2.9949346
OS 2.7987318 3.0014876
OS 2.7921788 3.0058662
OS 2.7844489 3.0074038
OE
OB 3.1387796 2.9574038 H
OS 3.0836614 2.9574038
OS 3.0759315 2.9558662
OS 3.0693785 2.9514876
OS 3.0649999 2.9449346
OS 3.0634623 2.9372047
OS 3.0649999 2.9294748
OS 3.0693785 2.9229218
OS 3.0759315 2.9185432
OS 3.0836614 2.9170056
OS 3.1387796 2.9170056
OS 3.1465095 2.9185432
OS 3.1530625 2.9229218
OS 3.1574411 2.9294748
OS 3.1589787 2.9372047
OS 3.1574411 2.9449346
OS 3.1530625 2.9514876
OS 3.1465095 2.9558662
OS 3.1387796 2.9574038
OE
OB 2.7844489 2.9574038 H
OS 2.7293307 2.9574038
OS 2.7216008 2.9558662
OS 2.7150478 2.9514876
OS 2.7106692 2.9449346
OS 2.7091316 2.9372047
OS 2.7106692 2.9294748
OS 2.7150478 2.9229218
OS 2.7216008 2.9185432
OS 2.7293307 2.9170056
OS 2.7844489 2.9170056
OS 2.7921788 2.9185432
OS 2.7987318 2.9229218
OS 2.8031104 2.9294748
OS 2.804648 2.9372047
OS 2.8031104 2.9449346
OS 2.7987318 2.9514876
OS 2.7921788 2.9558662
OS 2.7844489 2.9574038
OE
SE
S P 0
OB 6.8051181 2.7027559 I
OS 6.3523621 2.7027559
OS 6.3326771 2.6830709
OS 6.3326771 2.4862205
OS 6.1161417 2.4862205
OS 6.1109186 2.4809974
OS 6.1062992 2.4829109
OS 6.1062992 2.7716536
OS 6.4507874 2.7716536
OS 6.4606299 2.7814961
OS 6.4606299 2.9685039
OS 6.8051181 2.9685039
OS 6.8051181 2.7027559
OE
SE
S P 0
OB 6.9429134 1.511811 I
OS 6.726378 1.2952756
OS 6.6633858 1.2952756
OS 6.6633858 1.5904646
OS 6.6642991 1.5904646
OS 6.6642991 1.6316614
OS 6.6633858 1.6316614
OS 6.6633858 1.6504646
OS 6.6642991 1.6504646
OS 6.6642991 1.6916614
OS 6.6633858 1.6916614
OS 6.6633858 1.7004646
OS 6.6642991 1.7004646
OS 6.6642991 1.7416614
OS 6.6633858 1.7416614
OS 6.6633858 1.7554646
OS 6.6642991 1.7554646
OS 6.6642991 1.7883149
OS 6.6882033 1.8122191
OS 6.6920854 1.8129913
OS 6.6948048 1.8148083
OS 6.7055039 1.8148083
OS 6.7055039 1.788378
OS 6.7498503 1.788378
OS 6.7498503 1.8437479
OS 6.7537284 1.8464567
OS 6.7559565 1.8464567
OS 6.7598346 1.8437479
OS 6.7598346 1.788378
OS 6.804181 1.788378
OS 6.804181 1.8437479
OS 6.8080591 1.8464567
OS 6.8709565 1.8464567
OS 6.8748346 1.8437479
OS 6.8748346 1.788378
OS 6.919181 1.788378
OS 6.919181 1.8437479
OS 6.9230591 1.8464567
OS 6.9429134 1.8464567
OS 6.9429134 1.511811
OE
SE
S P 0
OB 7.0019685 3.5 I
OS 6.4704724 3.5
OS 6.4704724 3.8937008
OS 7.0019685 3.8937008
OS 7.0019685 3.5
OE
OB 6.9001969 3.6472339 H
OS 6.8852614 3.6452676
OS 6.8713437 3.6395027
OS 6.8593924 3.6303321
OS 6.8502218 3.6183808
OS 6.8444569 3.6044631
OS 6.8424906 3.5895276
OS 6.8444569 3.5745921
OS 6.8502218 3.5606744
OS 6.8593924 3.5487231
OS 6.8713437 3.5395525
OS 6.8852614 3.5337876
OS 6.9001969 3.5318213
OS 6.9151324 3.5337876
OS 6.9290501 3.5395525
OS 6.9410014 3.5487231
OS 6.950172 3.5606744
OS 6.9559369 3.5745921
OS 6.9579032 3.5895276
OS 6.9559369 3.6044631
OS 6.950172 3.6183808
OS 6.9410014 3.6303321
OS 6.9290501 3.6395027
OS 6.9151324 3.6452676
OS 6.9001969 3.6472339
OE
OB 6.7348425 3.6472339 H
OS 6.719907 3.6452676
OS 6.7059893 3.6395027
OS 6.694038 3.6303321
OS 6.6848674 3.6183808
OS 6.6791025 3.6044631
OS 6.6771362 3.5895276
OS 6.6791025 3.5745921
OS 6.6848674 3.5606744
OS 6.694038 3.5487231
OS 6.7059893 3.5395525
OS 6.719907 3.5337876
OS 6.7348425 3.5318213
OS 6.749778 3.5337876
OS 6.7636957 3.5395525
OS 6.775647 3.5487231
OS 6.7848176 3.5606744
OS 6.7905825 3.5745921
OS 6.7925488 3.5895276
OS 6.7905825 3.6044631
OS 6.7848176 3.6183808
OS 6.775647 3.6303321
OS 6.7636957 3.6395027
OS 6.749778 3.6452676
OS 6.7348425 3.6472339
OE
OB 6.5694882 3.6472339 H
OS 6.5545527 3.6452676
OS 6.540635 3.6395027
OS 6.5286837 3.6303321
OS 6.5195131 3.6183807
OS 6.5137482 3.6044631
OS 6.5117819 3.5895276
OS 6.5137482 3.5745921
OS 6.5195131 3.5606745
OS 6.5286837 3.5487231
OS 6.540635 3.5395525
OS 6.5545527 3.5337876
OS 6.5694882 3.5318213
OS 6.5844237 3.5337876
OS 6.5983414 3.5395525
OS 6.6102927 3.5487231
OS 6.6194633 3.5606745
OS 6.6252282 3.5745921
OS 6.6271945 3.5895276
OS 6.6252282 3.6044631
OS 6.6194633 3.6183807
OS 6.6102927 3.6303321
OS 6.5983414 3.6395027
OS 6.5844237 3.6452676
OS 6.5694882 3.6472339
OE
SE
P 0.149508 2.830047 80 P 0 0 ;0=70,1=1
P 0.149508 3.853669 80 P 0 0 ;0=70,1=1
P 0.6538425 1.551063 59 P 0 0 ;0=69,1=1
P 0.6539669 2.5938902 59 P 0 0 ;0=69,1=1
P 0.6548425 0.790063 59 P 0 0 ;0=69,1=1
P 0.6548425 1.314063 59 P 0 0 ;0=69,1=1
P 0.6548425 1.839063 59 P 0 0 ;0=69,1=1
P 0.6548425 2.073063 59 P 0 0 ;0=69,1=1
P 0.6548425 2.365063 59 P 0 0 ;0=69,1=1
P 0.6558425 1.028063 59 P 0 0 ;0=69,1=1
P 0.9370078 2.3179133 59 P 0 0 ;0=69,1=1
P 0.988189 1.7175197 59 P 0 0 ;0=69,1=1
P 0.9901575 0.6870079 59 P 0 0 ;0=69,1=1
P 0.996063 1.1870079 59 P 0 0 ;0=69,1=1
P 0.9968357 2.256036 59 P 0 0 ;0=69,1=1
P 1.0048425 0.906063 59 P 0 0 ;0=69,1=1
P 1.0088425 1.430063 59 P 0 0 ;0=69,1=1
P 1.0098425 1.956063 59 P 0 0 ;0=69,1=1
P 1.0208425 2.481063 59 P 0 0 ;0=69,1=1
P 1.2428425 1.472063 59 P 0 0 ;0=69,1=1
P 1.2488425 2.000063 59 P 0 0 ;0=69,1=1
P 1.2568425 0.942063 59 P 0 0 ;0=69,1=1
P 1.2618425 2.482063 59 P 0 0 ;0=69,1=1
P 1.2948425 4.256063 59 P 0 0 ;0=69,1=1
P 1.3454724 4.1751969 59 P 0 0 ;0=69,1=1
P 1.3937008 1.8169291 59 P 0 0 ;0=69,1=1
P 1.4084645 3.980315 59 P 0 0 ;0=69,1=1
P 1.4408425 3.557063 59 P 0 0 ;0=69,1=1
P 1.4598425 3.147063 59 P 0 0 ;0=69,1=1
P 1.5498425 3.621063 59 P 0 0 ;0=69,1=1
P 1.5578425 4.229063 59 P 0 0 ;0=69,1=1
P 1.5679134 1.2854331 59 P 0 0 ;0=69,1=1
P 1.5682025 2.067703 59 P 0 0 ;0=69,1=1
P 1.5698819 4.1712599 59 P 0 0 ;0=69,1=1
P 1.5748425 3.596063 59 P 0 0 ;0=69,1=1
P 1.6198425 2.121063 59 P 0 0 ;0=69,1=1
P 1.6708425 1.595063 59 P 0 0 ;0=69,1=1
P 1.6708425 1.694063 59 P 0 0 ;0=69,1=1
P 1.6718425 1.399063 59 P 0 0 ;0=69,1=1
P 1.6718425 1.497063 59 P 0 0 ;0=69,1=1
P 1.6718425 1.792063 59 P 0 0 ;0=69,1=1
P 1.6748425 1.989063 59 P 0 0 ;0=69,1=1
P 1.6758425 1.891063 59 P 0 0 ;0=69,1=1
P 1.6918425 4.079063 59 P 0 0 ;0=69,1=1
P 1.7148425 1.595063 59 P 0 0 ;0=69,1=1
P 1.7168425 1.399063 59 P 0 0 ;0=69,1=1
P 1.7188425 1.497063 59 P 0 0 ;0=69,1=1
P 1.7188425 1.792063 59 P 0 0 ;0=69,1=1
P 1.7198425 1.536063 59 P 0 0 ;0=69,1=1
P 1.7218425 1.694063 59 P 0 0 ;0=69,1=1
P 1.7218425 1.890063 59 P 0 0 ;0=69,1=1
P 1.7218425 1.989063 59 P 0 0 ;0=69,1=1
P 1.7268425 4.329374 59 P 0 0 ;0=69,1=1
P 1.7498425 4.110063 59 P 0 0 ;0=69,1=1
P 1.7548425 2.126063 59 P 0 0 ;0=69,1=1
P 1.7548425 3.661063 59 P 0 0 ;0=69,1=1
P 1.7798425 4.156063 59 P 0 0 ;0=69,1=1
P 1.7888425 4.329374 59 P 0 0 ;0=69,1=1
P 1.7978425 0.355063 59 P 0 0 ;0=69,1=1
P 1.7982283 1.3041339 59 P 0 0 ;0=69,1=1
P 1.8227825 1.674003 59 P 0 0 ;0=69,1=1
P 1.8326771 0.2559055 59 P 0 0 ;0=69,1=1
P 1.8326771 0.2874016 59 P 0 0 ;0=69,1=1
P 1.8498425 3.701063 59 P 0 0 ;0=69,1=1
P 1.8523622 0.2559055 59 P 0 0 ;0=69,1=1
P 1.8523622 0.2874016 59 P 0 0 ;0=69,1=1
P 1.8720472 0.2559055 59 P 0 0 ;0=69,1=1
P 1.8720472 0.2874016 59 P 0 0 ;0=69,1=1
P 1.8799377 1.811803 59 P 0 0 ;0=69,1=1
P 1.8848425 2.071063 59 P 0 0 ;0=69,1=1
P 1.8848425 3.601063 59 P 0 0 ;0=69,1=1
P 1.8938425 1.693063 59 P 0 0 ;0=69,1=1
P 1.8973025 1.516523 59 P 0 0 ;0=69,1=1
P 1.9038425 4.018063 59 P 0 0 ;0=69,1=1
P 1.9161425 0.244763 59 P 0 0 ;0=69,1=1
P 2.0048425 1.336063 59 P 0 0 ;0=69,1=1
P 2.0048425 3.816063 59 P 0 0 ;0=69,1=1
P 2.0288425 1.361663 59 P 0 0 ;0=69,1=1
P 2.0298425 3.836063 59 P 0 0 ;0=69,1=1
P 2.0348425 0.246063 59 P 0 0 ;0=69,1=1
P 2.0598425 1.386063 59 P 0 0 ;0=69,1=1
P 2.0598425 3.871063 59 P 0 0 ;0=69,1=1
P 2.0767716 0.2559055 59 P 0 0 ;0=69,1=1
P 2.0767716 0.2874016 59 P 0 0 ;0=69,1=1
P 2.0838425 1.411663 59 P 0 0 ;0=69,1=1
P 2.0848425 3.896063 59 P 0 0 ;0=69,1=1
P 2.1122047 0.2559055 59 P 0 0 ;0=69,1=1
P 2.1122047 0.2874016 59 P 0 0 ;0=69,1=1
P 2.1398425 3.611063 59 P 0 0 ;0=69,1=1
P 2.1398425 3.738063 59 P 0 0 ;0=69,1=1
P 2.1460663 4.1037909 59 P 0 0 ;0=69,1=1
P 2.1468425 2.753063 59 P 0 0 ;0=69,1=1
P 2.1515748 0.2559055 59 P 0 0 ;0=69,1=1
P 2.1515748 0.2874016 59 P 0 0 ;0=69,1=1
P 2.2058425 3.200063 59 P 0 0 ;0=69,1=1
P 2.2068425 1.298063 59 P 0 0 ;0=69,1=1
P 2.2317425 2.584163 59 P 0 0 ;0=69,1=1
P 2.2348425 3.506063 59 P 0 0 ;0=69,1=1
P 2.2523425 2.613563 59 P 0 0 ;0=69,1=1
P 2.2538425 2.279063 59 P 0 0 ;0=69,1=1
P 2.253937 4.0866142 59 P 0 0 ;0=69,1=1
P 2.2548425 3.536063 59 P 0 0 ;0=69,1=1
P 2.2588425 3.741063 59 P 0 0 ;0=69,1=1
P 2.2598425 3.261063 59 P 0 0 ;0=69,1=1
P 2.2720325 2.463873 59 P 0 0 ;0=69,1=1
P 2.2748425 1.506063 59 P 0 0 ;0=69,1=1
P 2.2908425 4.217063 59 P 0 0 ;0=69,1=1
P 2.2998425 1.916063 59 P 0 0 ;0=69,1=1
P 2.3098425 0.246063 59 P 0 0 ;0=69,1=1
P 2.3114125 1.0900094 59 P 0 0 ;0=69,1=1
P 2.3118425 0.934063 59 P 0 0 ;0=69,1=1
P 2.3215354 2.586063 59 P 0 0 ;0=69,1=1
P 2.3215354 3.361063 59 P 0 0 ;0=69,1=1
P 2.3308425 2.215063 59 P 0 0 ;0=69,1=1
P 2.3503937 0.4055118 59 P 0 0 ;0=69,1=1
P 2.3533464 4.0177165 59 P 0 0 ;0=69,1=1
P 2.3848425 1.941063 59 P 0 0 ;0=69,1=1
P 2.3897638 0.4055118 59 P 0 0 ;0=69,1=1
P 2.3898425 3.481063 59 P 0 0 ;0=69,1=1
P 2.394685 2.7204724 59 P 0 0 ;0=69,1=1
P 2.4048425 2.412063 59 P 0 0 ;0=69,1=1
P 2.4098325 0.932053 59 P 0 0 ;0=69,1=1
P 2.4098325 1.088053 59 P 0 0 ;0=69,1=1
P 2.4098425 1.967063 59 P 0 0 ;0=69,1=1
P 2.4098425 2.283063 59 P 0 0 ;0=69,1=1
P 2.4098425 2.314063 59 P 0 0 ;0=69,1=1
P 2.4098425 2.579063 59 P 0 0 ;0=69,1=1
P 2.4133858 0.2795276 59 P 0 0 ;0=69,1=1
P 2.4138425 3.295063 59 P 0 0 ;0=69,1=1
P 2.4140551 3.1998504 59 P 0 0 ;0=69,1=1
P 2.4187174 3.1185066 59 P 0 0 ;0=69,1=1
P 2.4192759 2.7886295 59 P 0 0 ;0=69,1=1
P 2.4291925 2.621063 59 P 0 0 ;0=69,1=1
P 2.4348425 3.546063 59 P 0 0 ;0=69,1=1
P 2.4448819 0.2795276 59 P 0 0 ;0=69,1=1
P 2.4468425 1.437063 59 P 0 0 ;0=69,1=1
P 2.4470546 0.2425914 59 P 0 0 ;0=69,1=1
P 2.4508425 2.282063 59 P 0 0 ;0=69,1=1
P 2.462374 3.1722441 59 P 0 0 ;0=69,1=1
P 2.4698827 0.4109883 59 P 0 0 ;0=69,1=1
P 2.4738425 2.980063 59 P 0 0 ;0=69,1=1
P 2.4758425 2.291063 59 P 0 0 ;0=69,1=1
P 2.4758425 2.456063 59 P 0 0 ;0=69,1=1
P 2.4788425 0.937063 59 P 0 0 ;0=69,1=1
P 2.4888425 2.413063 59 P 0 0 ;0=69,1=1
P 2.4948425 2.661063 59 P 0 0 ;0=69,1=1
P 2.4948425 2.696063 59 P 0 0 ;0=69,1=1
P 2.4998425 2.236063 59 P 0 0 ;0=69,1=1
P 2.5028425 1.316063 59 P 0 0 ;0=69,1=1
P 2.5082625 0.931483 59 P 0 0 ;0=69,1=1
P 2.5088425 1.090063 59 P 0 0 ;0=69,1=1
P 2.511811 0.4055118 59 P 0 0 ;0=69,1=1
P 2.5258425 2.463063 59 P 0 0 ;0=69,1=1
P 2.531398 2.830047 80 P 0 0 ;0=70,1=1
P 2.531398 3.853669 80 P 0 0 ;0=70,1=1
P 2.5460625 0.244843 59 P 0 0 ;0=69,1=1
P 2.5498425 1.755063 59 P 0 0 ;0=69,1=1
P 2.5708425 4.283063 59 P 0 0 ;0=69,1=1
P 2.5758425 2.412063 59 P 0 0 ;0=69,1=1
P 2.5787402 0.2795276 59 P 0 0 ;0=69,1=1
P 2.5798425 1.790063 59 P 0 0 ;0=69,1=1
P 2.5798425 2.281063 59 P 0 0 ;0=69,1=1
P 2.5798425 3.486063 59 P 0 0 ;0=69,1=1
P 2.5818425 2.308063 59 P 0 0 ;0=69,1=1
P 2.5868425 2.569063 59 P 0 0 ;0=69,1=1
P 2.5908425 3.288063 59 P 0 0 ;0=69,1=1
P 2.5918425 3.1862205 59 P 0 0 ;0=69,1=1
P 2.5984252 0.7952756 59 P 0 0 ;0=69,1=1
P 2.5998425 2.436063 59 P 0 0 ;0=69,1=1
P 2.6048425 1.734063 59 P 0 0 ;0=69,1=1
P 2.6066825 0.931903 59 P 0 0 ;0=69,1=1
P 2.6068425 1.091063 59 P 0 0 ;0=69,1=1
P 2.6102362 0.2795276 59 P 0 0 ;0=69,1=1
P 2.6220472 0.976378 59 P 0 0 ;0=69,1=1
P 2.6248425 2.461063 59 P 0 0 ;0=69,1=1
P 2.6259843 0.7952756 59 P 0 0 ;0=69,1=1
P 2.6268425 1.770063 59 P 0 0 ;0=69,1=1
P 2.6318425 2.876063 59 P 0 0 ;0=69,1=1
P 2.6348425 3.406063 59 P 0 0 ;0=69,1=1
P 2.636874 0.2479055 59 P 0 0 ;0=69,1=1
P 2.6438425 1.616063 59 P 0 0 ;0=69,1=1
P 2.6458425 2.274063 59 P 0 0 ;0=69,1=1
P 2.6496063 0.976378 59 P 0 0 ;0=69,1=1
P 2.6653543 0.4055118 59 P 0 0 ;0=69,1=1
P 2.6653543 0.7952756 59 P 0 0 ;0=69,1=1
P 2.6658425 1.092063 59 P 0 0 ;0=69,1=1
P 2.6658425 2.291063 59 P 0 0 ;0=69,1=1
P 2.6668425 1.640063 59 P 0 0 ;0=69,1=1
P 2.6748425 3.501063 59 P 0 0 ;0=69,1=1
P 2.6798425 3.661063 59 P 0 0 ;0=69,1=1
P 2.6811024 0.976378 59 P 0 0 ;0=69,1=1
P 2.6858425 2.311063 59 P 0 0 ;0=69,1=1
P 2.6858425 2.568063 59 P 0 0 ;0=69,1=1
P 2.6929134 0.7952756 59 P 0 0 ;0=69,1=1
P 2.6929134 2.7214567 59 P 0 0 ;0=69,1=1
P 2.6948425 1.481063 59 P 0 0 ;0=69,1=1
P 2.7028425 2.289063 59 P 0 0 ;0=69,1=1
P 2.7047244 0.4055118 59 P 0 0 ;0=69,1=1
P 2.7086614 0.976378 59 P 0 0 ;0=69,1=1
P 2.7198425 1.591063 59 P 0 0 ;0=69,1=1
P 2.7224094 3.7860709 59 P 0 0 ;0=69,1=1
P 2.7244825 1.093063 59 P 0 0 ;0=69,1=1
P 2.7248425 3.521063 59 P 0 0 ;0=69,1=1
P 2.7248425 3.729063 59 P 0 0 ;0=69,1=1
P 2.7268425 2.293063 59 P 0 0 ;0=69,1=1
P 2.7322835 0.7952756 59 P 0 0 ;0=69,1=1
P 2.7401575 0.976378 59 P 0 0 ;0=69,1=1
P 2.74882 0.282312 59 P 0 0 ;0=69,1=1
P 2.7598425 0.7952756 59 P 0 0 ;0=69,1=1
P 2.7677165 0.976378 59 P 0 0 ;0=69,1=1
P 2.7748425 3.566063 59 P 0 0 ;0=69,1=1
P 2.7795276 0.2795276 59 P 0 0 ;0=69,1=1
P 2.7838425 2.429063 59 P 0 0 ;0=69,1=1
P 2.7838425 2.568063 59 P 0 0 ;0=69,1=1
P 2.7841625 1.094063 59 P 0 0 ;0=69,1=1
P 2.7992126 0.7952756 59 P 0 0 ;0=69,1=1
P 2.7992126 0.976378 59 P 0 0 ;0=69,1=1
P 2.7998425 3.616063 59 P 0 0 ;0=69,1=1
P 2.7999951 0.2519685 59 P 0 0 ;0=69,1=1
P 2.8038425 2.307063 59 P 0 0 ;0=69,1=1
P 2.8218425 2.601063 59 P 0 0 ;0=69,1=1
P 2.8219832 0.4078519 59 P 0 0 ;0=69,1=1
P 2.8267717 0.7952756 59 P 0 0 ;0=69,1=1
P 2.8267717 0.976378 59 P 0 0 ;0=69,1=1
P 2.8418425 2.263063 59 P 0 0 ;0=69,1=1
P 2.8428425 1.095063 59 P 0 0 ;0=69,1=1
P 2.8543307 0.4055118 59 P 0 0 ;0=69,1=1
P 2.8608425 3.787063 59 P 0 0 ;0=69,1=1
P 2.8622047 0.7952756 59 P 0 0 ;0=69,1=1
P 2.8718425 2.297063 59 P 0 0 ;0=69,1=1
P 2.8782843 0.2495967 59 P 0 0 ;0=69,1=1
P 2.8818425 2.566063 59 P 0 0 ;0=69,1=1
P 2.8888425 4.221063 59 P 0 0 ;0=69,1=1
P 2.8937008 0.7952756 59 P 0 0 ;0=69,1=1
P 2.8948425 1.561063 59 P 0 0 ;0=69,1=1
P 2.8948425 2.431063 59 P 0 0 ;0=69,1=1
P 2.9018425 1.095063 59 P 0 0 ;0=69,1=1
P 2.9054946 0.2795104 59 P 0 0 ;0=69,1=1
P 2.9198425 1.536063 59 P 0 0 ;0=69,1=1
P 2.9208425 2.428063 59 P 0 0 ;0=69,1=1
P 2.9338425 0.953063 59 P 0 0 ;0=69,1=1
P 2.9370079 0.2795276 59 P 0 0 ;0=69,1=1
P 2.9428425 2.286063 59 P 0 0 ;0=69,1=1
P 2.9488425 2.456063 59 P 0 0 ;0=69,1=1
P 2.9574751 0.2519685 59 P 0 0 ;0=69,1=1
P 2.9588425 2.621063 59 P 0 0 ;0=69,1=1
P 2.980457 0.4091539 59 P 0 0 ;0=69,1=1
P 2.9858425 2.287063 59 P 0 0 ;0=69,1=1
P 2.9933858 3.751063 59 P 0 0 ;0=69,1=1
P 3.0148425 3.831063 59 P 0 0 ;0=69,1=1
P 3.019685 0.4055118 59 P 0 0 ;0=69,1=1
P 3.0568817 1.811803 59 P 0 0 ;0=69,1=1
P 3.0688976 3.3956693 59 P 0 0 ;0=69,1=1
P 3.0974409 0.2519685 59 P 0 0 ;0=69,1=1
P 3.1830708 3.1358268 59 P 0 0 ;0=69,1=1
P 3.1889764 3.1870079 59 P 0 0 ;0=69,1=1
P 3.1972633 1.714063 59 P 0 0 ;0=69,1=1
P 3.1978425 2.970063 59 P 0 0 ;0=69,1=1
P 3.2198425 3.806063 59 P 0 0 ;0=69,1=1
P 3.2248425 1.6613472 59 P 0 0 ;0=69,1=1
P 3.2308425 3.235063 59 P 0 0 ;0=69,1=1
P 3.2398425 3.596063 59 P 0 0 ;0=69,1=1
P 3.2528425 1.661063 59 P 0 0 ;0=69,1=1
P 3.2636972 3.3039177 59 P 0 0 ;0=69,1=1
P 3.2698425 3.788063 59 P 0 0 ;0=69,1=1
P 3.2755905 3.1417323 59 P 0 0 ;0=69,1=1
P 3.277559 2.9635827 59 P 0 0 ;0=69,1=1
P 3.2988425 1.971063 59 P 0 0 ;0=69,1=1
P 3.3028425 3.344063 59 P 0 0 ;0=69,1=1
P 3.3291721 1.826063 59 P 0 0 ;0=69,1=1
P 3.3308425 3.301063 59 P 0 0 ;0=69,1=1
P 3.3428425 2.263063 59 P 0 0 ;0=69,1=1
P 3.3448425 2.996063 59 P 0 0 ;0=69,1=1
P 3.3588425 3.448063 59 P 0 0 ;0=69,1=1
P 3.3688425 3.050063 59 P 0 0 ;0=69,1=1
P 3.3708425 2.888063 59 P 0 0 ;0=69,1=1
P 3.3748425 3.273063 59 P 0 0 ;0=69,1=1
P 3.3798425 1.336063 59 P 0 0 ;0=69,1=1
P 3.3798425 1.386063 59 P 0 0 ;0=69,1=1
P 3.3928425 1.871063 59 P 0 0 ;0=69,1=1
P 3.3948425 3.447063 59 P 0 0 ;0=69,1=1
P 3.3958425 4.222063 59 P 0 0 ;0=69,1=1
P 3.4048425 1.363323 59 P 0 0 ;0=69,1=1
P 3.4068425 1.461063 59 P 0 0 ;0=69,1=1
P 3.4072822 1.411323 59 P 0 0 ;0=69,1=1
P 3.4108425 1.7136509 59 P 0 0 ;0=69,1=1
P 3.4138425 1.573063 59 P 0 0 ;0=69,1=1
P 3.4144661 1.805063 59 P 0 0 ;0=69,1=1
P 3.4248425 3.636063 59 P 0 0 ;0=69,1=1
P 3.4368425 3.457063 59 P 0 0 ;0=69,1=1
P 3.4392507 1.870938 59 P 0 0 ;0=69,1=1
P 3.4698425 3.456063 59 P 0 0 ;0=69,1=1
P 3.4918425 3.103063 59 P 0 0 ;0=69,1=1
P 3.4918425 3.297063 59 P 0 0 ;0=69,1=1
P 3.4988425 2.341063 59 P 0 0 ;0=69,1=1
P 3.5048425 4.086063 59 P 0 0 ;0=69,1=1
P 3.5298425 3.481063 59 P 0 0 ;0=69,1=1
P 3.5318425 3.660063 59 P 0 0 ;0=69,1=1
P 3.5398425 3.806063 59 P 0 0 ;0=69,1=1
P 3.542865 3.3190405 59 P 0 0 ;0=69,1=1
P 3.5498425 1.413063 59 P 0 0 ;0=69,1=1
P 3.5498425 1.441063 59 P 0 0 ;0=69,1=1
P 3.5548425 1.841063 59 P 0 0 ;0=69,1=1
P 3.5548425 1.891063 59 P 0 0 ;0=69,1=1
P 3.5548425 1.941063 59 P 0 0 ;0=69,1=1
P 3.5548425 1.991063 59 P 0 0 ;0=69,1=1
P 3.5718425 2.033063 59 P 0 0 ;0=69,1=1
P 3.5718425 2.058063 59 P 0 0 ;0=69,1=1
P 3.5898425 1.711063 59 P 0 0 ;0=69,1=1
P 3.5908425 1.662063 59 P 0 0 ;0=69,1=1
P 3.5948425 1.514063 59 P 0 0 ;0=69,1=1
P 3.6038425 0.682063 59 P 0 0 ;0=69,1=1
P 3.6228425 3.486063 59 P 0 0 ;0=69,1=1
P 3.6238425 2.587063 59 P 0 0 ;0=69,1=1
P 3.6428425 0.636063 59 P 0 0 ;0=69,1=1
P 3.6538425 3.293063 59 P 0 0 ;0=69,1=1
P 3.6998425 3.751063 59 P 0 0 ;0=69,1=1
P 3.6998425 3.836063 59 P 0 0 ;0=69,1=1
P 3.7178425 3.072063 59 P 0 0 ;0=69,1=1
P 3.7188425 1.713063 59 P 0 0 ;0=69,1=1
P 3.7198425 1.766063 59 P 0 0 ;0=69,1=1
P 3.7198425 1.921063 59 P 0 0 ;0=69,1=1
P 3.7198425 1.996063 59 P 0 0 ;0=69,1=1
P 3.7248425 1.675063 59 P 0 0 ;0=69,1=1
P 3.7328425 1.418063 59 P 0 0 ;0=69,1=1
P 3.7448425 3.261063 59 P 0 0 ;0=69,1=1
P 3.7448425 3.342063 59 P 0 0 ;0=69,1=1
P 3.7738632 1.6661021 59 P 0 0 ;0=69,1=1
P 3.7778425 4.023063 59 P 0 0 ;0=69,1=1
P 3.7998425 3.201063 59 P 0 0 ;0=69,1=1
P 3.8038425 1.691063 59 P 0 0 ;0=69,1=1
P 3.8048425 1.840063 59 P 0 0 ;0=69,1=1
P 3.8068425 3.235063 59 P 0 0 ;0=69,1=1
P 3.8298425 3.176063 59 P 0 0 ;0=69,1=1
P 3.8298425 3.806063 59 P 0 0 ;0=69,1=1
P 3.8308425 3.762063 59 P 0 0 ;0=69,1=1
P 3.8348425 1.481063 59 P 0 0 ;0=69,1=1
P 3.8548425 3.151063 59 P 0 0 ;0=69,1=1
P 3.8648425 1.511063 59 P 0 0 ;0=69,1=1
P 3.8808425 3.109063 59 P 0 0 ;0=69,1=1
P 3.8948425 1.566063 59 P 0 0 ;0=69,1=1
P 3.9248425 1.536063 59 P 0 0 ;0=69,1=1
P 3.9398425 3.121063 59 P 0 0 ;0=69,1=1
P 3.9448425 1.816063 59 P 0 0 ;0=69,1=1
P 3.9608425 2.724063 59 P 0 0 ;0=69,1=1
P 3.9688425 1.671063 59 P 0 0 ;0=69,1=1
P 3.9698425 1.552063 59 P 0 0 ;0=69,1=1
P 3.9948425 1.551063 59 P 0 0 ;0=69,1=1
P 3.9968425 1.711063 59 P 0 0 ;0=69,1=1
P 4.0348425 1.546063 59 P 0 0 ;0=69,1=1
P 4.0398425 2.406063 59 P 0 0 ;0=69,1=1
P 4.0398425 3.784063 59 P 0 0 ;0=69,1=1
P 4.0498425 3.665063 59 P 0 0 ;0=69,1=1
P 4.0648425 1.511063 59 P 0 0 ;0=69,1=1
P 4.0648425 1.796063 59 P 0 0 ;0=69,1=1
P 4.0648425 2.722063 59 P 0 0 ;0=69,1=1
P 4.0688425 3.135063 59 P 0 0 ;0=69,1=1
P 4.0858425 3.892063 59 P 0 0 ;0=69,1=1
P 4.1148425 3.135063 59 P 0 0 ;0=69,1=1
P 4.1203866 3.5941508 59 P 0 0 ;0=69,1=1
P 4.1318425 1.686063 59 P 0 0 ;0=69,1=1
P 4.1348425 1.651063 59 P 0 0 ;0=69,1=1
P 4.1348425 1.751063 59 P 0 0 ;0=69,1=1
P 4.1513063 1.6236232 59 P 0 0 ;0=69,1=1
P 4.1528425 3.135063 59 P 0 0 ;0=69,1=1
P 4.1798425 1.601063 59 P 0 0 ;0=69,1=1
P 4.1948425 3.884063 59 P 0 0 ;0=69,1=1
P 4.2088425 3.135063 59 P 0 0 ;0=69,1=1
P 4.2348425 2.725063 59 P 0 0 ;0=69,1=1
P 4.2548425 3.776063 59 P 0 0 ;0=69,1=1
P 4.2728425 3.135063 59 P 0 0 ;0=69,1=1
P 4.3338425 3.135063 59 P 0 0 ;0=69,1=1
P 4.3398425 2.725063 59 P 0 0 ;0=69,1=1
P 4.3878425 4.206063 59 P 0 0 ;0=69,1=1
P 4.4318425 3.135063 59 P 0 0 ;0=69,1=1
P 4.4778425 3.135063 59 P 0 0 ;0=69,1=1
P 4.5036614 2.7898819 59 P 0 0 ;0=69,1=1
P 4.7547119 4.1159324 59 P 0 0 ;0=69,1=1
P 4.7942913 2.8080709 59 P 0 0 ;0=69,1=1
P 4.9108425 4.203063 59 P 0 0 ;0=69,1=1
P 5.2670079 4.0888976 59 P 0 0 ;0=69,1=1
P 5.2748425 3.511063 59 P 0 0 ;0=69,1=1
P 5.5778425 2.214063 59 P 0 0 ;0=69,1=1
P 5.6348425 2.236063 59 P 0 0 ;0=69,1=1
P 5.6768425 3.546063 59 P 0 0 ;0=69,1=1
P 5.7338425 3.556063 59 P 0 0 ;0=69,1=1
P 5.9948425 3.552063 59 P 0 0 ;0=69,1=1
P 6.0048425 2.434063 59 P 0 0 ;0=69,1=1
P 6.0488425 2.171063 59 P 0 0 ;0=69,1=1
P 6.253937 2.9094488 59 P 0 0 ;0=69,1=1
P 6.2748425 2.391063 59 P 0 0 ;0=69,1=1
P 6.2824161 3.226063 59 P 0 0 ;0=69,1=1
P 6.2848425 2.501063 59 P 0 0 ;0=69,1=1
P 6.2948425 3.701063 59 P 0 0 ;0=69,1=1
P 6.3048425 3.121063 59 P 0 0 ;0=69,1=1
P 6.3094161 3.199063 59 P 0 0 ;0=69,1=1
P 6.3348425 3.266063 59 P 0 0 ;0=69,1=1
P 6.3398425 3.151063 59 P 0 0 ;0=69,1=1
P 6.3547483 3.3311384 59 P 0 0 ;0=69,1=1
P 6.3720472 2.9094488 59 P 0 0 ;0=69,1=1
P 6.3958425 2.111063 59 P 0 0 ;0=69,1=1
P 6.3968425 2.556063 59 P 0 0 ;0=69,1=1
P 6.3978425 2.501063 59 P 0 0 ;0=69,1=1
P 6.3978425 2.610063 59 P 0 0 ;0=69,1=1
P 6.3988425 2.453063 59 P 0 0 ;0=69,1=1
P 6.3988425 2.657063 59 P 0 0 ;0=69,1=1
P 6.4098425 3.371063 59 P 0 0 ;0=69,1=1
P 6.4248425 2.181063 59 P 0 0 ;0=69,1=1
P 6.4398425 3.191063 59 P 0 0 ;0=69,1=1
P 6.4448425 3.291063 59 P 0 0 ;0=69,1=1
P 6.4475772 3.396063 59 P 0 0 ;0=69,1=1
P 6.4568425 3.009063 59 P 0 0 ;0=69,1=1
P 6.4768425 3.231063 59 P 0 0 ;0=69,1=1
P 6.4798425 3.426063 59 P 0 0 ;0=69,1=1
P 6.5098425 3.456063 59 P 0 0 ;0=69,1=1
P 6.5488425 1.531063 59 P 0 0 ;0=69,1=1
P 6.6018425 1.777063 59 P 0 0 ;0=69,1=1
P 6.6028425 1.612063 59 P 0 0 ;0=69,1=1
P 6.6028425 1.672063 59 P 0 0 ;0=69,1=1
P 6.6028425 1.722063 59 P 0 0 ;0=69,1=1
P 6.6078425 2.176063 59 P 0 0 ;0=69,1=1
P 6.6268425 3.032063 59 P 0 0 ;0=69,1=1
P 6.6288425 1.372063 59 P 0 0 ;0=69,1=1
P 6.6476378 3.1299213 59 P 0 0 ;0=69,1=1
P 6.6488425 3.341063 59 P 0 0 ;0=69,1=1
P 6.6858425 1.828063 59 P 0 0 ;0=69,1=1
P 6.6998425 1.881063 59 P 0 0 ;0=69,1=1
P 6.8448425 1.661063 59 P 0 0 ;0=69,1=1
P 6.9498425 2.095063 59 P 0 0 ;0=69,1=1
P 6.9744094 1.9399606 59 P 0 0 ;0=69,1=1

### steps/pcb/layers/top_overlay/features
#Layer_Color=65535
#
#Feature symbol names
#
$0 r3.937
$1 r1
$2 r15.75
$3 r10
$4 r23.622
$5 r9.8425
$6 r7.874
$7 r15.748
$8 r5
$9 r5.91
$10 r6
$11 r4.7244
$12 r8
$13 r7
$14 r7.9921
$15 r9
$16 rect25x10

#
#Feature attribute names
#
@0 .nomenclature
@1 .string
@2 .string_angle

#
#Feature attribute text strings
#
&0 BT1
&1 U10AL
&2 U3
&3 R1
&4 R14
&5 R17
&6 IC?
&7 P2
&8 R36
&9 R16
&10 R15
&11 P1
&12 1
&13 2
&14 3
&15 4
&16 JP2
&17 JP1
&18 C72
&19 C73
&20 C74
&21 C75
&22 C76
&23 C77
&24 C78
&25 C79
&26 C80
&27 C81
&28 C82
&29 C83
&30 C84
&31 C85
&32 C86
&33 C91
&34 C92
&35 R42
&36 R43
&37 U16
&38 J4
&39 R5
&40 X1
&41 U13
&42 U11
&43 U10
&44 U9
&45 U8
&46 U6
&47 U5
&48 U2
&49 U1
&50 SW1
&51 S6
&52 S5
&53 R35
&54 R34
&55 R33
&56 R32
&57 R31
&58 R30
&59 R29
&60 R28
&61 R27
&62 R26
&63 R25
&64 R24
&65 R23
&66 R22
&67 R21
&68 R20
&69 R19
&70 R18
&71 R9
&72 R8
&73 R7
&74 R6
&75 R4
&76 R3
&77 R2
&78 L2
&79 L1
&80 J3
&81 J2
&82 J1
&83 FB3
&84 FB2
&85 F1
&86 D18
&87 D17
&88 D16
&89 D15
&90 D14
&91 D13
&92 D12
&93 D11
&94 D10
&95 D9
&96 D8
&97 D7
&98 D6
&99 D5
&100 D4
&101 D3
&102 D2
&103 D1
&104 C67
&105 C66
&106 C65
&107 C63
&108 C62
&109 C61
&110 C60
&111 C59
&112 C58
&113 C57
&114 C56
&115 C55
&116 C54
&117 C22
&118 C21
&119 C20
&120 C19
&121 C18
&122 C17
&123 C16
&124 C15
&125 C14
&126 C13
&127 C12
&128 C11
&129 C10
&130 C9
&131 C8
&132 C7
&133 C6
&134 C5
&135 C4
&136 C3
&137 C2
&138 C1
&139 AN8
&140 AN7
&141 AN6
&142 AN5
&143 AN4
&144 AN3
&145 AN2
&146 AN1

#
#Layer features
#
A 0.2105315 2.8299213 0.2105315 2.8299213 0.1495079 2.8299213 3 P 0 N
A 0.2105315 3.8535433 0.2105315 3.8535433 0.1495079 3.8535433 3 P 0 N
A 0.6182677 4.1758662 0.6182677 4.1758662 0.6162992 4.1758662 0 P 0 N
A 0.8199343 4.1758662 0.8199343 4.1758662 0.8179658 4.1758662 0 P 0 N
A 1.0216009 4.1758662 1.0216009 4.1758662 1.0196324 4.1758662 0 P 0 N
A 1.2170866 0.8224016 1.2170866 0.8224016 1.2121653 0.8224016 5 P 0 N
A 1.2170866 1.3474016 1.2170866 1.3474016 1.2121653 1.3474016 5 P 0 N
A 1.2170866 1.8724016 1.2170866 1.8724016 1.2121653 1.8724016 5 P 0 N
A 1.2170866 2.3974016 1.2170866 2.3974016 1.2121653 2.3974016 5 P 0 N
A 1.2232675 4.1758662 1.2232675 4.1758662 1.221299 4.1758662 0 P 0 N
A 1.6364803 4.2300748 1.6364803 4.2300748 1.631559 4.2300748 5 P 0 N
A 1.7270314 4.1711181 1.7270314 4.1711181 1.7152204 4.1711181 4 P 0 N
A 1.7712204 0.4310709 1.6275196 0.4310709 1.69937 0.4310709 0 P 0 N
A 1.8427125 1.318673 1.8427125 1.318673 1.8348325 1.318673 2 P 0 N
A 2.2198525 2.300533 2.2198525 2.300533 2.2119725 2.300533 2 P 0 N
A 2.5924212 2.8299213 2.5924212 2.8299213 2.5313976 2.8299213 3 P 0 N
A 2.5924212 3.8535433 2.5924212 3.8535433 2.5313976 3.8535433 3 P 0 N
A 2.7618111 3.3206693 2.7618111 3.3206693 2.7568898 3.3206693 5 P 0 N
A 2.7818505 3.7503543 2.7818505 3.7503543 2.7769292 3.7503543 5 P 0 N
A 2.863189 3.2795275 2.863189 3.2795275 2.851378 3.2795275 4 P 0 N
A 2.8698425 3.8611023 2.8698425 3.8611023 2.8448425 3.8611023 6 P 0 N
A 2.8968505 3.7503543 2.8968505 3.7503543 2.8919292 3.7503543 5 P 0 N
A 2.9895825 1.096593 2.9895825 1.096593 2.9817025 1.096593 2 P 0 N
A 3.2470472 2.8661417 3.2509842 2.8661417 3.2490157 2.8661417 0 P 0 N
A 3.2509842 2.8661417 3.2470472 2.8661417 3.2490157 2.8661417 0 P 0 N
A 3.3068505 3.7503543 3.3068505 3.7503543 3.3019292 3.7503543 5 P 0 N
A 3.4416225 2.088353 3.4416225 2.088353 3.4337425 2.088353 2 P 0 N
A 3.5318505 3.7503543 3.5318505 3.7503543 3.5269292 3.7503543 5 P 0 N
A 3.5632677 3.7058662 3.5632677 3.7058662 3.5612992 3.7058662 0 P 0 N
A 3.6203543 3.9312598 3.6203543 3.9312598 3.6183858 3.9312598 0 P 0 N
A 3.7774803 3.8890748 3.7774803 3.8890748 3.772559 3.8890748 5 P 0 N
A 3.8680314 3.8301181 3.8680314 3.8301181 3.8562204 3.8301181 4 P 0 N
A 4.1298072 1.5996232 4.1298072 1.5996232 4.1248072 1.5996232 3 P 0 N
A 4.2559055 3.6318898 4.2559055 3.6318898 4.253937 3.6318898 0 P 0 N
A 4.3326772 0.8338582 4.3326772 0.8338582 4.3277559 0.8338582 5 P 0 N
A 5.8811023 3.7335433 5.8811023 3.7335433 5.8791338 3.7335433 0 P 0 N
A 6.1277165 3.7411023 6.1277165 3.7411023 6.1198425 3.7411023 7 P 0 N
A 6.1911023 3.7335433 6.1911023 3.7335433 6.1891338 3.7335433 0 P 0 N
A 6.1961023 3.5985433 6.1961023 3.5985433 6.1941338 3.5985433 0 P 0 N
A 6.6798425 3.131063 6.6798425 3.131063 6.6748425 3.131063 3 P 0 N
L -0.0001175 0.177913 0.5908825 0.177913 1 P 0
L -0.0004331 0.1781182 0.5901181 0.1781182 0 P 0
L 0.0180118 2.7167323 0.0180118 3.9667323 3 P 0
L 0.0180118 2.7167323 2.6628937 2.7167323 3 P 0
L 0.0180118 3.9667323 2.6628937 3.9667323 3 P 0
L 0.0298425 0.766063 0.0698425 0.726063 13 P 0
L 0.0298425 1.046063 0.0698425 1.086063 13 P 0
L 0.0298425 1.291063 0.0698425 1.251063 13 P 0
L 0.0298425 1.571063 0.0698425 1.611063 13 P 0
L 0.0298425 1.816063 0.0698425 1.776063 13 P 0
L 0.0298425 2.096063 0.0698425 2.136063 13 P 0
L 0.0298425 2.341063 0.0698425 2.301063 13 P 0
L 0.0298425 2.621063 0.0698425 2.661063 13 P 0
L 0.0698425 0.726063 0.0998425 0.726063 13 P 0
L 0.0698425 1.086063 0.0998425 1.086063 13 P 0
L 0.0698425 1.251063 0.0998425 1.251063 13 P 0
L 0.0698425 1.611063 0.0998425 1.611063 13 P 0
L 0.0698425 1.776063 0.0998425 1.776063 13 P 0
L 0.0698425 2.136063 0.0998425 2.136063 13 P 0
L 0.0698425 2.301063 0.0998425 2.301063 13 P 0
L 0.0698425 2.661063 0.0998425 2.661063 13 P 0
L 0.0998425 0.726063 0.3798425 0.726063 13 P 0
L 0.0998425 1.086063 0.3798425 1.086063 13 P 0
L 0.0998425 1.251063 0.3798425 1.251063 13 P 0
L 0.0998425 1.611063 0.3798425 1.611063 13 P 0
L 0.0998425 1.776063 0.3798425 1.776063 13 P 0
L 0.0998425 2.136063 0.3798425 2.136063 13 P 0
L 0.0998425 2.301063 0.3798425 2.301063 13 P 0
L 0.0998425 2.661063 0.3798425 2.661063 13 P 0
L 0.3798425 0.726063 0.3798425 0.806063 13 P 0
L 0.3798425 1.006063 0.3798425 1.086063 13 P 0
L 0.3798425 1.251063 0.3798425 1.331063 13 P 0
L 0.3798425 1.531063 0.3798425 1.611063 13 P 0
L 0.3798425 1.776063 0.3798425 1.856063 13 P 0
L 0.3798425 2.056063 0.3798425 2.136063 13 P 0
L 0.3798425 2.301063 0.3798425 2.381063 13 P 0
L 0.3798425 2.581063 0.3798425 2.661063 13 P 0
L 0.4048619 0.7285703 0.4048619 0.7485638 15 P 0 ;0,1=143,2=0.000000
L 0.4048619 0.7485638 0.4148587 0.7585606 15 P 0 ;0,1=143,2=0.000000
L 0.4048619 1.7755703 0.4048619 1.7955638 15 P 0 ;0,1=145,2=0.000000
L 0.4048619 1.7955638 0.4148587 1.8055606 15 P 0 ;0,1=145,2=0.000000
L 0.4063594 2.3015703 0.4063594 2.3215638 15 P 0 ;0,1=146,2=0.000000
L 0.4063594 2.3215638 0.4163562 2.3315606 15 P 0 ;0,1=146,2=0.000000
L 0.4068619 1.2525703 0.4068619 1.2725638 15 P 0 ;0,1=144,2=0.000000
L 0.4068619 1.2725638 0.4168587 1.2825606 15 P 0 ;0,1=144,2=0.000000
L 0.4148587 0.7585606 0.4248554 0.7485638 15 P 0 ;0,1=143,2=0.000000
L 0.4148587 1.8055606 0.4248554 1.7955638 15 P 0 ;0,1=145,2=0.000000
L 0.4163562 2.3315606 0.4263529 2.3215638 15 P 0 ;0,1=146,2=0.000000
L 0.4168587 1.2825606 0.4268554 1.2725638 15 P 0 ;0,1=144,2=0.000000
L 0.4248554 0.7285703 0.4248554 0.7435655 15 P 0 ;0,1=143,2=0.000000
L 0.4248554 0.7435655 0.4048619 0.7435655 15 P 0 ;0,1=143,2=0.000000
L 0.4248554 0.7485638 0.4248554 0.7285703 15 P 0 ;0,1=143,2=0.000000
L 0.4248554 1.7755703 0.4248554 1.7905655 15 P 0 ;0,1=145,2=0.000000
L 0.4248554 1.7905655 0.4048619 1.7905655 15 P 0 ;0,1=145,2=0.000000
L 0.4248554 1.7955638 0.4248554 1.7755703 15 P 0 ;0,1=145,2=0.000000
L 0.4263529 2.3015703 0.4263529 2.3165655 15 P 0 ;0,1=146,2=0.000000
L 0.4263529 2.3165655 0.4063594 2.3165655 15 P 0 ;0,1=146,2=0.000000
L 0.4263529 2.3215638 0.4263529 2.3015703 15 P 0 ;0,1=146,2=0.000000
L 0.4268554 1.2525703 0.4268554 1.2675655 15 P 0 ;0,1=144,2=0.000000
L 0.4268554 1.2675655 0.4068619 1.2675655 15 P 0 ;0,1=144,2=0.000000
L 0.4268554 1.2725638 0.4268554 1.2525703 15 P 0 ;0,1=144,2=0.000000
L 0.4348522 0.7285703 0.4348522 0.7585606 15 P 0 ;0,1=143,2=0.000000
L 0.4348522 0.7585606 0.4548457 0.7285703 15 P 0 ;0,1=143,2=0.000000
L 0.4348522 1.7755703 0.4348522 1.8055606 15 P 0 ;0,1=145,2=0.000000
L 0.4348522 1.8055606 0.4548457 1.7755703 15 P 0 ;0,1=145,2=0.000000
L 0.4363497 2.3015703 0.4363497 2.3315606 15 P 0 ;0,1=146,2=0.000000
L 0.4363497 2.3315606 0.4563432 2.3015703 15 P 0 ;0,1=146,2=0.000000
L 0.4368522 1.2525703 0.4368522 1.2825606 15 P 0 ;0,1=144,2=0.000000
L 0.4368522 1.2825606 0.4568457 1.2525703 15 P 0 ;0,1=144,2=0.000000
L 0.4548457 0.7285703 0.4548457 0.7585606 15 P 0 ;0,1=143,2=0.000000
L 0.4548457 1.7755703 0.4548457 1.8055606 15 P 0 ;0,1=145,2=0.000000
L 0.4563432 2.3015703 0.4563432 2.3315606 15 P 0 ;0,1=146,2=0.000000
L 0.4568457 1.2525703 0.4568457 1.2825606 15 P 0 ;0,1=144,2=0.000000
L 0.4648425 0.7435655 0.484836 0.7435655 15 P 0 ;0,1=143,2=0.000000
L 0.4648425 1.7755703 0.484836 1.7955638 15 P 0 ;0,1=145,2=0.000000
L 0.46634 2.3015703 0.4763368 2.3015703 15 P 0 ;0,1=146,2=0.000000
L 0.4668425 1.2775622 0.4718409 1.2825606 15 P 0 ;0,1=144,2=0.000000
L 0.4698409 1.8055606 0.4648425 1.8005622 15 P 0 ;0,1=145,2=0.000000
L 0.4713384 2.3015703 0.4713384 2.3315606 15 P 0 ;0,1=146,2=0.000000
L 0.4713384 2.3315606 0.46634 2.3265622 15 P 0 ;0,1=146,2=0.000000
L 0.4718409 1.2525703 0.4668425 1.2575687 15 P 0 ;0,1=144,2=0.000000
L 0.4718409 1.2825606 0.4818377 1.2825606 15 P 0 ;0,1=144,2=0.000000
L 0.4763368 2.3015703 0.4713384 2.3015703 15 P 0 ;0,1=146,2=0.000000
L 0.4768393 1.2675655 0.4818377 1.2675655 15 P 0 ;0,1=144,2=0.000000
L 0.4798377 0.7285703 0.4798377 0.7585606 15 P 0 ;0,1=143,2=0.000000
L 0.4798377 0.7585606 0.4648425 0.7435655 15 P 0 ;0,1=143,2=0.000000
L 0.4798377 1.8055606 0.4698409 1.8055606 15 P 0 ;0,1=145,2=0.000000
L 0.4818377 1.2525703 0.4718409 1.2525703 15 P 0 ;0,1=144,2=0.000000
L 0.4818377 1.2675655 0.4768393 1.2675655 15 P 0 ;0,1=144,2=0.000000
L 0.4818377 1.2675655 0.486836 1.2625671 15 P 0 ;0,1=144,2=0.000000
L 0.4818377 1.2825606 0.486836 1.2775622 15 P 0 ;0,1=144,2=0.000000
L 0.484836 1.7755703 0.4648425 1.7755703 15 P 0 ;0,1=145,2=0.000000
L 0.484836 1.7955638 0.484836 1.8005622 15 P 0 ;0,1=145,2=0.000000
L 0.484836 1.8005622 0.4798377 1.8055606 15 P 0 ;0,1=145,2=0.000000
L 0.486836 1.2575687 0.4818377 1.2525703 15 P 0 ;0,1=144,2=0.000000
L 0.486836 1.2625671 0.486836 1.2575687 15 P 0 ;0,1=144,2=0.000000
L 0.486836 1.2725638 0.4818377 1.2675655 15 P 0 ;0,1=144,2=0.000000
L 0.486836 1.2775622 0.486836 1.2725638 15 P 0 ;0,1=144,2=0.000000
L 0.5368425 1.062063 0.5368425 1.0820565 15 P 0 ;0,1=139,2=0.000000
L 0.5368425 1.0820565 0.5468393 1.0920533 15 P 0 ;0,1=139,2=0.000000
L 0.5368425 1.587063 0.5368425 1.6070565 15 P 0 ;0,1=140,2=0.000000
L 0.5368425 1.6070565 0.5468393 1.6170533 15 P 0 ;0,1=140,2=0.000000
L 0.5368425 2.112063 0.5368425 2.1320565 15 P 0 ;0,1=142,2=0.000000
L 0.5368425 2.1320565 0.5468393 2.1420533 15 P 0 ;0,1=142,2=0.000000
L 0.5368425 2.637063 0.5368425 2.6570565 15 P 0 ;0,1=141,2=0.000000
L 0.5368425 2.6570565 0.5468393 2.6670533 15 P 0 ;0,1=141,2=0.000000
L 0.5468393 1.0920533 0.556836 1.0820565 15 P 0 ;0,1=139,2=0.000000
L 0.5468393 1.6170533 0.556836 1.6070565 15 P 0 ;0,1=140,2=0.000000
L 0.5468393 2.1420533 0.556836 2.1320565 15 P 0 ;0,1=142,2=0.000000
L 0.5468393 2.6670533 0.556836 2.6570565 15 P 0 ;0,1=141,2=0.000000
L 0.556836 1.062063 0.556836 1.0770582 15 P 0 ;0,1=139,2=0.000000
L 0.556836 1.0770582 0.5368425 1.0770582 15 P 0 ;0,1=139,2=0.000000
L 0.556836 1.0820565 0.556836 1.062063 15 P 0 ;0,1=139,2=0.000000
L 0.556836 1.587063 0.556836 1.6020582 15 P 0 ;0,1=140,2=0.000000
L 0.556836 1.6020582 0.5368425 1.6020582 15 P 0 ;0,1=140,2=0.000000
L 0.556836 1.6070565 0.556836 1.587063 15 P 0 ;0,1=140,2=0.000000
L 0.556836 2.112063 0.556836 2.1270582 15 P 0 ;0,1=142,2=0.000000
L 0.556836 2.1270582 0.5368425 2.1270582 15 P 0 ;0,1=142,2=0.000000
L 0.556836 2.1320565 0.556836 2.112063 15 P 0 ;0,1=142,2=0.000000
L 0.556836 2.637063 0.556836 2.6520582 15 P 0 ;0,1=141,2=0.000000
L 0.556836 2.6520582 0.5368425 2.6520582 15 P 0 ;0,1=141,2=0.000000
L 0.556836 2.6570565 0.556836 2.637063 15 P 0 ;0,1=141,2=0.000000
L 0.5583449 3.9980824 0.5583449 4.0130776 15 P 0 ;0,1=60,2=90.000000
L 0.5583449 4.0130776 0.5633433 4.0180759 15 P 0 ;0,1=60,2=90.000000
L 0.5583449 4.0330711 0.5633433 4.0280727 15 P 0 ;0,1=60,2=90.000000
L 0.5583449 4.0430679 0.5583449 4.0330711 15 P 0 ;0,1=60,2=90.000000
L 0.5583449 4.0630614 0.5583449 4.0730582 15 P 0 ;0,1=60,2=90.000000
L 0.5583449 4.0730582 0.5633433 4.0780565 15 P 0 ;0,1=60,2=90.000000
L 0.5613449 4.1783287 0.5913352 4.1783287 15 P 0 ;0,1=93,2=90.000000
L 0.5613449 4.1933239 0.5613449 4.1783287 15 P 0 ;0,1=93,2=90.000000
L 0.5613449 4.2133174 0.5663433 4.208319 15 P 0 ;0,1=93,2=90.000000
L 0.5613449 4.2383093 0.5663433 4.2333109 15 P 0 ;0,1=93,2=90.000000
L 0.5633433 4.0180759 0.57334 4.0180759 15 P 0 ;0,1=60,2=90.000000
L 0.5633433 4.0480662 0.5583449 4.0430679 15 P 0 ;0,1=60,2=90.000000
L 0.5633433 4.058063 0.5583449 4.0630614 15 P 0 ;0,1=60,2=90.000000
L 0.5633433 4.0780565 0.5683417 4.0780565 15 P 0 ;0,1=60,2=90.000000
L 0.5663433 4.1983222 0.5613449 4.1933239 15 P 0 ;0,1=93,2=90.000000
L 0.5668328 1.062063 0.5668328 1.0920533 15 P 0 ;0,1=139,2=0.000000
L 0.5668328 1.0920533 0.5868263 1.062063 15 P 0 ;0,1=139,2=0.000000
L 0.5668328 1.587063 0.5668328 1.6170533 15 P 0 ;0,1=140,2=0.000000
L 0.5668328 1.6170533 0.5868263 1.587063 15 P 0 ;0,1=140,2=0.000000
L 0.5668328 2.112063 0.5668328 2.1420533 15 P 0 ;0,1=142,2=0.000000
L 0.5668328 2.1420533 0.5868263 2.112063 15 P 0 ;0,1=142,2=0.000000
L 0.5668328 2.637063 0.5668328 2.6670533 15 P 0 ;0,1=141,2=0.000000
L 0.5668328 2.6670533 0.5868263 2.637063 15 P 0 ;0,1=141,2=0.000000
L 0.5683417 4.0480662 0.5633433 4.0480662 15 P 0 ;0,1=60,2=90.000000
L 0.5683417 4.058063 0.5633433 4.058063 15 P 0 ;0,1=60,2=90.000000
L 0.5683417 4.0780565 0.57334 4.0730582 15 P 0 ;0,1=60,2=90.000000
L 0.57334 4.0180759 0.5783384 4.0130776 15 P 0 ;0,1=60,2=90.000000
L 0.57334 4.0630614 0.5683417 4.058063 15 P 0 ;0,1=60,2=90.000000
L 0.57334 4.0630614 0.57334 4.0730582 15 P 0 ;0,1=60,2=90.000000
L 0.57334 4.0730582 0.5783384 4.0780565 15 P 0 ;0,1=60,2=90.000000
L 0.5783384 4.0080792 0.5883352 4.0180759 15 P 0 ;0,1=60,2=90.000000
L 0.5783384 4.0130776 0.5783384 3.9980824 15 P 0 ;0,1=60,2=90.000000
L 0.5783384 4.058063 0.57334 4.0630614 15 P 0 ;0,1=60,2=90.000000
L 0.5783384 4.0780565 0.5833368 4.0780565 15 P 0 ;0,1=60,2=90.000000
L 0.5833368 4.058063 0.5783384 4.058063 15 P 0 ;0,1=60,2=90.000000
L 0.5833368 4.0780565 0.5883352 4.0730582 15 P 0 ;0,1=60,2=90.000000
L 0.5863368 4.1983222 0.5663433 4.1983222 15 P 0 ;0,1=93,2=90.000000
L 0.5868263 1.062063 0.5868263 1.0920533 15 P 0 ;0,1=139,2=0.000000
L 0.5868263 1.587063 0.5868263 1.6170533 15 P 0 ;0,1=140,2=0.000000
L 0.5868263 2.112063 0.5868263 2.1420533 15 P 0 ;0,1=142,2=0.000000
L 0.5868263 2.637063 0.5868263 2.6670533 15 P 0 ;0,1=141,2=0.000000
L 0.5883352 3.9980824 0.5583449 3.9980824 15 P 0 ;0,1=60,2=90.000000
L 0.5883352 4.0280727 0.5683417 4.0480662 15 P 0 ;0,1=60,2=90.000000
L 0.5883352 4.0480662 0.5883352 4.0280727 15 P 0 ;0,1=60,2=90.000000
L 0.5883352 4.0630614 0.5833368 4.058063 15 P 0 ;0,1=60,2=90.000000
L 0.5883352 4.0730582 0.5883352 4.0630614 15 P 0 ;0,1=60,2=90.000000
L 0.5901181 0.1781182 0.5901181 0.5029213 0 P 0
L 0.5901181 0.5029213 1.312559 0.5029213 0 P 0
L 0.5908825 0.177913 0.5908825 0.502913 1 P 0
L 0.5913352 4.1783287 0.5913352 4.1933239 15 P 0 ;0,1=93,2=90.000000
L 0.5913352 4.1933239 0.5863368 4.1983222 15 P 0 ;0,1=93,2=90.000000
L 0.5913352 4.208319 0.5913352 4.2183158 15 P 0 ;0,1=93,2=90.000000
L 0.5913352 4.2133174 0.5613449 4.2133174 15 P 0 ;0,1=93,2=90.000000
L 0.5913352 4.2183158 0.5913352 4.2133174 15 P 0 ;0,1=93,2=90.000000
L 0.5913352 4.2333109 0.5913352 4.2433077 15 P 0 ;0,1=93,2=90.000000
L 0.5913352 4.2383093 0.5613449 4.2383093 15 P 0 ;0,1=93,2=90.000000
L 0.5913352 4.2433077 0.5913352 4.2383093 15 P 0 ;0,1=93,2=90.000000
L 0.5968231 1.0670614 0.5968231 1.0720598 15 P 0 ;0,1=139,2=0.000000
L 0.5968231 1.0720598 0.6018215 1.0770582 15 P 0 ;0,1=139,2=0.000000
L 0.5968231 1.0820565 0.5968231 1.0870549 15 P 0 ;0,1=139,2=0.000000
L 0.5968231 1.0870549 0.6018215 1.0920533 15 P 0 ;0,1=139,2=0.000000
L 0.5968231 1.5920614 0.5968231 1.587063 15 P 0 ;0,1=140,2=0.000000
L 0.5968231 1.6170533 0.6168166 1.6170533 15 P 0 ;0,1=140,2=0.000000
L 0.5968231 2.1270582 0.6068199 2.1320565 15 P 0 ;0,1=142,2=0.000000
L 0.5968231 2.1420533 0.5968231 2.1270582 15 P 0 ;0,1=142,2=0.000000
L 0.5968231 2.6420614 0.6018215 2.637063 15 P 0 ;0,1=141,2=0.000000
L 0.5968231 2.6520582 0.5968231 2.6420614 15 P 0 ;0,1=141,2=0.000000
L 0.6018215 1.062063 0.5968231 1.0670614 15 P 0 ;0,1=139,2=0.000000
L 0.6018215 1.0770582 0.5968231 1.0820565 15 P 0 ;0,1=139,2=0.000000
L 0.6018215 1.0770582 0.6118183 1.0770582 15 P 0 ;0,1=139,2=0.000000
L 0.6018215 1.0920533 0.6118183 1.0920533 15 P 0 ;0,1=139,2=0.000000
L 0.6018215 2.112063 0.5968231 2.1170614 15 P 0 ;0,1=142,2=0.000000
L 0.6018215 2.637063 0.6118183 2.637063 15 P 0 ;0,1=141,2=0.000000
L 0.6068199 2.1320565 0.6118183 2.1320565 15 P 0 ;0,1=142,2=0.000000
L 0.6068199 2.6620549 0.5968231 2.6520582 15 P 0 ;0,1=141,2=0.000000
L 0.6118183 1.062063 0.6018215 1.062063 15 P 0 ;0,1=139,2=0.000000
L 0.6118183 1.0770582 0.6168166 1.0720598 15 P 0 ;0,1=139,2=0.000000
L 0.6118183 1.0920533 0.6168166 1.0870549 15 P 0 ;0,1=139,2=0.000000
L 0.6118183 2.112063 0.6018215 2.112063 15 P 0 ;0,1=142,2=0.000000
L 0.6118183 2.1320565 0.6168166 2.1270582 15 P 0 ;0,1=142,2=0.000000
L 0.6118183 2.637063 0.6168166 2.6420614 15 P 0 ;0,1=141,2=0.000000
L 0.6118183 2.6520582 0.5968231 2.6520582 15 P 0 ;0,1=141,2=0.000000
L 0.6168166 1.0670614 0.6118183 1.062063 15 P 0 ;0,1=139,2=0.000000
L 0.6168166 1.0720598 0.6168166 1.0670614 15 P 0 ;0,1=139,2=0.000000
L 0.6168166 1.0820565 0.6118183 1.0770582 15 P 0 ;0,1=139,2=0.000000
L 0.6168166 1.0870549 0.6168166 1.0820565 15 P 0 ;0,1=139,2=0.000000
L 0.6168166 1.6120549 0.5968231 1.5920614 15 P 0 ;0,1=140,2=0.000000
L 0.6168166 1.6170533 0.6168166 1.6120549 15 P 0 ;0,1=140,2=0.000000
L 0.6168166 2.1170614 0.6118183 2.112063 15 P 0 ;0,1=142,2=0.000000
L 0.6168166 2.1270582 0.6168166 2.1170614 15 P 0 ;0,1=142,2=0.000000
L 0.6168166 2.1420533 0.5968231 2.1420533 15 P 0 ;0,1=142,2=0.000000
L 0.6168166 2.6420614 0.6168166 2.6470598 15 P 0 ;0,1=141,2=0.000000
L 0.6168166 2.6470598 0.6118183 2.6520582 15 P 0 ;0,1=141,2=0.000000
L 0.6168166 2.6670533 0.6068199 2.6620549 15 P 0 ;0,1=141,2=0.000000
L 0.6192835 4.066063 0.6586535 4.066063 10 P 0
L 0.7593449 3.9980824 0.7593449 4.0130776 15 P 0 ;0,1=59,2=90.000000
L 0.7593449 4.0130776 0.7643433 4.0180759 15 P 0 ;0,1=59,2=90.000000
L 0.7593449 4.0330711 0.7643433 4.0280727 15 P 0 ;0,1=59,2=90.000000
L 0.7593449 4.0430679 0.7593449 4.0330711 15 P 0 ;0,1=59,2=90.000000
L 0.7593449 4.0630614 0.7643433 4.058063 15 P 0 ;0,1=59,2=90.000000
L 0.7593449 4.0730582 0.7593449 4.0630614 15 P 0 ;0,1=59,2=90.000000
L 0.7643433 4.0180759 0.77434 4.0180759 15 P 0 ;0,1=59,2=90.000000
L 0.7643433 4.0480662 0.7593449 4.0430679 15 P 0 ;0,1=59,2=90.000000
L 0.7643433 4.058063 0.7693417 4.058063 15 P 0 ;0,1=59,2=90.000000
L 0.7643433 4.0780565 0.7593449 4.0730582 15 P 0 ;0,1=59,2=90.000000
L 0.7643449 4.1688312 0.7943352 4.1688312 15 P 0 ;0,1=92,2=90.000000
L 0.7643449 4.1838264 0.7643449 4.1688312 15 P 0 ;0,1=92,2=90.000000
L 0.7643449 4.2038199 0.7693433 4.1988215 15 P 0 ;0,1=92,2=90.000000
L 0.7643449 4.2288118 0.7693433 4.2238134 15 P 0 ;0,1=92,2=90.000000
L 0.7643449 4.2388086 0.7643449 4.2288118 15 P 0 ;0,1=92,2=90.000000
L 0.7693417 4.0480662 0.7643433 4.0480662 15 P 0 ;0,1=59,2=90.000000
L 0.7693417 4.058063 0.77434 4.0630614 15 P 0 ;0,1=59,2=90.000000
L 0.7693433 4.1888247 0.7643449 4.1838264 15 P 0 ;0,1=92,2=90.000000
L 0.7693433 4.2438069 0.7643449 4.2388086 15 P 0 ;0,1=92,2=90.000000
L 0.77434 4.0180759 0.7793384 4.0130776 15 P 0 ;0,1=59,2=90.000000
L 0.77434 4.0630614 0.77434 4.0780565 15 P 0 ;0,1=59,2=90.000000
L 0.7743417 4.2438069 0.7693433 4.2438069 15 P 0 ;0,1=92,2=90.000000
L 0.7793384 4.0080792 0.7893352 4.0180759 15 P 0 ;0,1=59,2=90.000000
L 0.7793384 4.0130776 0.7793384 3.9980824 15 P 0 ;0,1=59,2=90.000000
L 0.7843368 4.058063 0.7893352 4.0630614 15 P 0 ;0,1=59,2=90.000000
L 0.7843368 4.0780565 0.7643433 4.0780565 15 P 0 ;0,1=59,2=90.000000
L 0.7893352 3.9980824 0.7593449 3.9980824 15 P 0 ;0,1=59,2=90.000000
L 0.7893352 4.0280727 0.7693417 4.0480662 15 P 0 ;0,1=59,2=90.000000
L 0.7893352 4.0480662 0.7893352 4.0280727 15 P 0 ;0,1=59,2=90.000000
L 0.7893352 4.0630614 0.7893352 4.0730582 15 P 0 ;0,1=59,2=90.000000
L 0.7893352 4.0730582 0.7843368 4.0780565 15 P 0 ;0,1=59,2=90.000000
L 0.7893368 4.1888247 0.7693433 4.1888247 15 P 0 ;0,1=92,2=90.000000
L 0.7943352 4.1688312 0.7943352 4.1838264 15 P 0 ;0,1=92,2=90.000000
L 0.7943352 4.1838264 0.7893368 4.1888247 15 P 0 ;0,1=92,2=90.000000
L 0.7943352 4.1988215 0.7943352 4.2088183 15 P 0 ;0,1=92,2=90.000000
L 0.7943352 4.2038199 0.7643449 4.2038199 15 P 0 ;0,1=92,2=90.000000
L 0.7943352 4.2088183 0.7943352 4.2038199 15 P 0 ;0,1=92,2=90.000000
L 0.7943352 4.2238134 0.7743417 4.2438069 15 P 0 ;0,1=92,2=90.000000
L 0.7943352 4.2438069 0.7943352 4.2238134 15 P 0 ;0,1=92,2=90.000000
L 0.8209501 4.066063 0.8603201 4.066063 10 P 0
L 0.8818425 1.071063 0.8968377 1.071063 15 P 0 ;0,1=86,2=0.000000
L 0.8818425 1.1010533 0.8818425 1.071063 15 P 0 ;0,1=86,2=0.000000
L 0.8818425 1.596063 0.8968377 1.596063 15 P 0 ;0,1=87,2=0.000000
L 0.8818425 1.6260533 0.8818425 1.596063 15 P 0 ;0,1=87,2=0.000000
L 0.8818425 2.121063 0.8968377 2.121063 15 P 0 ;0,1=89,2=0.000000
L 0.8818425 2.1510533 0.8818425 2.121063 15 P 0 ;0,1=89,2=0.000000
L 0.8818425 2.646063 0.8968377 2.646063 15 P 0 ;0,1=88,2=0.000000
L 0.8818425 2.6760533 0.8818425 2.646063 15 P 0 ;0,1=88,2=0.000000
L 0.8918425 0.772063 0.8918425 0.8020533 3 P 0 ;0,1=8,2=0.000000
L 0.8918425 0.8020533 0.9068377 0.8020533 3 P 0 ;0,1=8,2=0.000000
L 0.8968377 1.071063 0.901836 1.0760614 15 P 0 ;0,1=86,2=0.000000
L 0.8968377 1.1010533 0.8818425 1.1010533 15 P 0 ;0,1=86,2=0.000000
L 0.8968377 1.596063 0.901836 1.6010614 15 P 0 ;0,1=87,2=0.000000
L 0.8968377 1.6260533 0.8818425 1.6260533 15 P 0 ;0,1=87,2=0.000000
L 0.8968377 2.121063 0.901836 2.1260614 15 P 0 ;0,1=89,2=0.000000
L 0.8968377 2.1510533 0.8818425 2.1510533 15 P 0 ;0,1=89,2=0.000000
L 0.8968377 2.646063 0.901836 2.6510614 15 P 0 ;0,1=88,2=0.000000
L 0.8968377 2.6760533 0.8818425 2.6760533 15 P 0 ;0,1=88,2=0.000000
L 0.901836 1.0760614 0.901836 1.0960549 15 P 0 ;0,1=86,2=0.000000
L 0.901836 1.0960549 0.8968377 1.1010533 15 P 0 ;0,1=86,2=0.000000
L 0.901836 1.6010614 0.901836 1.6210549 15 P 0 ;0,1=87,2=0.000000
L 0.901836 1.6210549 0.8968377 1.6260533 15 P 0 ;0,1=87,2=0.000000
L 0.901836 2.1260614 0.901836 2.1460549 15 P 0 ;0,1=89,2=0.000000
L 0.901836 2.1460549 0.8968377 2.1510533 15 P 0 ;0,1=89,2=0.000000
L 0.901836 2.6510614 0.901836 2.6710549 15 P 0 ;0,1=88,2=0.000000
L 0.901836 2.6710549 0.8968377 2.6760533 15 P 0 ;0,1=88,2=0.000000
L 0.9018393 0.7820598 0.911836 0.772063 3 P 0 ;0,1=8,2=0.000000
L 0.9031102 0.7820472 0.9031102 0.8283071 6 P 0
L 0.9031102 0.7820472 1.1865748 0.7820472 6 P 0
L 0.9031102 0.9838189 0.9031102 1.0300787 6 P 0
L 0.9031102 1.0300787 1.1865748 1.0300787 6 P 0
L 0.9031102 1.3070472 0.9031102 1.3533071 6 P 0
L 0.9031102 1.3070472 1.1865748 1.3070472 6 P 0
L 0.9031102 1.5088189 0.9031102 1.5550787 6 P 0
L 0.9031102 1.5550787 1.1865748 1.5550787 6 P 0
L 0.9031102 1.8320472 0.9031102 1.8783071 6 P 0
L 0.9031102 1.8320472 1.1865748 1.8320472 6 P 0
L 0.9031102 2.0338189 0.9031102 2.0800787 6 P 0
L 0.9031102 2.0800787 1.1865748 2.0800787 6 P 0
L 0.9031102 2.3570472 0.9031102 2.4033071 6 P 0
L 0.9031102 2.3570472 1.1865748 2.3570472 6 P 0
L 0.9031102 2.5588189 0.9031102 2.6050787 6 P 0
L 0.9031102 2.6050787 1.1865748 2.6050787 6 P 0
L 0.9068377 0.7820598 0.8918425 0.7820598 3 P 0 ;0,1=8,2=0.000000
L 0.9068377 0.8020533 0.911836 0.7970549 3 P 0 ;0,1=8,2=0.000000
L 0.9118328 1.071063 0.9218296 1.071063 15 P 0 ;0,1=86,2=0.000000
L 0.9118328 1.596063 0.9218296 1.596063 15 P 0 ;0,1=87,2=0.000000
L 0.9118328 2.121063 0.9218296 2.121063 15 P 0 ;0,1=89,2=0.000000
L 0.9118328 2.646063 0.9218296 2.646063 15 P 0 ;0,1=88,2=0.000000
L 0.911836 0.7870582 0.9068377 0.7820598 3 P 0 ;0,1=8,2=0.000000
L 0.911836 0.7970549 0.911836 0.7870582 3 P 0 ;0,1=8,2=0.000000
L 0.9168312 1.071063 0.9168312 1.1010533 15 P 0 ;0,1=86,2=0.000000
L 0.9168312 1.1010533 0.9118328 1.0960549 15 P 0 ;0,1=86,2=0.000000
L 0.9168312 1.596063 0.9168312 1.6260533 15 P 0 ;0,1=87,2=0.000000
L 0.9168312 1.6260533 0.9118328 1.6210549 15 P 0 ;0,1=87,2=0.000000
L 0.9168312 2.121063 0.9168312 2.1510533 15 P 0 ;0,1=89,2=0.000000
L 0.9168312 2.1510533 0.9118328 2.1460549 15 P 0 ;0,1=89,2=0.000000
L 0.9168312 2.646063 0.9168312 2.6760533 15 P 0 ;0,1=88,2=0.000000
L 0.9168312 2.6760533 0.9118328 2.6710549 15 P 0 ;0,1=88,2=0.000000
L 0.9218296 1.071063 0.9168312 1.071063 15 P 0 ;0,1=86,2=0.000000
L 0.9218296 1.596063 0.9168312 1.596063 15 P 0 ;0,1=87,2=0.000000
L 0.9218296 2.121063 0.9168312 2.121063 15 P 0 ;0,1=89,2=0.000000
L 0.9218296 2.646063 0.9168312 2.646063 15 P 0 ;0,1=88,2=0.000000
L 0.9218328 0.7970549 0.9268312 0.8020533 3 P 0 ;0,1=8,2=0.000000
L 0.922244 1.7332677 0.9379921 1.7332677 6 P 0
L 0.922244 1.7608268 0.9379921 1.7608268 6 P 0
L 0.9232282 0.7047243 0.9389763 0.7047243 6 P 0
L 0.9232282 0.7322834 0.9389763 0.7322834 6 P 0
L 0.926181 1.2106299 0.9419291 1.2106299 6 P 0
L 0.926181 1.238189 0.9419291 1.238189 6 P 0
L 0.9268312 0.772063 0.9218328 0.7770614 3 P 0 ;0,1=8,2=0.000000
L 0.9268312 0.8020533 0.936828 0.8020533 3 P 0 ;0,1=8,2=0.000000
L 0.930118 2.2706692 0.9458661 2.2706692 6 P 0
L 0.930118 2.2982283 0.9458661 2.2982283 6 P 0
L 0.9318296 0.7870582 0.936828 0.7870582 3 P 0 ;0,1=8,2=0.000000
L 0.9368247 1.0760614 0.9368247 1.0810598 15 P 0 ;0,1=86,2=0.000000
L 0.9368247 1.0810598 0.9418231 1.0860582 15 P 0 ;0,1=86,2=0.000000
L 0.9368247 1.0910565 0.9368247 1.0960549 15 P 0 ;0,1=86,2=0.000000
L 0.9368247 1.0960549 0.9418231 1.1010533 15 P 0 ;0,1=86,2=0.000000
L 0.9368247 1.6010614 0.9368247 1.596063 15 P 0 ;0,1=87,2=0.000000
L 0.9368247 1.6260533 0.9568182 1.6260533 15 P 0 ;0,1=87,2=0.000000
L 0.9368247 2.1360582 0.9468215 2.1410565 15 P 0 ;0,1=89,2=0.000000
L 0.9368247 2.1510533 0.9368247 2.1360582 15 P 0 ;0,1=89,2=0.000000
L 0.9368247 2.6510614 0.9418231 2.646063 15 P 0 ;0,1=88,2=0.000000
L 0.9368247 2.6610582 0.9368247 2.6510614 15 P 0 ;0,1=88,2=0.000000
L 0.936828 0.772063 0.9268312 0.772063 3 P 0 ;0,1=8,2=0.000000
L 0.936828 0.7870582 0.9318296 0.7870582 3 P 0 ;0,1=8,2=0.000000
L 0.936828 0.7870582 0.9418263 0.7820598 3 P 0 ;0,1=8,2=0.000000
L 0.936828 0.8020533 0.9418263 0.7970549 3 P 0 ;0,1=8,2=0.000000
L 0.9418231 1.071063 0.9368247 1.0760614 15 P 0 ;0,1=86,2=0.000000
L 0.9418231 1.0860582 0.9368247 1.0910565 15 P 0 ;0,1=86,2=0.000000
L 0.9418231 1.0860582 0.9518199 1.0860582 15 P 0 ;0,1=86,2=0.000000
L 0.9418231 1.1010533 0.9518199 1.1010533 15 P 0 ;0,1=86,2=0.000000
L 0.9418231 2.121063 0.9368247 2.1260614 15 P 0 ;0,1=89,2=0.000000
L 0.9418231 2.646063 0.9518199 2.646063 15 P 0 ;0,1=88,2=0.000000
L 0.9418263 0.7770614 0.936828 0.772063 3 P 0 ;0,1=8,2=0.000000
L 0.9418263 0.7820598 0.9418263 0.7770614 3 P 0 ;0,1=8,2=0.000000
L 0.9418263 0.7920565 0.936828 0.7870582 3 P 0 ;0,1=8,2=0.000000
L 0.9418263 0.7970549 0.9418263 0.7920565 3 P 0 ;0,1=8,2=0.000000
L 0.9468215 2.1410565 0.9518199 2.1410565 15 P 0 ;0,1=89,2=0.000000
L 0.9468215 2.6710549 0.9368247 2.6610582 15 P 0 ;0,1=88,2=0.000000
L 0.9518199 1.071063 0.9418231 1.071063 15 P 0 ;0,1=86,2=0.000000
L 0.9518199 1.0860582 0.9568182 1.0810598 15 P 0 ;0,1=86,2=0.000000
L 0.9518199 1.1010533 0.9568182 1.0960549 15 P 0 ;0,1=86,2=0.000000
L 0.9518199 2.121063 0.9418231 2.121063 15 P 0 ;0,1=89,2=0.000000
L 0.9518199 2.1410565 0.9568182 2.1360582 15 P 0 ;0,1=89,2=0.000000
L 0.9518199 2.646063 0.9568182 2.6510614 15 P 0 ;0,1=88,2=0.000000
L 0.9518199 2.6610582 0.9368247 2.6610582 15 P 0 ;0,1=88,2=0.000000
L 0.9518231 0.7770614 0.9568215 0.772063 3 P 0 ;0,1=8,2=0.000000
L 0.9518231 0.7870582 0.9518231 0.7770614 3 P 0 ;0,1=8,2=0.000000
L 0.9568182 1.0760614 0.9518199 1.071063 15 P 0 ;0,1=86,2=0.000000
L 0.9568182 1.0810598 0.9568182 1.0760614 15 P 0 ;0,1=86,2=0.000000
L 0.9568182 1.0910565 0.9518199 1.0860582 15 P 0 ;0,1=86,2=0.000000
L 0.9568182 1.0960549 0.9568182 1.0910565 15 P 0 ;0,1=86,2=0.000000
L 0.9568182 1.6210549 0.9368247 1.6010614 15 P 0 ;0,1=87,2=0.000000
L 0.9568182 1.6260533 0.9568182 1.6210549 15 P 0 ;0,1=87,2=0.000000
L 0.9568182 2.1260614 0.9518199 2.121063 15 P 0 ;0,1=89,2=0.000000
L 0.9568182 2.1360582 0.9568182 2.1260614 15 P 0 ;0,1=89,2=0.000000
L 0.9568182 2.1510533 0.9368247 2.1510533 15 P 0 ;0,1=89,2=0.000000
L 0.9568182 2.6510614 0.9568182 2.6560598 15 P 0 ;0,1=88,2=0.000000
L 0.9568182 2.6560598 0.9518199 2.6610582 15 P 0 ;0,1=88,2=0.000000
L 0.9568182 2.6760533 0.9468215 2.6710549 15 P 0 ;0,1=88,2=0.000000
L 0.9568215 0.772063 0.9668183 0.772063 3 P 0 ;0,1=8,2=0.000000
L 0.9603449 4.1648312 0.9903352 4.1648312 15 P 0 ;0,1=91,2=90.000000
L 0.9603449 4.1798264 0.9603449 4.1648312 15 P 0 ;0,1=91,2=90.000000
L 0.9603449 4.1998199 0.9653433 4.1948215 15 P 0 ;0,1=91,2=90.000000
L 0.9603449 4.2248118 0.9603449 4.2348086 15 P 0 ;0,1=91,2=90.000000
L 0.9603449 4.2348086 0.9653433 4.2398069 15 P 0 ;0,1=91,2=90.000000
L 0.9618199 0.7970549 0.9518231 0.7870582 3 P 0 ;0,1=8,2=0.000000
L 0.9633449 4.0040824 0.9633449 4.0190776 15 P 0 ;0,1=58,2=90.000000
L 0.9633449 4.0190776 0.9683433 4.0240759 15 P 0 ;0,1=58,2=90.000000
L 0.9633449 4.0390711 0.9633449 4.0490679 15 P 0 ;0,1=58,2=90.000000
L 0.9633449 4.0490679 0.9683433 4.0540662 15 P 0 ;0,1=58,2=90.000000
L 0.9633449 4.0690614 0.9633449 4.0790582 15 P 0 ;0,1=58,2=90.000000
L 0.9633449 4.0790582 0.9683433 4.0840565 15 P 0 ;0,1=58,2=90.000000
L 0.9653433 4.1848247 0.9603449 4.1798264 15 P 0 ;0,1=91,2=90.000000
L 0.9653433 4.2198134 0.9603449 4.2248118 15 P 0 ;0,1=91,2=90.000000
L 0.9653433 4.2398069 0.9703417 4.2398069 15 P 0 ;0,1=91,2=90.000000
L 0.9668183 0.772063 0.9718166 0.7770614 3 P 0 ;0,1=8,2=0.000000
L 0.9668183 0.7870582 0.9518231 0.7870582 3 P 0 ;0,1=8,2=0.000000
L 0.9683433 4.0240759 0.97834 4.0240759 15 P 0 ;0,1=58,2=90.000000
L 0.9683433 4.0340727 0.9633449 4.0390711 15 P 0 ;0,1=58,2=90.000000
L 0.9683433 4.0540662 0.9733417 4.0540662 15 P 0 ;0,1=58,2=90.000000
L 0.9683433 4.064063 0.9633449 4.0690614 15 P 0 ;0,1=58,2=90.000000
L 0.9683433 4.0840565 0.9883368 4.0840565 15 P 0 ;0,1=58,2=90.000000
L 0.9703417 4.2398069 0.97534 4.2348086 15 P 0 ;0,1=91,2=90.000000
L 0.9718166 0.7770614 0.9718166 0.7820598 3 P 0 ;0,1=8,2=0.000000
L 0.9718166 0.7820598 0.9668183 0.7870582 3 P 0 ;0,1=8,2=0.000000
L 0.9718166 0.8020533 0.9618199 0.7970549 3 P 0 ;0,1=8,2=0.000000
L 0.9733417 4.0540662 0.97834 4.0490679 15 P 0 ;0,1=58,2=90.000000
L 0.97534 4.2298102 0.97534 4.2348086 15 P 0 ;0,1=91,2=90.000000
L 0.97534 4.2348086 0.97534 4.2298102 15 P 0 ;0,1=91,2=90.000000
L 0.97534 4.2348086 0.9803384 4.2398069 15 P 0 ;0,1=91,2=90.000000
L 0.97834 4.0240759 0.9833384 4.0190776 15 P 0 ;0,1=58,2=90.000000
L 0.97834 4.0440695 0.97834 4.0490679 15 P 0 ;0,1=58,2=90.000000
L 0.97834 4.0490679 0.97834 4.0440695 15 P 0 ;0,1=58,2=90.000000
L 0.97834 4.0490679 0.9833384 4.0540662 15 P 0 ;0,1=58,2=90.000000
L 0.9803384 4.2398069 0.9853368 4.2398069 15 P 0 ;0,1=91,2=90.000000
L 0.9833384 4.0140792 0.9933352 4.0240759 15 P 0 ;0,1=58,2=90.000000
L 0.9833384 4.0190776 0.9833384 4.0040824 15 P 0 ;0,1=58,2=90.000000
L 0.9833384 4.0540662 0.9883368 4.0540662 15 P 0 ;0,1=58,2=90.000000
L 0.9853368 4.1848247 0.9653433 4.1848247 15 P 0 ;0,1=91,2=90.000000
L 0.9853368 4.2398069 0.9903352 4.2348086 15 P 0 ;0,1=91,2=90.000000
L 0.9883368 4.0540662 0.9933352 4.0490679 15 P 0 ;0,1=58,2=90.000000
L 0.9883368 4.064063 0.9683433 4.064063 15 P 0 ;0,1=58,2=90.000000
L 0.9883368 4.0840565 0.9933352 4.0790582 15 P 0 ;0,1=58,2=90.000000
L 0.9903352 4.1648312 0.9903352 4.1798264 15 P 0 ;0,1=91,2=90.000000
L 0.9903352 4.1798264 0.9853368 4.1848247 15 P 0 ;0,1=91,2=90.000000
L 0.9903352 4.1948215 0.9903352 4.2048183 15 P 0 ;0,1=91,2=90.000000
L 0.9903352 4.1998199 0.9603449 4.1998199 15 P 0 ;0,1=91,2=90.000000
L 0.9903352 4.2048183 0.9903352 4.1998199 15 P 0 ;0,1=91,2=90.000000
L 0.9903352 4.2248118 0.9853368 4.2198134 15 P 0 ;0,1=91,2=90.000000
L 0.9903352 4.2348086 0.9903352 4.2248118 15 P 0 ;0,1=91,2=90.000000
L 0.9933352 4.0040824 0.9633449 4.0040824 15 P 0 ;0,1=58,2=90.000000
L 0.9933352 4.0390711 0.9883368 4.0340727 15 P 0 ;0,1=58,2=90.000000
L 0.9933352 4.0490679 0.9933352 4.0390711 15 P 0 ;0,1=58,2=90.000000
L 0.9933352 4.0690614 0.9883368 4.064063 15 P 0 ;0,1=58,2=90.000000
L 0.9933352 4.0790582 0.9933352 4.0690614 15 P 0 ;0,1=58,2=90.000000
L 1.0226167 4.066063 1.0619867 4.066063 10 P 0
L 1.0481421 1.2182725 1.0481421 1.2482628 3 P 0 ;0,1=9,2=0.000000
L 1.0481421 1.2482628 1.0631373 1.2482628 3 P 0 ;0,1=9,2=0.000000
L 1.0581389 1.2282693 1.0681356 1.2182725 3 P 0 ;0,1=9,2=0.000000
L 1.0631373 1.2282693 1.0481421 1.2282693 3 P 0 ;0,1=9,2=0.000000
L 1.0631373 1.2482628 1.0681356 1.2432644 3 P 0 ;0,1=9,2=0.000000
L 1.0681356 1.2332677 1.0631373 1.2282693 3 P 0 ;0,1=9,2=0.000000
L 1.0681356 1.2432644 1.0681356 1.2332677 3 P 0 ;0,1=9,2=0.000000
L 1.0697956 1.7320522 1.0697956 1.7620425 3 P 0 ;0,1=10,2=0.000000
L 1.0697956 1.7620425 1.0847908 1.7620425 3 P 0 ;0,1=10,2=0.000000
L 1.0697956 2.2694537 1.0697956 2.299444 3 P 0 ;0,1=4,2=0.000000
L 1.0697956 2.299444 1.0847908 2.299444 3 P 0 ;0,1=4,2=0.000000
L 1.0781324 1.2182725 1.0881292 1.2182725 3 P 0 ;0,1=9,2=0.000000
L 1.0797924 1.742049 1.0897891 1.7320522 3 P 0 ;0,1=10,2=0.000000
L 1.0797924 2.2794505 1.0897891 2.2694537 3 P 0 ;0,1=4,2=0.000000
L 1.0831308 1.2182725 1.0831308 1.2482628 3 P 0 ;0,1=9,2=0.000000
L 1.0831308 1.2482628 1.0781324 1.2432644 3 P 0 ;0,1=9,2=0.000000
L 1.0847908 1.742049 1.0697956 1.742049 3 P 0 ;0,1=10,2=0.000000
L 1.0847908 1.7620425 1.0897891 1.7570441 3 P 0 ;0,1=10,2=0.000000
L 1.0847908 2.2794505 1.0697956 2.2794505 3 P 0 ;0,1=4,2=0.000000
L 1.0847908 2.299444 1.0897891 2.2944456 3 P 0 ;0,1=4,2=0.000000
L 1.0881292 1.2182725 1.0831308 1.2182725 3 P 0 ;0,1=9,2=0.000000
L 1.0897891 1.7470474 1.0847908 1.742049 3 P 0 ;0,1=10,2=0.000000
L 1.0897891 1.7570441 1.0897891 1.7470474 3 P 0 ;0,1=10,2=0.000000
L 1.0897891 2.2844489 1.0847908 2.2794505 3 P 0 ;0,1=4,2=0.000000
L 1.0897891 2.2944456 1.0897891 2.2844489 3 P 0 ;0,1=4,2=0.000000
L 1.0997859 1.7320522 1.1097827 1.7320522 3 P 0 ;0,1=10,2=0.000000
L 1.0997859 2.2694537 1.1097827 2.2694537 3 P 0 ;0,1=4,2=0.000000
L 1.1031243 1.2232709 1.1081227 1.2182725 3 P 0 ;0,1=9,2=0.000000
L 1.1031243 1.2332677 1.1031243 1.2232709 3 P 0 ;0,1=9,2=0.000000
L 1.1047843 1.7320522 1.1047843 1.7620425 3 P 0 ;0,1=10,2=0.000000
L 1.1047843 1.7620425 1.0997859 1.7570441 3 P 0 ;0,1=10,2=0.000000
L 1.1047843 2.2694537 1.1047843 2.299444 3 P 0 ;0,1=4,2=0.000000
L 1.1047843 2.299444 1.0997859 2.2944456 3 P 0 ;0,1=4,2=0.000000
L 1.1081227 1.2182725 1.1181195 1.2182725 3 P 0 ;0,1=9,2=0.000000
L 1.1097827 1.7320522 1.1047843 1.7320522 3 P 0 ;0,1=10,2=0.000000
L 1.1097827 2.2694537 1.1047843 2.2694537 3 P 0 ;0,1=4,2=0.000000
L 1.1131211 1.2432644 1.1031243 1.2332677 3 P 0 ;0,1=9,2=0.000000
L 1.1181195 1.2182725 1.1231178 1.2232709 3 P 0 ;0,1=9,2=0.000000
L 1.1181195 1.2332677 1.1031243 1.2332677 3 P 0 ;0,1=9,2=0.000000
L 1.1231178 1.2232709 1.1231178 1.2282693 3 P 0 ;0,1=9,2=0.000000
L 1.1231178 1.2282693 1.1181195 1.2332677 3 P 0 ;0,1=9,2=0.000000
L 1.1231178 1.2482628 1.1131211 1.2432644 3 P 0 ;0,1=9,2=0.000000
L 1.1247778 1.7470474 1.1347746 1.7520457 3 P 0 ;0,1=10,2=0.000000
L 1.1247778 1.7620425 1.1247778 1.7470474 3 P 0 ;0,1=10,2=0.000000
L 1.1247778 2.2844489 1.1447713 2.2844489 3 P 0 ;0,1=4,2=0.000000
L 1.1297762 1.7320522 1.1247778 1.7370506 3 P 0 ;0,1=10,2=0.000000
L 1.1347746 1.7520457 1.139773 1.7520457 3 P 0 ;0,1=10,2=0.000000
L 1.139773 1.7320522 1.1297762 1.7320522 3 P 0 ;0,1=10,2=0.000000
L 1.139773 1.7520457 1.1447713 1.7470474 3 P 0 ;0,1=10,2=0.000000
L 1.139773 2.2694537 1.139773 2.299444 3 P 0 ;0,1=4,2=0.000000
L 1.139773 2.299444 1.1247778 2.2844489 3 P 0 ;0,1=4,2=0.000000
L 1.1447713 1.7370506 1.139773 1.7320522 3 P 0 ;0,1=10,2=0.000000
L 1.1447713 1.7470474 1.1447713 1.7370506 3 P 0 ;0,1=10,2=0.000000
L 1.1447713 1.7620425 1.1247778 1.7620425 3 P 0 ;0,1=10,2=0.000000
L 1.1623449 4.1678312 1.1923352 4.1678312 15 P 0 ;0,1=90,2=90.000000
L 1.1623449 4.1828264 1.1623449 4.1678312 15 P 0 ;0,1=90,2=90.000000
L 1.1623449 4.2028199 1.1673433 4.1978215 15 P 0 ;0,1=90,2=90.000000
L 1.1623449 4.2378086 1.17734 4.2228134 15 P 0 ;0,1=90,2=90.000000
L 1.1673433 4.1878247 1.1623449 4.1828264 15 P 0 ;0,1=90,2=90.000000
L 1.1683449 4.0135799 1.1683449 4.0285751 15 P 0 ;0,1=57,2=90.000000
L 1.1683449 4.0285751 1.1733433 4.0335734 15 P 0 ;0,1=57,2=90.000000
L 1.1683449 4.0485686 1.1683449 4.0585654 15 P 0 ;0,1=57,2=90.000000
L 1.1683449 4.0585654 1.1733433 4.0635637 15 P 0 ;0,1=57,2=90.000000
L 1.1683449 4.0785589 1.1733433 4.0735605 15 P 0 ;0,1=57,2=90.000000
L 1.1733433 4.0335734 1.18334 4.0335734 15 P 0 ;0,1=57,2=90.000000
L 1.1733433 4.0435702 1.1683449 4.0485686 15 P 0 ;0,1=57,2=90.000000
L 1.1733433 4.0635637 1.1783417 4.0635637 15 P 0 ;0,1=57,2=90.000000
L 1.17734 4.2228134 1.17734 4.2428069 15 P 0 ;0,1=90,2=90.000000
L 1.1783417 4.0635637 1.18334 4.0585654 15 P 0 ;0,1=57,2=90.000000
L 1.18334 4.0335734 1.1883384 4.0285751 15 P 0 ;0,1=57,2=90.000000
L 1.18334 4.053567 1.18334 4.0585654 15 P 0 ;0,1=57,2=90.000000
L 1.18334 4.0585654 1.18334 4.053567 15 P 0 ;0,1=57,2=90.000000
L 1.18334 4.0585654 1.1883384 4.0635637 15 P 0 ;0,1=57,2=90.000000
L 1.1865748 0.7820472 1.1865748 0.8283071 6 P 0
L 1.1865748 0.9838189 1.1865748 1.0300787 6 P 0
L 1.1865748 1.3070472 1.1865748 1.3533071 6 P 0
L 1.1865748 1.5088189 1.1865748 1.5550787 6 P 0
L 1.1865748 1.8320472 1.1865748 1.8783071 6 P 0
L 1.1865748 2.0338189 1.1865748 2.0800787 6 P 0
L 1.1865748 2.3570472 1.1865748 2.4033071 6 P 0
L 1.1865748 2.5588189 1.1865748 2.6050787 6 P 0
L 1.1873368 4.1878247 1.1673433 4.1878247 15 P 0 ;0,1=90,2=90.000000
L 1.1883384 4.0235767 1.1983352 4.0335734 15 P 0 ;0,1=57,2=90.000000
L 1.1883384 4.0285751 1.1883384 4.0135799 15 P 0 ;0,1=57,2=90.000000
L 1.1883384 4.0635637 1.1933368 4.0635637 15 P 0 ;0,1=57,2=90.000000
L 1.1923352 4.1678312 1.1923352 4.1828264 15 P 0 ;0,1=90,2=90.000000
L 1.1923352 4.1828264 1.1873368 4.1878247 15 P 0 ;0,1=90,2=90.000000
L 1.1923352 4.1978215 1.1923352 4.2078183 15 P 0 ;0,1=90,2=90.000000
L 1.1923352 4.2028199 1.1623449 4.2028199 15 P 0 ;0,1=90,2=90.000000
L 1.1923352 4.2078183 1.1923352 4.2028199 15 P 0 ;0,1=90,2=90.000000
L 1.1923352 4.2378086 1.1623449 4.2378086 15 P 0 ;0,1=90,2=90.000000
L 1.1933368 4.0635637 1.1983352 4.0585654 15 P 0 ;0,1=57,2=90.000000
L 1.1983352 4.0135799 1.1683449 4.0135799 15 P 0 ;0,1=57,2=90.000000
L 1.1983352 4.0485686 1.1933368 4.0435702 15 P 0 ;0,1=57,2=90.000000
L 1.1983352 4.0585654 1.1983352 4.0485686 15 P 0 ;0,1=57,2=90.000000
L 1.1983352 4.0735605 1.1983352 4.0835573 15 P 0 ;0,1=57,2=90.000000
L 1.1983352 4.0785589 1.1683449 4.0785589 15 P 0 ;0,1=57,2=90.000000
L 1.1983352 4.0835573 1.1983352 4.0785589 15 P 0 ;0,1=57,2=90.000000
L 1.2242833 4.066063 1.2636533 4.066063 10 P 0
L 1.312559 0.313945 1.312559 0.5029213 0 P 0
L 1.312559 0.313945 1.6275197 0.313945 0 P 0
L 1.3307858 4.2962599 1.3257874 4.3012583 15 P 0 ;0,1=17,2=0.000000
L 1.3326771 4.1043307 1.3326771 4.1200788 6 P 0
L 1.3326772 4 1.3326772 4.0157481 6 P 0
L 1.3357842 4.2962599 1.3307858 4.2962599 15 P 0 ;0,1=17,2=0.000000
L 1.3357842 4.3262502 1.3407826 4.3262502 15 P 0 ;0,1=17,2=0.000000
L 1.3407826 4.3012583 1.3357842 4.2962599 15 P 0 ;0,1=17,2=0.000000
L 1.3407826 4.3262502 1.3407826 4.3012583 15 P 0 ;0,1=17,2=0.000000
L 1.3457809 4.3262502 1.3357842 4.3262502 15 P 0 ;0,1=17,2=0.000000
L 1.3557777 4.2962599 1.3557777 4.3262502 15 P 0 ;0,1=17,2=0.000000
L 1.3557777 4.3262502 1.3707729 4.3262502 15 P 0 ;0,1=17,2=0.000000
L 1.3602362 4.1043307 1.3602362 4.1200788 6 P 0
L 1.3602363 4 1.3602363 4.0157481 6 P 0
L 1.3707729 4.3062567 1.3557777 4.3062567 15 P 0 ;0,1=17,2=0.000000
L 1.3707729 4.3262502 1.3757712 4.3212518 15 P 0 ;0,1=17,2=0.000000
L 1.3757712 4.3112551 1.3707729 4.3062567 15 P 0 ;0,1=17,2=0.000000
L 1.3757712 4.3212518 1.3757712 4.3112551 15 P 0 ;0,1=17,2=0.000000
L 1.385768 4.2962599 1.3957648 4.2962599 15 P 0 ;0,1=17,2=0.000000
L 1.3907664 4.2962599 1.3907664 4.3262502 15 P 0 ;0,1=17,2=0.000000
L 1.3907664 4.3262502 1.385768 4.3212518 15 P 0 ;0,1=17,2=0.000000
L 1.3957648 4.2962599 1.3907664 4.2962599 15 P 0 ;0,1=17,2=0.000000
L 1.4076771 4.003937 1.4076771 4.303937 10 P 0
L 1.4076771 4.003937 1.5076771 4.003937 10 P 0
L 1.4076771 4.303937 1.5076771 4.303937 10 P 0
L 1.5058619 4.2595687 1.5108603 4.2545703 15 P 0 ;0,1=34,2=0.000000
L 1.5058619 4.2795622 1.5058619 4.2595687 15 P 0 ;0,1=34,2=0.000000
L 1.5076771 4.003937 1.5076771 4.303937 10 P 0
L 1.5108603 4.2545703 1.5208571 4.2545703 15 P 0 ;0,1=34,2=0.000000
L 1.5108603 4.2845606 1.5058619 4.2795622 15 P 0 ;0,1=34,2=0.000000
L 1.5208571 4.2545703 1.5258554 4.2595687 15 P 0 ;0,1=34,2=0.000000
L 1.5208571 4.2845606 1.5108603 4.2845606 15 P 0 ;0,1=34,2=0.000000
L 1.5258554 4.2795622 1.5208571 4.2845606 15 P 0 ;0,1=34,2=0.000000
L 1.5358522 4.2595687 1.5408506 4.2545703 15 P 0 ;0,1=34,2=0.000000
L 1.5358522 4.2745638 1.5408506 4.2695655 15 P 0 ;0,1=34,2=0.000000
L 1.5358522 4.2795622 1.5358522 4.2745638 15 P 0 ;0,1=34,2=0.000000
L 1.5408506 4.2545703 1.5508474 4.2545703 15 P 0 ;0,1=34,2=0.000000
L 1.5408506 4.2695655 1.5558457 4.2695655 15 P 0 ;0,1=34,2=0.000000
L 1.5408506 4.2845606 1.5358522 4.2795622 15 P 0 ;0,1=34,2=0.000000
L 1.5413449 4.0258312 1.5663368 4.0258312 15 P 0 ;0,1=37,2=90.000000
L 1.5413449 4.0608199 1.5463433 4.0558215 15 P 0 ;0,1=37,2=90.000000
L 1.5413449 4.1008069 1.5463433 4.0908102 15 P 0 ;0,1=37,2=90.000000
L 1.5463433 4.0908102 1.55634 4.0808134 15 P 0 ;0,1=37,2=90.000000
L 1.5508325 0.815533 1.5508325 2.587193 8 P 0
L 1.5508325 0.815533 3.7161925 0.815533 8 P 0
L 1.5508325 2.587193 3.7161925 2.587193 8 P 0
L 1.5508474 4.2545703 1.5558457 4.2595687 15 P 0 ;0,1=34,2=0.000000
L 1.5508474 4.2845606 1.5408506 4.2845606 15 P 0 ;0,1=34,2=0.000000
L 1.5558457 4.2595687 1.5558457 4.2795622 15 P 0 ;0,1=34,2=0.000000
L 1.5558457 4.2795622 1.5508474 4.2845606 15 P 0 ;0,1=34,2=0.000000
L 1.55634 4.0808134 1.5663368 4.0808134 15 P 0 ;0,1=37,2=90.000000
L 1.55634 4.0958086 1.55634 4.0808134 15 P 0 ;0,1=37,2=90.000000
L 1.5568425 2.619063 1.5568425 2.6490533 15 P 0 ;0,1=11,2=0.000000
L 1.5568425 2.6490533 1.5718377 2.6490533 15 P 0 ;0,1=11,2=0.000000
L 1.5613384 4.1008069 1.55634 4.0958086 15 P 0 ;0,1=37,2=90.000000
L 1.5658425 4.2545703 1.585836 4.2745638 15 P 0 ;0,1=34,2=0.000000
L 1.5663368 4.0258312 1.5713352 4.0308296 15 P 0 ;0,1=37,2=90.000000
L 1.5663368 4.0458247 1.5413449 4.0458247 15 P 0 ;0,1=37,2=90.000000
L 1.5663368 4.0808134 1.5713352 4.0858118 15 P 0 ;0,1=37,2=90.000000
L 1.5663368 4.1008069 1.5613384 4.1008069 15 P 0 ;0,1=37,2=90.000000
L 1.5708409 4.2845606 1.5658425 4.2795622 15 P 0 ;0,1=34,2=0.000000
L 1.5713352 4.0308296 1.5713352 4.0408264 15 P 0 ;0,1=37,2=90.000000
L 1.5713352 4.0408264 1.5663368 4.0458247 15 P 0 ;0,1=37,2=90.000000
L 1.5713352 4.0558215 1.5713352 4.0658183 15 P 0 ;0,1=37,2=90.000000
L 1.5713352 4.0608199 1.5413449 4.0608199 15 P 0 ;0,1=37,2=90.000000
L 1.5713352 4.0658183 1.5713352 4.0608199 15 P 0 ;0,1=37,2=90.000000
L 1.5713352 4.0858118 1.5713352 4.0958086 15 P 0 ;0,1=37,2=90.000000
L 1.5713352 4.0958086 1.5663368 4.1008069 15 P 0 ;0,1=37,2=90.000000
L 1.5718377 2.6290598 1.5568425 2.6290598 15 P 0 ;0,1=11,2=0.000000
L 1.5718377 2.6490533 1.576836 2.6440549 15 P 0 ;0,1=11,2=0.000000
L 1.576836 2.6340582 1.5718377 2.6290598 15 P 0 ;0,1=11,2=0.000000
L 1.576836 2.6440549 1.576836 2.6340582 15 P 0 ;0,1=11,2=0.000000
L 1.5808377 4.2845606 1.5708409 4.2845606 15 P 0 ;0,1=34,2=0.000000
L 1.585836 4.2545703 1.5658425 4.2545703 15 P 0 ;0,1=34,2=0.000000
L 1.585836 4.2745638 1.585836 4.2795622 15 P 0 ;0,1=34,2=0.000000
L 1.585836 4.2795622 1.5808377 4.2845606 15 P 0 ;0,1=34,2=0.000000
L 1.5868328 2.619063 1.5968296 2.619063 15 P 0 ;0,1=11,2=0.000000
L 1.5918312 2.619063 1.5918312 2.6490533 15 P 0 ;0,1=11,2=0.000000
L 1.5918312 2.6490533 1.5868328 2.6440549 15 P 0 ;0,1=11,2=0.000000
L 1.5968296 2.619063 1.5918312 2.619063 15 P 0 ;0,1=11,2=0.000000
L 1.6180925 1.282273 1.6180925 1.308533 9 P 0
L 1.6180925 1.282273 1.6417125 1.282273 9 P 0
L 1.6180925 2.098533 1.6180925 2.124793 9 P 0
L 1.6180925 2.124793 1.6417125 2.124793 9 P 0
L 1.6275197 0.313945 1.6275197 0.4310709 0 P 0
L 1.6417125 1.260623 1.6417125 1.282273 9 P 0
L 1.6417125 1.260623 1.7519525 1.260623 9 P 0
L 1.6417125 2.124793 1.6417125 2.146443 9 P 0
L 1.6417125 2.146443 1.7519525 2.146443 9 P 0
L 1.6684325 2.2345268 1.6784293 2.2445236 3 P 0 ;0,1=14,2=0.000000
L 1.6708425 4.245063 1.7208425 4.245063 10 P 0
L 1.6708425 4.301063 1.7208425 4.301063 10 P 0
L 1.6758503 4.0136378 1.6758503 4.2104882 6 P 0
L 1.6758503 4.0136378 1.8018346 4.0136378 6 P 0
L 1.6758503 4.2104882 1.8018346 4.2104882 6 P 0
L 1.6784293 2.184543 1.6684325 2.1945398 3 P 0 ;0,1=14,2=0.000000
L 1.6784293 2.2445236 1.6984228 2.2445236 3 P 0 ;0,1=14,2=0.000000
L 1.688426 2.2145333 1.6984228 2.2145333 3 P 0 ;0,1=14,2=0.000000
L 1.6984228 2.184543 1.6784293 2.184543 3 P 0 ;0,1=14,2=0.000000
L 1.6984228 2.2145333 1.688426 2.2145333 3 P 0 ;0,1=14,2=0.000000
L 1.6984228 2.2145333 1.7084196 2.2045365 3 P 0 ;0,1=14,2=0.000000
L 1.6984228 2.2445236 1.7084196 2.2345268 3 P 0 ;0,1=14,2=0.000000
L 1.7084196 2.1945398 1.6984228 2.184543 3 P 0 ;0,1=14,2=0.000000
L 1.7084196 2.2045365 1.7084196 2.1945398 3 P 0 ;0,1=14,2=0.000000
L 1.7084196 2.2245301 1.6984228 2.2145333 3 P 0 ;0,1=14,2=0.000000
L 1.7084196 2.2345268 1.7084196 2.2245301 3 P 0 ;0,1=14,2=0.000000
L 1.7519525 1.260623 1.7519525 1.282273 9 P 0
L 1.7519525 1.282273 1.7755725 1.282273 9 P 0
L 1.7519525 2.124793 1.7519525 2.146443 9 P 0
L 1.7519525 2.124793 1.7755725 2.124793 9 P 0
L 1.7755725 1.282273 1.7755725 1.308533 9 P 0
L 1.7755725 2.098533 1.7755725 2.124793 9 P 0
L 1.7878425 0.253063 1.7878425 0.2830533 15 P 0 ;0,1=7,2=0.000000
L 1.7878425 0.2830533 1.8028377 0.2830533 15 P 0 ;0,1=7,2=0.000000
L 1.8018346 4.0136378 1.8018346 4.2104882 6 P 0
L 1.8028377 0.2630598 1.7878425 0.2630598 15 P 0 ;0,1=7,2=0.000000
L 1.8028377 0.2830533 1.807836 0.2780549 15 P 0 ;0,1=7,2=0.000000
L 1.807836 0.2680582 1.8028377 0.2630598 15 P 0 ;0,1=7,2=0.000000
L 1.807836 0.2780549 1.807836 0.2680582 15 P 0 ;0,1=7,2=0.000000
L 1.8078425 4.238063 1.8678425 4.238063 10 P 0
L 1.8078425 4.314063 1.8678425 4.314063 10 P 0
L 1.8178328 0.253063 1.8378263 0.2730565 15 P 0 ;0,1=7,2=0.000000
L 1.8228312 0.2830533 1.8178328 0.2780549 15 P 0 ;0,1=7,2=0.000000
L 1.832828 0.2830533 1.8228312 0.2830533 15 P 0 ;0,1=7,2=0.000000
L 1.8378263 0.253063 1.8178328 0.253063 15 P 0 ;0,1=7,2=0.000000
L 1.8378263 0.2730565 1.8378263 0.2780549 15 P 0 ;0,1=7,2=0.000000
L 1.8378263 0.2780549 1.832828 0.2830533 15 P 0 ;0,1=7,2=0.000000
L 1.8958555 4.1670679 1.8958555 4.1970582 15 P 0 ;0,1=36,2=0.000000
L 1.8958555 4.1970582 1.9108507 4.1970582 15 P 0 ;0,1=36,2=0.000000
L 1.9058523 4.1770647 1.915849 4.1670679 15 P 0 ;0,1=36,2=0.000000
L 1.9108507 4.1770647 1.8958555 4.1770647 15 P 0 ;0,1=36,2=0.000000
L 1.9108507 4.1970582 1.915849 4.1920598 15 P 0 ;0,1=36,2=0.000000
L 1.9141575 4.102063 1.9535275 4.102063 10 P 0
L 1.915849 4.1820631 1.9108507 4.1770647 15 P 0 ;0,1=36,2=0.000000
L 1.915849 4.1920598 1.915849 4.1820631 15 P 0 ;0,1=36,2=0.000000
L 1.9258458 4.1820631 1.9458393 4.1820631 15 P 0 ;0,1=36,2=0.000000
L 1.9353448 4.2285784 1.9403432 4.22358 15 P 0 ;0,1=33,2=90.000000
L 1.9353448 4.2385752 1.9353448 4.2285784 15 P 0 ;0,1=33,2=90.000000
L 1.9353448 4.2585687 1.9403432 4.2535703 15 P 0 ;0,1=33,2=90.000000
L 1.9353448 4.2685655 1.9353448 4.2585687 15 P 0 ;0,1=33,2=90.000000
L 1.9353448 4.288559 1.9403432 4.2835606 15 P 0 ;0,1=33,2=90.000000
L 1.9403432 4.22358 1.9603367 4.22358 15 P 0 ;0,1=33,2=90.000000
L 1.9403432 4.2435735 1.9353448 4.2385752 15 P 0 ;0,1=33,2=90.000000
L 1.9403432 4.2535703 1.9453416 4.2535703 15 P 0 ;0,1=33,2=90.000000
L 1.9403432 4.2735638 1.9353448 4.2685655 15 P 0 ;0,1=33,2=90.000000
L 1.940841 4.1670679 1.940841 4.1970582 15 P 0 ;0,1=36,2=0.000000
L 1.940841 4.1970582 1.9258458 4.1820631 15 P 0 ;0,1=36,2=0.000000
L 1.9453416 4.2535703 1.9503399 4.2585687 15 P 0 ;0,1=33,2=90.000000
L 1.9503399 4.2585687 1.9503399 4.2735638 15 P 0 ;0,1=33,2=90.000000
L 1.9532774 3.995233 1.9532774 4.0002314 15 P 0 ;0,1=16,2=90.000000
L 1.9532774 4.0002314 1.9782693 4.0002314 15 P 0 ;0,1=16,2=90.000000
L 1.9532774 4.0052297 1.9532774 3.995233 15 P 0 ;0,1=16,2=90.000000
L 1.9532774 4.0152265 1.9532774 4.0302217 15 P 0 ;0,1=16,2=90.000000
L 1.9532774 4.0302217 1.9582758 4.03522 15 P 0 ;0,1=16,2=90.000000
L 1.9532774 4.0502152 1.9582758 4.0452168 15 P 0 ;0,1=16,2=90.000000
L 1.9532774 4.060212 1.9532774 4.0502152 15 P 0 ;0,1=16,2=90.000000
L 1.9558361 4.1920598 1.9608345 4.1970582 15 P 0 ;0,1=36,2=0.000000
L 1.9582758 4.03522 1.9682725 4.03522 15 P 0 ;0,1=16,2=90.000000
L 1.9582758 4.0652103 1.9532774 4.060212 15 P 0 ;0,1=16,2=90.000000
L 1.9603367 4.22358 1.9653351 4.2285784 15 P 0 ;0,1=33,2=90.000000
L 1.9603367 4.2535703 1.9653351 4.2585687 15 P 0 ;0,1=33,2=90.000000
L 1.9603367 4.2735638 1.9403432 4.2735638 15 P 0 ;0,1=33,2=90.000000
L 1.9608345 4.1670679 1.9558361 4.1720663 15 P 0 ;0,1=36,2=0.000000
L 1.9608345 4.1970582 1.9708313 4.1970582 15 P 0 ;0,1=36,2=0.000000
L 1.9632742 4.0652103 1.9582758 4.0652103 15 P 0 ;0,1=16,2=90.000000
L 1.9653351 4.2285784 1.9653351 4.2385752 15 P 0 ;0,1=33,2=90.000000
L 1.9653351 4.2385752 1.9603367 4.2435735 15 P 0 ;0,1=33,2=90.000000
L 1.9653351 4.2585687 1.9653351 4.2685655 15 P 0 ;0,1=33,2=90.000000
L 1.9653351 4.2685655 1.9603367 4.2735638 15 P 0 ;0,1=33,2=90.000000
L 1.9653351 4.2835606 1.9653351 4.2935574 15 P 0 ;0,1=33,2=90.000000
L 1.9653351 4.288559 1.9353448 4.288559 15 P 0 ;0,1=33,2=90.000000
L 1.9653351 4.2935574 1.9653351 4.288559 15 P 0 ;0,1=33,2=90.000000
L 1.9658329 4.1820631 1.9708313 4.1820631 15 P 0 ;0,1=36,2=0.000000
L 1.9682725 4.03522 1.9732709 4.0302217 15 P 0 ;0,1=16,2=90.000000
L 1.9708313 4.1670679 1.9608345 4.1670679 15 P 0 ;0,1=36,2=0.000000
L 1.9708313 4.1820631 1.9658329 4.1820631 15 P 0 ;0,1=36,2=0.000000
L 1.9708313 4.1820631 1.9758296 4.1770647 15 P 0 ;0,1=36,2=0.000000
L 1.9708313 4.1970582 1.9758296 4.1920598 15 P 0 ;0,1=36,2=0.000000
L 1.9732709 4.0302217 1.9732709 4.0152265 15 P 0 ;0,1=16,2=90.000000
L 1.9758296 4.1720663 1.9708313 4.1670679 15 P 0 ;0,1=36,2=0.000000
L 1.9758296 4.1770647 1.9758296 4.1720663 15 P 0 ;0,1=36,2=0.000000
L 1.9758296 4.1870614 1.9708313 4.1820631 15 P 0 ;0,1=36,2=0.000000
L 1.9758296 4.1920598 1.9758296 4.1870614 15 P 0 ;0,1=36,2=0.000000
L 1.9782693 4.0002314 1.9832677 3.995233 15 P 0 ;0,1=16,2=90.000000
L 1.9828619 2.6325703 1.9828619 2.6625606 15 P 0 ;0,1=66,2=0.000000
L 1.9828619 2.6625606 1.9978571 2.6625606 15 P 0 ;0,1=66,2=0.000000
L 1.9832677 3.9902346 1.9782693 3.9852362 15 P 0 ;0,1=16,2=90.000000
L 1.9832677 3.995233 1.9832677 3.9902346 15 P 0 ;0,1=16,2=90.000000
L 1.9832677 4.0152265 1.9532774 4.0152265 15 P 0 ;0,1=16,2=90.000000
L 1.9832677 4.0452168 1.9632742 4.0652103 15 P 0 ;0,1=16,2=90.000000
L 1.9832677 4.0652103 1.9832677 4.0452168 15 P 0 ;0,1=16,2=90.000000
L 1.9928587 2.6425671 2.0028554 2.6325703 15 P 0 ;0,1=66,2=0.000000
L 1.9933071 4.007874 1.9933071 4.307874 10 P 0
L 1.9933071 4.007874 2.0933071 4.007874 10 P 0
L 1.9933071 4.307874 2.0933071 4.307874 10 P 0
L 1.9978571 2.6425671 1.9828619 2.6425671 15 P 0 ;0,1=66,2=0.000000
L 1.9978571 2.6625606 2.0028554 2.6575622 15 P 0 ;0,1=66,2=0.000000
L 2.0028554 2.6475655 1.9978571 2.6425671 15 P 0 ;0,1=66,2=0.000000
L 2.0028554 2.6575622 2.0028554 2.6475655 15 P 0 ;0,1=66,2=0.000000
L 2.0128522 2.6325703 2.0328457 2.6525638 15 P 0 ;0,1=66,2=0.000000
L 2.0178506 2.6625606 2.0128522 2.6575622 15 P 0 ;0,1=66,2=0.000000
L 2.0278474 2.6625606 2.0178506 2.6625606 15 P 0 ;0,1=66,2=0.000000
L 2.0328457 2.6325703 2.0128522 2.6325703 15 P 0 ;0,1=66,2=0.000000
L 2.0328457 2.6525638 2.0328457 2.6575622 15 P 0 ;0,1=66,2=0.000000
L 2.0328457 2.6575622 2.0278474 2.6625606 15 P 0 ;0,1=66,2=0.000000
L 2.0428425 2.6325703 2.062836 2.6525638 15 P 0 ;0,1=66,2=0.000000
L 2.0478409 2.6625606 2.0428425 2.6575622 15 P 0 ;0,1=66,2=0.000000
L 2.0578377 2.6625606 2.0478409 2.6625606 15 P 0 ;0,1=66,2=0.000000
L 2.062836 2.6325703 2.0428425 2.6325703 15 P 0 ;0,1=66,2=0.000000
L 2.062836 2.6525638 2.062836 2.6575622 15 P 0 ;0,1=66,2=0.000000
L 2.062836 2.6575622 2.0578377 2.6625606 15 P 0 ;0,1=66,2=0.000000
L 2.0663449 3.6210808 2.0713433 3.6160824 15 P 0 ;0,1=111,2=90.000000
L 2.0663449 3.6310776 2.0663449 3.6210808 15 P 0 ;0,1=111,2=90.000000
L 2.0663449 3.6460727 2.08134 3.6460727 15 P 0 ;0,1=111,2=90.000000
L 2.0663449 3.6660662 2.0663449 3.6460727 15 P 0 ;0,1=111,2=90.000000
L 2.0663449 3.6810614 2.0713433 3.676063 15 P 0 ;0,1=111,2=90.000000
L 2.0663449 3.6910582 2.0663449 3.6810614 15 P 0 ;0,1=111,2=90.000000
L 2.0684325 0.9645333 2.1084196 0.9645333 3 P 0 ;0,1=15,2=0.000000
L 2.0684325 2.409543 2.1084196 2.4495301 3 P 0 ;0,1=13,2=0.000000
L 2.0713433 3.6160824 2.0913368 3.6160824 15 P 0 ;0,1=111,2=90.000000
L 2.0713433 3.6360759 2.0663449 3.6310776 15 P 0 ;0,1=111,2=90.000000
L 2.0713433 3.676063 2.0763417 3.676063 15 P 0 ;0,1=111,2=90.000000
L 2.0713433 3.6960565 2.0663449 3.6910582 15 P 0 ;0,1=111,2=90.000000
L 2.0763417 3.6560695 2.0763417 3.6610679 15 P 0 ;0,1=111,2=90.000000
L 2.0763417 3.6610679 2.08134 3.6660662 15 P 0 ;0,1=111,2=90.000000
L 2.0763417 3.676063 2.08134 3.6810614 15 P 0 ;0,1=111,2=90.000000
L 2.0784293 2.4695236 2.0684325 2.4595268 3 P 0 ;0,1=13,2=0.000000
L 2.08134 3.6460727 2.0763417 3.6560695 15 P 0 ;0,1=111,2=90.000000
L 2.08134 3.6660662 2.0913368 3.6660662 15 P 0 ;0,1=111,2=90.000000
L 2.08134 3.6810614 2.08134 3.6960565 15 P 0 ;0,1=111,2=90.000000
L 2.0913368 3.6160824 2.0963352 3.6210808 15 P 0 ;0,1=111,2=90.000000
L 2.0913368 3.6660662 2.0963352 3.6610679 15 P 0 ;0,1=111,2=90.000000
L 2.0913368 3.676063 2.0963352 3.6810614 15 P 0 ;0,1=111,2=90.000000
L 2.0913368 3.6960565 2.0713433 3.6960565 15 P 0 ;0,1=111,2=90.000000
L 2.0933071 4.007874 2.0933071 4.307874 10 P 0
L 2.0963352 3.6210808 2.0963352 3.6310776 15 P 0 ;0,1=111,2=90.000000
L 2.0963352 3.6310776 2.0913368 3.6360759 15 P 0 ;0,1=111,2=90.000000
L 2.0963352 3.6510711 2.0913368 3.6460727 15 P 0 ;0,1=111,2=90.000000
L 2.0963352 3.6610679 2.0963352 3.6510711 15 P 0 ;0,1=111,2=90.000000
L 2.0963352 3.6810614 2.0963352 3.6910582 15 P 0 ;0,1=111,2=90.000000
L 2.0963352 3.6910582 2.0913368 3.6960565 15 P 0 ;0,1=111,2=90.000000
L 2.0984228 0.934543 2.0984228 0.9945236 3 P 0 ;0,1=15,2=0.000000
L 2.0984228 0.9945236 2.0684325 0.9645333 3 P 0 ;0,1=15,2=0.000000
L 2.0984228 2.4695236 2.0784293 2.4695236 3 P 0 ;0,1=13,2=0.000000
L 2.1084196 2.409543 2.0684325 2.409543 3 P 0 ;0,1=13,2=0.000000
L 2.1084196 2.4495301 2.1084196 2.4595268 3 P 0 ;0,1=13,2=0.000000
L 2.1084196 2.4595268 2.0984228 2.4695236 3 P 0 ;0,1=13,2=0.000000
L 2.1271575 2.652063 2.1665275 2.652063 10 P 0
L 2.1377952 4.0374016 2.1377952 4.0531497 6 P 0
L 2.1539225 2.383413 2.1539225 2.493653 9 P 0
L 2.1539225 2.383413 2.1755725 2.383413 9 P 0
L 2.1539225 2.493653 2.1755725 2.493653 9 P 0
L 2.1539325 0.903473 2.1539325 1.013713 9 P 0
L 2.1539325 0.903473 2.1755825 0.903473 9 P 0
L 2.1539325 1.013713 2.1755825 1.013713 9 P 0
L 2.1653543 4.0374016 2.1653543 4.0531497 6 P 0
L 2.1718425 3.651063 2.1718425 3.711063 10 P 0
L 2.1725669 4.1603386 2.1725669 4.2353386 10 P 0
L 2.1755725 2.359793 2.1755725 2.383413 9 P 0
L 2.1755725 2.359793 2.2018325 2.359793 9 P 0
L 2.1755725 2.493653 2.1755725 2.517273 9 P 0
L 2.1755725 2.517273 2.2018325 2.517273 9 P 0
L 2.1755825 0.879853 2.1755825 0.903473 9 P 0
L 2.1755825 0.879853 2.2018425 0.879853 9 P 0
L 2.1755825 1.013713 2.1755825 1.037333 9 P 0
L 2.1755825 1.037333 2.2018425 1.037333 9 P 0
L 2.1988188 4.0374016 2.1988188 4.0531497 6 P 0
L 2.2023449 3.7680808 2.2073433 3.7630824 15 P 0 ;0,1=112,2=90.000000
L 2.2023449 3.7780776 2.2023449 3.7680808 15 P 0 ;0,1=112,2=90.000000
L 2.2023449 3.7930727 2.21734 3.7930727 15 P 0 ;0,1=112,2=90.000000
L 2.2023449 3.8130662 2.2023449 3.7930727 15 P 0 ;0,1=112,2=90.000000
L 2.2023449 3.8280614 2.2023449 3.8380582 15 P 0 ;0,1=112,2=90.000000
L 2.2023449 3.8380582 2.2073433 3.8430565 15 P 0 ;0,1=112,2=90.000000
L 2.2073433 3.7630824 2.2273368 3.7630824 15 P 0 ;0,1=112,2=90.000000
L 2.2073433 3.7830759 2.2023449 3.7780776 15 P 0 ;0,1=112,2=90.000000
L 2.2073433 3.823063 2.2023449 3.8280614 15 P 0 ;0,1=112,2=90.000000
L 2.2073433 3.8430565 2.2123417 3.8430565 15 P 0 ;0,1=112,2=90.000000
L 2.2123417 3.8030695 2.2123417 3.8080679 15 P 0 ;0,1=112,2=90.000000
L 2.2123417 3.8080679 2.21734 3.8130662 15 P 0 ;0,1=112,2=90.000000
L 2.2123417 3.823063 2.2073433 3.823063 15 P 0 ;0,1=112,2=90.000000
L 2.2123417 3.8430565 2.21734 3.8380582 15 P 0 ;0,1=112,2=90.000000
L 2.21734 3.7930727 2.2123417 3.8030695 15 P 0 ;0,1=112,2=90.000000
L 2.21734 3.8130662 2.2273368 3.8130662 15 P 0 ;0,1=112,2=90.000000
L 2.21734 3.8280614 2.2123417 3.823063 15 P 0 ;0,1=112,2=90.000000
L 2.21734 3.8280614 2.21734 3.8380582 15 P 0 ;0,1=112,2=90.000000
L 2.21734 3.8380582 2.2223384 3.8430565 15 P 0 ;0,1=112,2=90.000000
L 2.2223384 3.823063 2.21734 3.8280614 15 P 0 ;0,1=112,2=90.000000
L 2.2223384 3.8430565 2.2273368 3.8430565 15 P 0 ;0,1=112,2=90.000000
L 2.2263779 4.0374016 2.2263779 4.0531497 6 P 0
L 2.2273368 3.7630824 2.2323352 3.7680808 15 P 0 ;0,1=112,2=90.000000
L 2.2273368 3.8130662 2.2323352 3.8080679 15 P 0 ;0,1=112,2=90.000000
L 2.2273368 3.823063 2.2223384 3.823063 15 P 0 ;0,1=112,2=90.000000
L 2.2273368 3.8430565 2.2323352 3.8380582 15 P 0 ;0,1=112,2=90.000000
L 2.2323352 3.7680808 2.2323352 3.7780776 15 P 0 ;0,1=112,2=90.000000
L 2.2323352 3.7780776 2.2273368 3.7830759 15 P 0 ;0,1=112,2=90.000000
L 2.2323352 3.7980711 2.2273368 3.7930727 15 P 0 ;0,1=112,2=90.000000
L 2.2323352 3.8080679 2.2323352 3.7980711 15 P 0 ;0,1=112,2=90.000000
L 2.2323352 3.8280614 2.2273368 3.823063 15 P 0 ;0,1=112,2=90.000000
L 2.2323352 3.8380582 2.2323352 3.8280614 15 P 0 ;0,1=112,2=90.000000
L 2.2478425 3.651063 2.2478425 3.711063 10 P 0
L 2.3738425 3.008063 2.3738425 3.0380533 3 P 0 ;0,1=5,2=0.000000
L 2.3738425 3.0380533 2.3888377 3.0380533 3 P 0 ;0,1=5,2=0.000000
L 2.3740158 2.9212598 2.3740158 2.9370079 6 P 0
L 2.3838393 3.0180598 2.393836 3.008063 3 P 0 ;0,1=5,2=0.000000
L 2.3888377 3.0180598 2.3738425 3.0180598 3 P 0 ;0,1=5,2=0.000000
L 2.3888377 3.0380533 2.393836 3.0330549 3 P 0 ;0,1=5,2=0.000000
L 2.3888582 3.7160614 2.3938566 3.711063 15 P 0 ;0,1=44,2=0.000000
L 2.3888582 3.7410533 2.3888582 3.7160614 15 P 0 ;0,1=44,2=0.000000
L 2.393836 3.0230582 2.3888377 3.0180598 3 P 0 ;0,1=5,2=0.000000
L 2.393836 3.0330549 2.393836 3.0230582 3 P 0 ;0,1=5,2=0.000000
L 2.3938566 3.711063 2.4038534 3.711063 15 P 0 ;0,1=44,2=0.000000
L 2.4015749 2.9212598 2.4015749 2.9370079 6 P 0
L 2.4025669 4.1066443 2.4025669 4.116641 3 P 0 ;0,1=12,2=270.000000
L 2.4025669 4.116641 2.4625475 4.116641 3 P 0 ;0,1=12,2=270.000000
L 2.4025669 4.1266378 2.4025669 4.1066443 3 P 0 ;0,1=12,2=270.000000
L 2.4038328 3.008063 2.4138296 3.008063 3 P 0 ;0,1=5,2=0.000000
L 2.4038534 3.711063 2.4088517 3.7160614 15 P 0 ;0,1=44,2=0.000000
L 2.4088312 3.008063 2.4088312 3.0380533 3 P 0 ;0,1=5,2=0.000000
L 2.4088312 3.0380533 2.4038328 3.0330549 3 P 0 ;0,1=5,2=0.000000
L 2.4088517 3.7160614 2.4088517 3.7410533 15 P 0 ;0,1=44,2=0.000000
L 2.4138296 3.008063 2.4088312 3.008063 3 P 0 ;0,1=5,2=0.000000
L 2.4188485 3.7160614 2.4238469 3.711063 15 P 0 ;0,1=44,2=0.000000
L 2.4188485 3.7310565 2.4238469 3.7260582 15 P 0 ;0,1=44,2=0.000000
L 2.4188485 3.7360549 2.4188485 3.7310565 15 P 0 ;0,1=44,2=0.000000
L 2.4238469 3.711063 2.4338437 3.711063 15 P 0 ;0,1=44,2=0.000000
L 2.4238469 3.7260582 2.438842 3.7260582 15 P 0 ;0,1=44,2=0.000000
L 2.4238469 3.7410533 2.4188485 3.7360549 15 P 0 ;0,1=44,2=0.000000
L 2.4288247 3.0130614 2.4288247 3.008063 3 P 0 ;0,1=5,2=0.000000
L 2.4288247 3.0380533 2.4488182 3.0380533 3 P 0 ;0,1=5,2=0.000000
L 2.4338437 3.711063 2.438842 3.7160614 15 P 0 ;0,1=44,2=0.000000
L 2.4338437 3.7410533 2.4238469 3.7410533 15 P 0 ;0,1=44,2=0.000000
L 2.4384394 0.5403579 2.4384394 0.5553531 15 P 0 ;0,1=65,2=90.000000
L 2.4384394 0.5553531 2.4434378 0.5603514 15 P 0 ;0,1=65,2=90.000000
L 2.4384394 0.5753466 2.4434378 0.5703482 15 P 0 ;0,1=65,2=90.000000
L 2.4384394 0.5853434 2.4384394 0.5753466 15 P 0 ;0,1=65,2=90.000000
L 2.4384394 0.6053369 2.4384394 0.6153337 15 P 0 ;0,1=65,2=90.000000
L 2.4384394 0.6153337 2.4434378 0.620332 15 P 0 ;0,1=65,2=90.000000
L 2.438842 3.7160614 2.438842 3.7360549 15 P 0 ;0,1=44,2=0.000000
L 2.438842 3.7360549 2.4338437 3.7410533 15 P 0 ;0,1=44,2=0.000000
L 2.4434378 0.5603514 2.4534345 0.5603514 15 P 0 ;0,1=65,2=90.000000
L 2.4434378 0.5903417 2.4384394 0.5853434 15 P 0 ;0,1=65,2=90.000000
L 2.4434378 0.6003385 2.4384394 0.6053369 15 P 0 ;0,1=65,2=90.000000
L 2.4434378 0.620332 2.4484362 0.620332 15 P 0 ;0,1=65,2=90.000000
L 2.4484362 0.5903417 2.4434378 0.5903417 15 P 0 ;0,1=65,2=90.000000
L 2.4484362 0.620332 2.4534345 0.6153337 15 P 0 ;0,1=65,2=90.000000
L 2.4488182 3.0330549 2.4288247 3.0130614 3 P 0 ;0,1=5,2=0.000000
L 2.4488182 3.0380533 2.4488182 3.0330549 3 P 0 ;0,1=5,2=0.000000
L 2.4534345 0.5603514 2.4584329 0.5553531 15 P 0 ;0,1=65,2=90.000000
L 2.4534345 0.6103353 2.4534345 0.6153337 15 P 0 ;0,1=65,2=90.000000
L 2.4534345 0.6153337 2.4534345 0.6103353 15 P 0 ;0,1=65,2=90.000000
L 2.4534345 0.6153337 2.4584329 0.620332 15 P 0 ;0,1=65,2=90.000000
L 2.4584329 0.5503547 2.4684297 0.5603514 15 P 0 ;0,1=65,2=90.000000
L 2.4584329 0.5553531 2.4584329 0.5403579 15 P 0 ;0,1=65,2=90.000000
L 2.4584329 0.620332 2.4634313 0.620332 15 P 0 ;0,1=65,2=90.000000
L 2.4625475 4.116641 2.4525507 4.1266378 3 P 0 ;0,1=12,2=270.000000
L 2.4634313 0.620332 2.4684297 0.6153337 15 P 0 ;0,1=65,2=90.000000
L 2.4684297 0.5403579 2.4384394 0.5403579 15 P 0 ;0,1=65,2=90.000000
L 2.4684297 0.5703482 2.4484362 0.5903417 15 P 0 ;0,1=65,2=90.000000
L 2.4684297 0.5903417 2.4684297 0.5703482 15 P 0 ;0,1=65,2=90.000000
L 2.4684297 0.6053369 2.4634313 0.6003385 15 P 0 ;0,1=65,2=90.000000
L 2.4684297 0.6153337 2.4684297 0.6053369 15 P 0 ;0,1=65,2=90.000000
L 2.4925669 4.1603386 2.4925669 4.2353386 10 P 0
L 2.520353 4.1585703 2.5153546 4.1635687 15 P 0 ;0,1=38,2=0.000000
L 2.5253514 4.1585703 2.520353 4.1585703 15 P 0 ;0,1=38,2=0.000000
L 2.5253514 4.1885606 2.5303498 4.1885606 15 P 0 ;0,1=38,2=0.000000
L 2.5303498 4.1635687 2.5253514 4.1585703 15 P 0 ;0,1=38,2=0.000000
L 2.5303498 4.1885606 2.5303498 4.1635687 15 P 0 ;0,1=38,2=0.000000
L 2.5353481 4.1885606 2.5253514 4.1885606 15 P 0 ;0,1=38,2=0.000000
L 2.5453449 4.1735655 2.5653384 4.1735655 15 P 0 ;0,1=38,2=0.000000
L 2.5603401 4.1585703 2.5603401 4.1885606 15 P 0 ;0,1=38,2=0.000000
L 2.5603401 4.1885606 2.5453449 4.1735655 15 P 0 ;0,1=38,2=0.000000
L 2.6018425 3.541063 2.6018425 3.601063 10 P 0
L 2.6293546 4.2265687 2.634353 4.2215703 15 P 0 ;0,1=47,2=0.000000
L 2.6293546 4.2515606 2.6293546 4.2265687 15 P 0 ;0,1=47,2=0.000000
L 2.634353 4.2215703 2.6443498 4.2215703 15 P 0 ;0,1=47,2=0.000000
L 2.6443498 4.2215703 2.6493481 4.2265687 15 P 0 ;0,1=47,2=0.000000
L 2.6493481 4.2265687 2.6493481 4.2515606 15 P 0 ;0,1=47,2=0.000000
L 2.6593449 4.2365655 2.6693417 4.2415638 15 P 0 ;0,1=47,2=0.000000
L 2.6593449 4.2515606 2.6593449 4.2365655 15 P 0 ;0,1=47,2=0.000000
L 2.6628937 2.7167323 2.6628937 3.9667323 3 P 0
L 2.6643433 4.2215703 2.6593449 4.2265687 15 P 0 ;0,1=47,2=0.000000
L 2.6693417 4.2415638 2.6743401 4.2415638 15 P 0 ;0,1=47,2=0.000000
L 2.6743401 4.2215703 2.6643433 4.2215703 15 P 0 ;0,1=47,2=0.000000
L 2.6743401 4.2415638 2.6793384 4.2365655 15 P 0 ;0,1=47,2=0.000000
L 2.6765355 3.6794882 2.6765355 3.7188582 6 P 0
L 2.6765355 3.6794882 2.694252 3.6794882 6 P 0
L 2.6778425 3.541063 2.6778425 3.601063 10 P 0
L 2.6793384 4.2265687 2.6743401 4.2215703 15 P 0 ;0,1=47,2=0.000000
L 2.6793384 4.2365655 2.6793384 4.2265687 15 P 0 ;0,1=47,2=0.000000
L 2.6793384 4.2515606 2.6593449 4.2515606 15 P 0 ;0,1=47,2=0.000000
L 2.6923449 3.3590808 2.6973433 3.3540824 15 P 0 ;0,1=110,2=90.000000
L 2.6923449 3.3690776 2.6923449 3.3590808 15 P 0 ;0,1=110,2=90.000000
L 2.6923449 3.4040662 2.6973433 3.3940695 15 P 0 ;0,1=110,2=90.000000
L 2.6923449 3.4190614 2.6923449 3.4290582 15 P 0 ;0,1=110,2=90.000000
L 2.6923449 3.4290582 2.6973433 3.4340565 15 P 0 ;0,1=110,2=90.000000
L 2.6973433 3.3540824 2.7173368 3.3540824 15 P 0 ;0,1=110,2=90.000000
L 2.6973433 3.3740759 2.6923449 3.3690776 15 P 0 ;0,1=110,2=90.000000
L 2.6973433 3.3940695 2.70734 3.3840727 15 P 0 ;0,1=110,2=90.000000
L 2.6973433 3.414063 2.6923449 3.4190614 15 P 0 ;0,1=110,2=90.000000
L 2.6973433 3.4340565 2.7173368 3.4340565 15 P 0 ;0,1=110,2=90.000000
L 2.7053546 3.8225703 2.7203498 3.8225703 15 P 0 ;0,1=98,2=0.000000
L 2.7053546 3.8525606 2.7053546 3.8225703 15 P 0 ;0,1=98,2=0.000000
L 2.70734 3.3840727 2.7173368 3.3840727 15 P 0 ;0,1=110,2=90.000000
L 2.70734 3.3990679 2.70734 3.3840727 15 P 0 ;0,1=110,2=90.000000
L 2.7123384 3.4040662 2.70734 3.3990679 15 P 0 ;0,1=110,2=90.000000
L 2.7173368 3.3540824 2.7223352 3.3590808 15 P 0 ;0,1=110,2=90.000000
L 2.7173368 3.3840727 2.7223352 3.3890711 15 P 0 ;0,1=110,2=90.000000
L 2.7173368 3.4040662 2.7123384 3.4040662 15 P 0 ;0,1=110,2=90.000000
L 2.7173368 3.414063 2.6973433 3.414063 15 P 0 ;0,1=110,2=90.000000
L 2.7173368 3.4340565 2.7223352 3.4290582 15 P 0 ;0,1=110,2=90.000000
L 2.7203498 3.8225703 2.7253481 3.8275687 15 P 0 ;0,1=98,2=0.000000
L 2.7203498 3.8525606 2.7053546 3.8525606 15 P 0 ;0,1=98,2=0.000000
L 2.7223352 3.3590808 2.7223352 3.3690776 15 P 0 ;0,1=110,2=90.000000
L 2.7223352 3.3690776 2.7173368 3.3740759 15 P 0 ;0,1=110,2=90.000000
L 2.7223352 3.3890711 2.7223352 3.3990679 15 P 0 ;0,1=110,2=90.000000
L 2.7223352 3.3990679 2.7173368 3.4040662 15 P 0 ;0,1=110,2=90.000000
L 2.7223352 3.4190614 2.7173368 3.414063 15 P 0 ;0,1=110,2=90.000000
L 2.7223352 3.4290582 2.7223352 3.4190614 15 P 0 ;0,1=110,2=90.000000
L 2.7253481 3.8275687 2.7253481 3.8475622 15 P 0 ;0,1=98,2=0.000000
L 2.7253481 3.8475622 2.7203498 3.8525606 15 P 0 ;0,1=98,2=0.000000
L 2.7353449 3.8275687 2.7403433 3.8225703 15 P 0 ;0,1=98,2=0.000000
L 2.7353449 3.8375655 2.7353449 3.8275687 15 P 0 ;0,1=98,2=0.000000
L 2.7403433 3.8225703 2.7503401 3.8225703 15 P 0 ;0,1=98,2=0.000000
L 2.7448425 3.9036221 2.7448425 4.2685827 6 P 0
L 2.7448425 3.9036221 2.906063 3.9036221 6 P 0
L 2.7448425 4.2685827 2.906063 4.2685827 6 P 0
L 2.7453417 3.8475622 2.7353449 3.8375655 15 P 0 ;0,1=98,2=0.000000
L 2.7454331 3.6794882 2.7631496 3.6794882 6 P 0
L 2.7503401 3.8225703 2.7553384 3.8275687 15 P 0 ;0,1=98,2=0.000000
L 2.7503401 3.8375655 2.7353449 3.8375655 15 P 0 ;0,1=98,2=0.000000
L 2.7553384 3.8275687 2.7553384 3.8325671 15 P 0 ;0,1=98,2=0.000000
L 2.7553384 3.8325671 2.7503401 3.8375655 15 P 0 ;0,1=98,2=0.000000
L 2.7553384 3.8525606 2.7453417 3.8475622 15 P 0 ;0,1=98,2=0.000000
L 2.7631496 3.6794882 2.7631496 3.7188582 6 P 0
L 2.7673449 3.4475783 2.7723433 3.4425799 15 P 0 ;0,1=109,2=90.000000
L 2.7673449 3.4575751 2.7673449 3.4475783 15 P 0 ;0,1=109,2=90.000000
L 2.7673449 3.4925637 2.7723433 3.482567 15 P 0 ;0,1=109,2=90.000000
L 2.7673449 3.5075589 2.7723433 3.5025605 15 P 0 ;0,1=109,2=90.000000
L 2.7723433 3.4425799 2.7923368 3.4425799 15 P 0 ;0,1=109,2=90.000000
L 2.7723433 3.4625734 2.7673449 3.4575751 15 P 0 ;0,1=109,2=90.000000
L 2.7723433 3.482567 2.78234 3.4725702 15 P 0 ;0,1=109,2=90.000000
L 2.78234 3.4725702 2.7923368 3.4725702 15 P 0 ;0,1=109,2=90.000000
L 2.78234 3.4875654 2.78234 3.4725702 15 P 0 ;0,1=109,2=90.000000
L 2.7873384 3.4925637 2.78234 3.4875654 15 P 0 ;0,1=109,2=90.000000
L 2.7915355 3.6794882 2.7915355 3.7188582 6 P 0
L 2.7915355 3.6794882 2.809252 3.6794882 6 P 0
L 2.7923368 3.4425799 2.7973352 3.4475783 15 P 0 ;0,1=109,2=90.000000
L 2.7923368 3.4725702 2.7973352 3.4775686 15 P 0 ;0,1=109,2=90.000000
L 2.7923368 3.4925637 2.7873384 3.4925637 15 P 0 ;0,1=109,2=90.000000
L 2.7973352 3.4475783 2.7973352 3.4575751 15 P 0 ;0,1=109,2=90.000000
L 2.7973352 3.4575751 2.7923368 3.4625734 15 P 0 ;0,1=109,2=90.000000
L 2.7973352 3.4775686 2.7973352 3.4875654 15 P 0 ;0,1=109,2=90.000000
L 2.7973352 3.4875654 2.7923368 3.4925637 15 P 0 ;0,1=109,2=90.000000
L 2.7973352 3.5025605 2.7973352 3.5125573 15 P 0 ;0,1=109,2=90.000000
L 2.7973352 3.5075589 2.7673449 3.5075589 15 P 0 ;0,1=109,2=90.000000
L 2.7973352 3.5125573 2.7973352 3.5075589 15 P 0 ;0,1=109,2=90.000000
L 2.8120079 2.9055118 2.8120079 3.3188976 6 P 0
L 2.8120079 2.9055118 3.0561024 2.9055118 6 P 0
L 2.8120079 3.3188976 3.0561024 3.3188976 6 P 0
L 2.8411498 3.356145 2.8461482 3.3511466 3 P 0 ;0,1=2,2=0.000000
L 2.8411498 3.3811369 2.8411498 3.356145 3 P 0 ;0,1=2,2=0.000000
L 2.8461482 3.3511466 2.856145 3.3511466 3 P 0 ;0,1=2,2=0.000000
L 2.856145 3.3511466 2.8611433 3.356145 3 P 0 ;0,1=2,2=0.000000
L 2.8604331 3.6794882 2.8781496 3.6794882 6 P 0
L 2.8611433 3.356145 2.8611433 3.3811369 3 P 0 ;0,1=2,2=0.000000
L 2.8653449 3.5485751 2.8953352 3.5485751 15 P 0 ;0,1=99,2=90.000000
L 2.8653449 3.5635703 2.8653449 3.5485751 15 P 0 ;0,1=99,2=90.000000
L 2.8653449 3.5785654 2.88034 3.5785654 15 P 0 ;0,1=99,2=90.000000
L 2.8653449 3.5985589 2.8653449 3.5785654 15 P 0 ;0,1=99,2=90.000000
L 2.8703433 3.5685686 2.8653449 3.5635703 15 P 0 ;0,1=99,2=90.000000
L 2.8711401 3.3761385 2.8761385 3.3811369 3 P 0 ;0,1=2,2=0.000000
L 2.8753417 3.5885622 2.8753417 3.5935606 15 P 0 ;0,1=99,2=90.000000
L 2.8753417 3.5935606 2.88034 3.5985589 15 P 0 ;0,1=99,2=90.000000
L 2.8761385 3.3511466 2.8711401 3.356145 3 P 0 ;0,1=2,2=0.000000
L 2.8761385 3.3811369 2.8861353 3.3811369 3 P 0 ;0,1=2,2=0.000000
L 2.8781496 3.6794882 2.8781496 3.7188582 6 P 0
L 2.88034 3.5785654 2.8753417 3.5885622 15 P 0 ;0,1=99,2=90.000000
L 2.88034 3.5985589 2.8903368 3.5985589 15 P 0 ;0,1=99,2=90.000000
L 2.8811369 3.3661418 2.8861353 3.3661418 3 P 0 ;0,1=2,2=0.000000
L 2.8861353 3.3511466 2.8761385 3.3511466 3 P 0 ;0,1=2,2=0.000000
L 2.8861353 3.3661418 2.8811369 3.3661418 3 P 0 ;0,1=2,2=0.000000
L 2.8861353 3.3661418 2.8911336 3.3611434 3 P 0 ;0,1=2,2=0.000000
L 2.8861353 3.3811369 2.8911336 3.3761385 3 P 0 ;0,1=2,2=0.000000
L 2.8903368 3.5685686 2.8703433 3.5685686 15 P 0 ;0,1=99,2=90.000000
L 2.8903368 3.5985589 2.8953352 3.5935606 15 P 0 ;0,1=99,2=90.000000
L 2.8911336 3.356145 2.8861353 3.3511466 3 P 0 ;0,1=2,2=0.000000
L 2.8911336 3.3611434 2.8911336 3.356145 3 P 0 ;0,1=2,2=0.000000
L 2.8911336 3.3711401 2.8861353 3.3661418 3 P 0 ;0,1=2,2=0.000000
L 2.8911336 3.3761385 2.8911336 3.3711401 3 P 0 ;0,1=2,2=0.000000
L 2.8953352 3.5485751 2.8953352 3.5635703 15 P 0 ;0,1=99,2=90.000000
L 2.8953352 3.5635703 2.8903368 3.5685686 15 P 0 ;0,1=99,2=90.000000
L 2.8953352 3.5835638 2.8903368 3.5785654 15 P 0 ;0,1=99,2=90.000000
L 2.8953352 3.5935606 2.8953352 3.5835638 15 P 0 ;0,1=99,2=90.000000
L 2.9148425 3.706063 2.9748425 3.706063 10 P 0
L 2.9423449 3.5138312 2.9423449 3.5288264 15 P 0 ;0,1=70,2=90.000000
L 2.9423449 3.5288264 2.9473433 3.5338247 15 P 0 ;0,1=70,2=90.000000
L 2.9423449 3.5488199 2.9473433 3.5438215 15 P 0 ;0,1=70,2=90.000000
L 2.9423449 3.5738118 2.9423449 3.5838086 15 P 0 ;0,1=70,2=90.000000
L 2.9423449 3.5838086 2.9473433 3.5888069 15 P 0 ;0,1=70,2=90.000000
L 2.9473433 3.5338247 2.95734 3.5338247 15 P 0 ;0,1=70,2=90.000000
L 2.9473433 3.5688134 2.9423449 3.5738118 15 P 0 ;0,1=70,2=90.000000
L 2.9473433 3.5888069 2.9523417 3.5888069 15 P 0 ;0,1=70,2=90.000000
L 2.9523417 3.5688134 2.9473433 3.5688134 15 P 0 ;0,1=70,2=90.000000
L 2.9523417 3.5888069 2.95734 3.5838086 15 P 0 ;0,1=70,2=90.000000
L 2.95734 3.5338247 2.9623384 3.5288264 15 P 0 ;0,1=70,2=90.000000
L 2.95734 3.5738118 2.9523417 3.5688134 15 P 0 ;0,1=70,2=90.000000
L 2.95734 3.5738118 2.95734 3.5838086 15 P 0 ;0,1=70,2=90.000000
L 2.95734 3.5838086 2.9623384 3.5888069 15 P 0 ;0,1=70,2=90.000000
L 2.9623384 3.523828 2.9723352 3.5338247 15 P 0 ;0,1=70,2=90.000000
L 2.9623384 3.5288264 2.9623384 3.5138312 15 P 0 ;0,1=70,2=90.000000
L 2.9623384 3.5688134 2.95734 3.5738118 15 P 0 ;0,1=70,2=90.000000
L 2.9623384 3.5888069 2.9673368 3.5888069 15 P 0 ;0,1=70,2=90.000000
L 2.9673368 3.5688134 2.9623384 3.5688134 15 P 0 ;0,1=70,2=90.000000
L 2.9673368 3.5888069 2.9723352 3.5838086 15 P 0 ;0,1=70,2=90.000000
L 2.9723352 3.5138312 2.9423449 3.5138312 15 P 0 ;0,1=70,2=90.000000
L 2.9723352 3.5438215 2.9723352 3.5538183 15 P 0 ;0,1=70,2=90.000000
L 2.9723352 3.5488199 2.9423449 3.5488199 15 P 0 ;0,1=70,2=90.000000
L 2.9723352 3.5538183 2.9723352 3.5488199 15 P 0 ;0,1=70,2=90.000000
L 2.9723352 3.5738118 2.9673368 3.5688134 15 P 0 ;0,1=70,2=90.000000
L 2.9723352 3.5838086 2.9723352 3.5738118 15 P 0 ;0,1=70,2=90.000000
L 2.9866205 0.5373579 2.9866205 0.5523531 15 P 0 ;0,1=64,2=90.000000
L 2.9866205 0.5523531 2.9916189 0.5573514 15 P 0 ;0,1=64,2=90.000000
L 2.9866205 0.5723466 2.9916189 0.5673482 15 P 0 ;0,1=64,2=90.000000
L 2.9866205 0.5823434 2.9866205 0.5723466 15 P 0 ;0,1=64,2=90.000000
L 2.9866205 0.6123337 3.0016156 0.5973385 15 P 0 ;0,1=64,2=90.000000
L 2.9916189 0.5573514 3.0016156 0.5573514 15 P 0 ;0,1=64,2=90.000000
L 2.9916189 0.5873417 2.9866205 0.5823434 15 P 0 ;0,1=64,2=90.000000
L 2.9918325 2.359793 3.0180925 2.359793 9 P 0
L 2.9918325 2.517273 3.0180925 2.517273 9 P 0
L 2.9918425 0.879853 3.0181025 0.879853 9 P 0
L 2.9918425 1.037333 3.0181025 1.037333 9 P 0
L 2.9966173 0.5873417 2.9916189 0.5873417 15 P 0 ;0,1=64,2=90.000000
L 3.0016156 0.5573514 3.006614 0.5523531 15 P 0 ;0,1=64,2=90.000000
L 3.0016156 0.5973385 3.0016156 0.617332 15 P 0 ;0,1=64,2=90.000000
L 3.006614 0.5473547 3.0166108 0.5573514 15 P 0 ;0,1=64,2=90.000000
L 3.006614 0.5523531 3.006614 0.5373579 15 P 0 ;0,1=64,2=90.000000
L 3.0148425 3.706063 3.0748425 3.706063 10 P 0
L 3.0166108 0.5373579 2.9866205 0.5373579 15 P 0 ;0,1=64,2=90.000000
L 3.0166108 0.5673482 2.9966173 0.5873417 15 P 0 ;0,1=64,2=90.000000
L 3.0166108 0.5873417 3.0166108 0.5673482 15 P 0 ;0,1=64,2=90.000000
L 3.0166108 0.6123337 2.9866205 0.6123337 15 P 0 ;0,1=64,2=90.000000
L 3.0180925 2.359793 3.0180925 2.383413 9 P 0
L 3.0180925 2.383413 3.0397425 2.383413 9 P 0
L 3.0180925 2.493653 3.0180925 2.517273 9 P 0
L 3.0180925 2.493653 3.0397425 2.493653 9 P 0
L 3.0181025 0.879853 3.0181025 0.903473 9 P 0
L 3.0181025 0.903473 3.0397525 0.903473 9 P 0
L 3.0181025 1.013713 3.0181025 1.037333 9 P 0
L 3.0181025 1.013713 3.0397525 1.013713 9 P 0
L 3.0363449 3.5138312 3.0363449 3.5288264 15 P 0 ;0,1=69,2=90.000000
L 3.0363449 3.5288264 3.0413433 3.5338247 15 P 0 ;0,1=69,2=90.000000
L 3.0363449 3.5488199 3.0413433 3.5438215 15 P 0 ;0,1=69,2=90.000000
L 3.0363449 3.5738118 3.0413433 3.5688134 15 P 0 ;0,1=69,2=90.000000
L 3.0363449 3.5838086 3.0363449 3.5738118 15 P 0 ;0,1=69,2=90.000000
L 3.0397425 2.383413 3.0397425 2.493653 9 P 0
L 3.0397525 0.903473 3.0397525 1.013713 9 P 0
L 3.0413433 3.5338247 3.05134 3.5338247 15 P 0 ;0,1=69,2=90.000000
L 3.0413433 3.5688134 3.0463417 3.5688134 15 P 0 ;0,1=69,2=90.000000
L 3.0413433 3.5888069 3.0363449 3.5838086 15 P 0 ;0,1=69,2=90.000000
L 3.0463417 3.5688134 3.05134 3.5738118 15 P 0 ;0,1=69,2=90.000000
L 3.05134 3.5338247 3.0563384 3.5288264 15 P 0 ;0,1=69,2=90.000000
L 3.05134 3.5738118 3.05134 3.5888069 15 P 0 ;0,1=69,2=90.000000
L 3.0561024 2.9055118 3.0561024 3.3188976 6 P 0
L 3.0563384 3.523828 3.0663352 3.5338247 15 P 0 ;0,1=69,2=90.000000
L 3.0563384 3.5288264 3.0563384 3.5138312 15 P 0 ;0,1=69,2=90.000000
L 3.0613368 3.5688134 3.0663352 3.5738118 15 P 0 ;0,1=69,2=90.000000
L 3.0613368 3.5888069 3.0413433 3.5888069 15 P 0 ;0,1=69,2=90.000000
L 3.0663352 3.5138312 3.0363449 3.5138312 15 P 0 ;0,1=69,2=90.000000
L 3.0663352 3.5438215 3.0663352 3.5538183 15 P 0 ;0,1=69,2=90.000000
L 3.0663352 3.5488199 3.0363449 3.5488199 15 P 0 ;0,1=69,2=90.000000
L 3.0663352 3.5538183 3.0663352 3.5488199 15 P 0 ;0,1=69,2=90.000000
L 3.0663352 3.5738118 3.0663352 3.5838086 15 P 0 ;0,1=69,2=90.000000
L 3.0663352 3.5838086 3.0613368 3.5888069 15 P 0 ;0,1=69,2=90.000000
L 3.1148425 3.706063 3.1748425 3.706063 10 P 0
L 3.1383449 3.5100824 3.1383449 3.5250776 15 P 0 ;0,1=68,2=90.000000
L 3.1383449 3.5250776 3.1433433 3.5300759 15 P 0 ;0,1=68,2=90.000000
L 3.1383449 3.5450711 3.1433433 3.5400727 15 P 0 ;0,1=68,2=90.000000
L 3.1383449 3.5550679 3.1383449 3.5450711 15 P 0 ;0,1=68,2=90.000000
L 3.1383449 3.5750614 3.1383449 3.5850582 15 P 0 ;0,1=68,2=90.000000
L 3.1383449 3.5850582 3.1433433 3.5900565 15 P 0 ;0,1=68,2=90.000000
L 3.1433433 3.5300759 3.15334 3.5300759 15 P 0 ;0,1=68,2=90.000000
L 3.1433433 3.5600662 3.1383449 3.5550679 15 P 0 ;0,1=68,2=90.000000
L 3.1433433 3.570063 3.1383449 3.5750614 15 P 0 ;0,1=68,2=90.000000
L 3.1433433 3.5900565 3.1633368 3.5900565 15 P 0 ;0,1=68,2=90.000000
L 3.1483417 3.5600662 3.1433433 3.5600662 15 P 0 ;0,1=68,2=90.000000
L 3.15334 3.5300759 3.1583384 3.5250776 15 P 0 ;0,1=68,2=90.000000
L 3.1583384 3.5200792 3.1683352 3.5300759 15 P 0 ;0,1=68,2=90.000000
L 3.1583384 3.5250776 3.1583384 3.5100824 15 P 0 ;0,1=68,2=90.000000
L 3.1591082 3.3955687 3.1641066 3.3905703 15 P 0 ;0,1=42,2=0.000000
L 3.1591082 3.4205606 3.1591082 3.3955687 15 P 0 ;0,1=42,2=0.000000
L 3.1633368 3.570063 3.1433433 3.570063 15 P 0 ;0,1=68,2=90.000000
L 3.1633368 3.5900565 3.1683352 3.5850582 15 P 0 ;0,1=68,2=90.000000
L 3.1641066 3.3905703 3.1741034 3.3905703 15 P 0 ;0,1=42,2=0.000000
L 3.1683352 3.5100824 3.1383449 3.5100824 15 P 0 ;0,1=68,2=90.000000
L 3.1683352 3.5400727 3.1483417 3.5600662 15 P 0 ;0,1=68,2=90.000000
L 3.1683352 3.5600662 3.1683352 3.5400727 15 P 0 ;0,1=68,2=90.000000
L 3.1683352 3.5750614 3.1633368 3.570063 15 P 0 ;0,1=68,2=90.000000
L 3.1683352 3.5850582 3.1683352 3.5750614 15 P 0 ;0,1=68,2=90.000000
L 3.1741034 3.3905703 3.1791017 3.3955687 15 P 0 ;0,1=42,2=0.000000
L 3.1791017 3.3955687 3.1791017 3.4205606 15 P 0 ;0,1=42,2=0.000000
L 3.1890985 3.3905703 3.1990953 3.3905703 15 P 0 ;0,1=42,2=0.000000
L 3.1918425 2.916063 3.2018393 2.916063 3 P 0 ;0,1=6,2=0.000000
L 3.1918425 2.9460533 3.2018393 2.9460533 3 P 0 ;0,1=6,2=0.000000
L 3.1940969 3.3905703 3.1940969 3.4205606 15 P 0 ;0,1=42,2=0.000000
L 3.1940969 3.4205606 3.1890985 3.4155622 15 P 0 ;0,1=42,2=0.000000
L 3.1968409 2.916063 3.1918425 2.916063 3 P 0 ;0,1=6,2=0.000000
L 3.1968409 2.9460533 3.1968409 2.916063 3 P 0 ;0,1=6,2=0.000000
L 3.1990953 3.3905703 3.1940969 3.3905703 15 P 0 ;0,1=42,2=0.000000
L 3.1998031 2.7755905 3.1998031 2.7834645 0 P 0
L 3.1998031 2.7755905 3.2194882 2.7755905 0 P 0
L 3.1998031 2.8464567 3.1998031 2.8543307 0 P 0
L 3.1998031 2.8543307 3.2194882 2.8543307 0 P 0
L 3.2015355 3.6794882 3.2015355 3.7188582 6 P 0
L 3.2015355 3.6794882 3.219252 3.6794882 6 P 0
L 3.2018393 2.9460533 3.1968409 2.9460533 3 P 0 ;0,1=6,2=0.000000
L 3.2140904 3.3905703 3.2240872 3.3905703 15 P 0 ;0,1=42,2=0.000000
L 3.2168344 2.9210614 3.2218328 2.916063 3 P 0 ;0,1=6,2=0.000000
L 3.2168344 2.9410549 3.2168344 2.9210614 3 P 0 ;0,1=6,2=0.000000
L 3.2190888 3.3905703 3.2190888 3.4205606 15 P 0 ;0,1=42,2=0.000000
L 3.2190888 3.4205606 3.2140904 3.4155622 15 P 0 ;0,1=42,2=0.000000
L 3.2218328 2.916063 3.2318296 2.916063 3 P 0 ;0,1=6,2=0.000000
L 3.2218328 2.9460533 3.2168344 2.9410549 3 P 0 ;0,1=6,2=0.000000
L 3.2240872 3.3905703 3.2190888 3.3905703 15 P 0 ;0,1=42,2=0.000000
L 3.2318296 2.916063 3.2368279 2.9210614 3 P 0 ;0,1=6,2=0.000000
L 3.2318296 2.9460533 3.2218328 2.9460533 3 P 0 ;0,1=6,2=0.000000
L 3.2353449 3.5005751 3.2653352 3.5005751 15 P 0 ;0,1=97,2=90.000000
L 3.2353449 3.5155703 3.2353449 3.5005751 15 P 0 ;0,1=97,2=90.000000
L 3.2353449 3.5305654 3.2353449 3.5505589 15 P 0 ;0,1=97,2=90.000000
L 3.2353449 3.5505589 3.2403433 3.5505589 15 P 0 ;0,1=97,2=90.000000
L 3.2368279 2.9410549 3.2318296 2.9460533 3 P 0 ;0,1=6,2=0.000000
L 3.2403433 3.5205686 3.2353449 3.5155703 15 P 0 ;0,1=97,2=90.000000
L 3.2403433 3.5505589 3.2603368 3.5305654 15 P 0 ;0,1=97,2=90.000000
L 3.2468247 2.9410549 3.2518231 2.9460533 3 P 0 ;0,1=6,2=0.000000
L 3.2518231 2.9460533 3.2618199 2.9460533 3 P 0 ;0,1=6,2=0.000000
L 3.2568215 2.9210614 3.2568215 2.916063 3 P 0 ;0,1=6,2=0.000000
L 3.2588582 2.7755905 3.2785433 2.7755905 0 P 0
L 3.2588582 2.8543307 3.2785433 2.8543307 0 P 0
L 3.2603368 3.5205686 3.2403433 3.5205686 15 P 0 ;0,1=97,2=90.000000
L 3.2603368 3.5305654 3.2653352 3.5305654 15 P 0 ;0,1=97,2=90.000000
L 3.2618199 2.9460533 3.2668182 2.9410549 3 P 0 ;0,1=6,2=0.000000
L 3.2653352 3.5005751 3.2653352 3.5155703 15 P 0 ;0,1=97,2=90.000000
L 3.2653352 3.5155703 3.2603368 3.5205686 15 P 0 ;0,1=97,2=90.000000
L 3.2668182 2.9360565 3.2568215 2.9260598 3 P 0 ;0,1=6,2=0.000000
L 3.2668182 2.9410549 3.2668182 2.9360565 3 P 0 ;0,1=6,2=0.000000
L 3.2704331 3.6794882 3.2881496 3.6794882 6 P 0
L 3.2740551 3.1629134 3.2740551 3.2022835 12 P 0
L 3.2740551 3.1629134 3.3134252 3.1629134 12 P 0
L 3.2740551 3.3991339 3.2740551 3.438504 12 P 0
L 3.2740551 3.438504 3.3134252 3.438504 12 P 0
L 3.2785433 2.7755905 3.2785433 2.7834645 0 P 0
L 3.2785433 2.8464567 3.2785433 2.8543307 0 P 0
L 3.2881496 3.6794882 3.2881496 3.7188582 6 P 0
L 3.3198425 3.706063 3.3798425 3.706063 10 P 0
L 3.3413449 3.5195799 3.3413449 3.5345751 15 P 0 ;0,1=67,2=90.000000
L 3.3413449 3.5345751 3.3463433 3.5395734 15 P 0 ;0,1=67,2=90.000000
L 3.3413449 3.5545686 3.3463433 3.5495702 15 P 0 ;0,1=67,2=90.000000
L 3.3413449 3.5645654 3.3413449 3.5545686 15 P 0 ;0,1=67,2=90.000000
L 3.3413449 3.5845589 3.3463433 3.5795605 15 P 0 ;0,1=67,2=90.000000
L 3.3463433 3.5395734 3.35634 3.5395734 15 P 0 ;0,1=67,2=90.000000
L 3.3463433 3.5695637 3.3413449 3.5645654 15 P 0 ;0,1=67,2=90.000000
L 3.3513417 3.5695637 3.3463433 3.5695637 15 P 0 ;0,1=67,2=90.000000
L 3.35634 3.5395734 3.3613384 3.5345751 15 P 0 ;0,1=67,2=90.000000
L 3.3613384 3.5295767 3.3713352 3.5395734 15 P 0 ;0,1=67,2=90.000000
L 3.3613384 3.5345751 3.3613384 3.5195799 15 P 0 ;0,1=67,2=90.000000
L 3.3713352 3.5195799 3.3413449 3.5195799 15 P 0 ;0,1=67,2=90.000000
L 3.3713352 3.5495702 3.3513417 3.5695637 15 P 0 ;0,1=67,2=90.000000
L 3.3713352 3.5695637 3.3713352 3.5495702 15 P 0 ;0,1=67,2=90.000000
L 3.3713352 3.5795605 3.3713352 3.5895573 15 P 0 ;0,1=67,2=90.000000
L 3.3713352 3.5845589 3.3413449 3.5845589 15 P 0 ;0,1=67,2=90.000000
L 3.3713352 3.5895573 3.3713352 3.5845589 15 P 0 ;0,1=67,2=90.000000
L 3.383622 3.9036221 3.5448425 3.9036221 6 P 0
L 3.383622 4.2685827 3.5448425 4.2685827 6 P 0
L 3.4048425 2.852063 3.4048425 2.872063 12 P 0
L 3.4048425 2.852063 3.4248425 2.852063 12 P 0
L 3.4048425 3.0293174 3.4048425 3.092063 12 P 0
L 3.4048425 3.092063 3.4587977 3.092063 12 P 0
L 3.4265355 3.6794882 3.4265355 3.7188582 6 P 0
L 3.4265355 3.6794882 3.444252 3.6794882 6 P 0
L 3.4468619 2.6945703 3.4468619 2.7245606 15 P 0 ;0,1=35,2=0.000000
L 3.4468619 2.7245606 3.4618571 2.7245606 15 P 0 ;0,1=35,2=0.000000
L 3.4568587 2.7045671 3.4668554 2.6945703 15 P 0 ;0,1=35,2=0.000000
L 3.4618571 2.7045671 3.4468619 2.7045671 15 P 0 ;0,1=35,2=0.000000
L 3.4618571 2.7245606 3.4668554 2.7195622 15 P 0 ;0,1=35,2=0.000000
L 3.4633449 3.7975751 3.4933352 3.7975751 15 P 0 ;0,1=96,2=90.000000
L 3.4633449 3.8125703 3.4633449 3.7975751 15 P 0 ;0,1=96,2=90.000000
L 3.4633449 3.8325638 3.4633449 3.8425606 15 P 0 ;0,1=96,2=90.000000
L 3.4633449 3.8425606 3.4683433 3.8475589 15 P 0 ;0,1=96,2=90.000000
L 3.4668554 2.7095655 3.4618571 2.7045671 15 P 0 ;0,1=35,2=0.000000
L 3.4668554 2.7195622 3.4668554 2.7095655 15 P 0 ;0,1=35,2=0.000000
L 3.4683433 3.8175686 3.4633449 3.8125703 15 P 0 ;0,1=96,2=90.000000
L 3.4683433 3.8275654 3.4633449 3.8325638 15 P 0 ;0,1=96,2=90.000000
L 3.4683433 3.8475589 3.4733417 3.8475589 15 P 0 ;0,1=96,2=90.000000
L 3.4733417 3.8275654 3.4683433 3.8275654 15 P 0 ;0,1=96,2=90.000000
L 3.4733417 3.8475589 3.47834 3.8425606 15 P 0 ;0,1=96,2=90.000000
L 3.4768522 2.7095655 3.4968457 2.7095655 15 P 0 ;0,1=35,2=0.000000
L 3.47834 3.8325638 3.4733417 3.8275654 15 P 0 ;0,1=96,2=90.000000
L 3.47834 3.8325638 3.47834 3.8425606 15 P 0 ;0,1=96,2=90.000000
L 3.47834 3.8425606 3.4833384 3.8475589 15 P 0 ;0,1=96,2=90.000000
L 3.4833384 3.8275654 3.47834 3.8325638 15 P 0 ;0,1=96,2=90.000000
L 3.4833384 3.8475589 3.4883368 3.8475589 15 P 0 ;0,1=96,2=90.000000
L 3.4883368 3.8175686 3.4683433 3.8175686 15 P 0 ;0,1=96,2=90.000000
L 3.4883368 3.8275654 3.4833384 3.8275654 15 P 0 ;0,1=96,2=90.000000
L 3.4883368 3.8475589 3.4933352 3.8425606 15 P 0 ;0,1=96,2=90.000000
L 3.4918474 2.6945703 3.4918474 2.7245606 15 P 0 ;0,1=35,2=0.000000
L 3.4918474 2.7245606 3.4768522 2.7095655 15 P 0 ;0,1=35,2=0.000000
L 3.4930025 1.282233 3.4930025 1.308493 9 P 0
L 3.4930025 1.282233 3.5166225 1.282233 9 P 0
L 3.4930025 2.098493 3.4930025 2.124753 9 P 0
L 3.4930025 2.124753 3.5166225 2.124753 9 P 0
L 3.4933352 3.7975751 3.4933352 3.8125703 15 P 0 ;0,1=96,2=90.000000
L 3.4933352 3.8125703 3.4883368 3.8175686 15 P 0 ;0,1=96,2=90.000000
L 3.4933352 3.8325638 3.4883368 3.8275654 15 P 0 ;0,1=96,2=90.000000
L 3.4933352 3.8425606 3.4933352 3.8325638 15 P 0 ;0,1=96,2=90.000000
L 3.4948619 0.7135687 3.4998603 0.7085703 15 P 0 ;0,1=108,2=0.000000
L 3.4948619 0.7335622 3.4948619 0.7135687 15 P 0 ;0,1=108,2=0.000000
L 3.4954331 3.6794882 3.5131496 3.6794882 6 P 0
L 3.4998603 0.7085703 3.5098571 0.7085703 15 P 0 ;0,1=108,2=0.000000
L 3.4998603 0.7385606 3.4948619 0.7335622 15 P 0 ;0,1=108,2=0.000000
L 3.5048425 2.777378 3.5048425 2.816748 10 P 0
L 3.5068425 2.6945703 3.526836 2.7145638 15 P 0 ;0,1=35,2=0.000000
L 3.5084749 3.438504 3.6283859 3.438504 12 P 0
L 3.5098571 0.7085703 3.5148554 0.7135687 15 P 0 ;0,1=108,2=0.000000
L 3.5098571 0.7385606 3.4998603 0.7385606 15 P 0 ;0,1=108,2=0.000000
L 3.5118409 2.7245606 3.5068425 2.7195622 15 P 0 ;0,1=35,2=0.000000
L 3.5131496 3.6794882 3.5131496 3.7188582 6 P 0
L 3.5148554 0.7335622 3.5098571 0.7385606 15 P 0 ;0,1=108,2=0.000000
L 3.5166225 1.260583 3.5166225 1.282233 9 P 0
L 3.5166225 1.260583 3.6268625 1.260583 9 P 0
L 3.5166225 2.124753 3.5166225 2.146403 9 P 0
L 3.5166225 2.146403 3.6268625 2.146403 9 P 0
L 3.5218377 2.7245606 3.5118409 2.7245606 15 P 0 ;0,1=35,2=0.000000
L 3.5248522 0.7135687 3.5298506 0.7085703 15 P 0 ;0,1=108,2=0.000000
L 3.5248522 0.7235655 3.5248522 0.7135687 15 P 0 ;0,1=108,2=0.000000
L 3.526836 2.6945703 3.5068425 2.6945703 15 P 0 ;0,1=35,2=0.000000
L 3.526836 2.7145638 3.526836 2.7195622 15 P 0 ;0,1=35,2=0.000000
L 3.526836 2.7195622 3.5218377 2.7245606 15 P 0 ;0,1=35,2=0.000000
L 3.5298506 0.7085703 3.5398474 0.7085703 15 P 0 ;0,1=108,2=0.000000
L 3.534849 0.7335622 3.5248522 0.7235655 15 P 0 ;0,1=108,2=0.000000
L 3.5398474 0.7085703 3.5448457 0.7135687 15 P 0 ;0,1=108,2=0.000000
L 3.5398474 0.7235655 3.5248522 0.7235655 15 P 0 ;0,1=108,2=0.000000
L 3.5434325 2.184543 3.563426 2.184543 3 P 0 ;0,1=12,2=0.000000
L 3.5448425 2.852063 3.5648425 2.852063 12 P 0
L 3.5448425 3.092063 3.5648425 3.092063 12 P 0
L 3.5448425 3.9036221 3.5448425 4.2685827 6 P 0
L 3.5448457 0.7135687 3.5448457 0.7185671 15 P 0 ;0,1=108,2=0.000000
L 3.5448457 0.7185671 3.5398474 0.7235655 15 P 0 ;0,1=108,2=0.000000
L 3.5448457 0.7385606 3.534849 0.7335622 15 P 0 ;0,1=108,2=0.000000
L 3.5534293 2.184543 3.5534293 2.2445236 3 P 0 ;0,1=12,2=0.000000
L 3.5534293 2.2445236 3.5434325 2.2345268 3 P 0 ;0,1=12,2=0.000000
L 3.5548425 0.7085703 3.574836 0.7285638 15 P 0 ;0,1=108,2=0.000000
L 3.5598409 0.7385606 3.5548425 0.7335622 15 P 0 ;0,1=108,2=0.000000
L 3.563426 2.184543 3.5534293 2.184543 3 P 0 ;0,1=12,2=0.000000
L 3.5648425 2.852063 3.5648425 2.872063 12 P 0
L 3.5648425 3.072063 3.5648425 3.092063 12 P 0
L 3.5698377 0.7385606 3.5598409 0.7385606 15 P 0 ;0,1=108,2=0.000000
L 3.574836 0.7085703 3.5548425 0.7085703 15 P 0 ;0,1=108,2=0.000000
L 3.574836 0.7285638 3.574836 0.7335622 15 P 0 ;0,1=108,2=0.000000
L 3.574836 0.7335622 3.5698377 0.7385606 15 P 0 ;0,1=108,2=0.000000
L 3.5783449 3.5718312 3.6083352 3.5718312 15 P 0 ;0,1=94,2=90.000000
L 3.5783449 3.5868264 3.5783449 3.5718312 15 P 0 ;0,1=94,2=90.000000
L 3.5783449 3.6068199 3.5833433 3.6018215 15 P 0 ;0,1=94,2=90.000000
L 3.5783449 3.6318118 3.5783449 3.6418086 15 P 0 ;0,1=94,2=90.000000
L 3.5783449 3.6418086 3.5833433 3.6468069 15 P 0 ;0,1=94,2=90.000000
L 3.5833433 3.5918247 3.5783449 3.5868264 15 P 0 ;0,1=94,2=90.000000
L 3.5833433 3.6268134 3.5783449 3.6318118 15 P 0 ;0,1=94,2=90.000000
L 3.5833433 3.6468069 3.6033368 3.6468069 15 P 0 ;0,1=94,2=90.000000
L 3.5886107 2.8645687 3.5936091 2.8595703 15 P 0 ;0,1=41,2=0.000000
L 3.5886107 2.8895606 3.5886107 2.8645687 15 P 0 ;0,1=41,2=0.000000
L 3.5890158 3.1629134 3.6283859 3.1629134 12 P 0
L 3.5903449 3.9615751 3.6203352 3.9615751 15 P 0 ;0,1=95,2=90.000000
L 3.5903449 3.9765703 3.5903449 3.9615751 15 P 0 ;0,1=95,2=90.000000
L 3.5903449 3.9965638 3.5953433 3.9915654 15 P 0 ;0,1=95,2=90.000000
L 3.5903449 4.0065606 3.5903449 3.9965638 15 P 0 ;0,1=95,2=90.000000
L 3.5936091 2.8595703 3.6036059 2.8595703 15 P 0 ;0,1=41,2=0.000000
L 3.5953433 3.9815686 3.5903449 3.9765703 15 P 0 ;0,1=95,2=90.000000
L 3.5953433 3.9915654 3.6003417 3.9915654 15 P 0 ;0,1=95,2=90.000000
L 3.5953433 4.0115589 3.5903449 4.0065606 15 P 0 ;0,1=95,2=90.000000
L 3.6003417 3.9915654 3.60534 3.9965638 15 P 0 ;0,1=95,2=90.000000
L 3.6033368 3.5918247 3.5833433 3.5918247 15 P 0 ;0,1=94,2=90.000000
L 3.6033368 3.6268134 3.5833433 3.6268134 15 P 0 ;0,1=94,2=90.000000
L 3.6033368 3.6468069 3.6083352 3.6418086 15 P 0 ;0,1=94,2=90.000000
L 3.6036059 2.8595703 3.6086042 2.8645687 15 P 0 ;0,1=41,2=0.000000
L 3.60534 3.9965638 3.60534 4.0115589 15 P 0 ;0,1=95,2=90.000000
L 3.6083352 3.5718312 3.6083352 3.5868264 15 P 0 ;0,1=94,2=90.000000
L 3.6083352 3.5868264 3.6033368 3.5918247 15 P 0 ;0,1=94,2=90.000000
L 3.6083352 3.6018215 3.6083352 3.6118183 15 P 0 ;0,1=94,2=90.000000
L 3.6083352 3.6068199 3.5783449 3.6068199 15 P 0 ;0,1=94,2=90.000000
L 3.6083352 3.6118183 3.6083352 3.6068199 15 P 0 ;0,1=94,2=90.000000
L 3.6083352 3.6318118 3.6033368 3.6268134 15 P 0 ;0,1=94,2=90.000000
L 3.6083352 3.6418086 3.6083352 3.6318118 15 P 0 ;0,1=94,2=90.000000
L 3.6086042 2.8645687 3.6086042 2.8895606 15 P 0 ;0,1=41,2=0.000000
L 3.6153368 3.9815686 3.5953433 3.9815686 15 P 0 ;0,1=95,2=90.000000
L 3.6153368 3.9915654 3.6203352 3.9965638 15 P 0 ;0,1=95,2=90.000000
L 3.6153368 4.0115589 3.5953433 4.0115589 15 P 0 ;0,1=95,2=90.000000
L 3.618601 2.8595703 3.6285978 2.8595703 15 P 0 ;0,1=41,2=0.000000
L 3.6203352 3.9615751 3.6203352 3.9765703 15 P 0 ;0,1=95,2=90.000000
L 3.6203352 3.9765703 3.6153368 3.9815686 15 P 0 ;0,1=95,2=90.000000
L 3.6203352 3.9965638 3.6203352 4.0065606 15 P 0 ;0,1=95,2=90.000000
L 3.6203352 4.0065606 3.6153368 4.0115589 15 P 0 ;0,1=95,2=90.000000
L 3.6235994 2.8595703 3.6235994 2.8895606 15 P 0 ;0,1=41,2=0.000000
L 3.6235994 2.8895606 3.618601 2.8845622 15 P 0 ;0,1=41,2=0.000000
L 3.6268625 1.260583 3.6268625 1.282233 9 P 0
L 3.6268625 1.282233 3.6504825 1.282233 9 P 0
L 3.6268625 2.124753 3.6268625 2.146403 9 P 0
L 3.6268625 2.124753 3.6504825 2.124753 9 P 0
L 3.6283859 3.1629134 3.6283859 3.2022835 12 P 0
L 3.6283859 3.3267535 3.6283859 3.438504 12 P 0
L 3.6285978 2.8595703 3.6235994 2.8595703 15 P 0 ;0,1=41,2=0.000000
L 3.6318619 3.8905703 3.6318619 3.9205606 15 P 0 ;0,1=63,2=0.000000
L 3.6318619 3.9205606 3.6468571 3.9205606 15 P 0 ;0,1=63,2=0.000000
L 3.6418587 3.9005671 3.6518554 3.8905703 15 P 0 ;0,1=63,2=0.000000
L 3.6435929 2.8845622 3.6485913 2.8895606 15 P 0 ;0,1=41,2=0.000000
L 3.6468571 3.9005671 3.6318619 3.9005671 15 P 0 ;0,1=63,2=0.000000
L 3.6468571 3.9205606 3.6518554 3.9155622 15 P 0 ;0,1=63,2=0.000000
L 3.6485913 2.8595703 3.6435929 2.8645687 15 P 0 ;0,1=41,2=0.000000
L 3.6485913 2.8895606 3.6585881 2.8895606 15 P 0 ;0,1=41,2=0.000000
L 3.6504825 1.282233 3.6504825 1.308493 9 P 0
L 3.6504825 2.098493 3.6504825 2.124753 9 P 0
L 3.6518554 3.9055655 3.6468571 3.9005671 15 P 0 ;0,1=63,2=0.000000
L 3.6518554 3.9155622 3.6518554 3.9055655 15 P 0 ;0,1=63,2=0.000000
L 3.6535897 2.8745655 3.6585881 2.8745655 15 P 0 ;0,1=41,2=0.000000
L 3.6558425 3.123063 3.6558425 3.183063 10 P 0
L 3.6585881 2.8595703 3.6485913 2.8595703 15 P 0 ;0,1=41,2=0.000000
L 3.6585881 2.8745655 3.6535897 2.8745655 15 P 0 ;0,1=41,2=0.000000
L 3.6585881 2.8745655 3.6635864 2.8695671 15 P 0 ;0,1=41,2=0.000000
L 3.6585881 2.8895606 3.6635864 2.8845622 15 P 0 ;0,1=41,2=0.000000
L 3.6608425 3.273063 3.6608425 3.323063 10 P 0
L 3.6618522 3.8905703 3.6818457 3.9105638 15 P 0 ;0,1=63,2=0.000000
L 3.6635864 2.8645687 3.6585881 2.8595703 15 P 0 ;0,1=41,2=0.000000
L 3.6635864 2.8695671 3.6635864 2.8645687 15 P 0 ;0,1=41,2=0.000000
L 3.6635864 2.8795638 3.6585881 2.8745655 15 P 0 ;0,1=41,2=0.000000
L 3.6635864 2.8845622 3.6635864 2.8795638 15 P 0 ;0,1=41,2=0.000000
L 3.6648425 0.688063 3.7248425 0.688063 10 P 0
L 3.6648425 0.764063 3.7248425 0.764063 10 P 0
L 3.6658425 3.3950614 3.6708409 3.390063 15 P 0 ;0,1=104,2=0.000000
L 3.6658425 3.4150549 3.6658425 3.3950614 15 P 0 ;0,1=104,2=0.000000
L 3.6668506 3.9205606 3.6618522 3.9155622 15 P 0 ;0,1=63,2=0.000000
L 3.6708409 3.390063 3.6808377 3.390063 15 P 0 ;0,1=104,2=0.000000
L 3.6708409 3.4200533 3.6658425 3.4150549 15 P 0 ;0,1=104,2=0.000000
L 3.6753449 3.6040824 3.6753449 3.6190776 15 P 0 ;0,1=62,2=90.000000
L 3.6753449 3.6190776 3.6803433 3.6240759 15 P 0 ;0,1=62,2=90.000000
L 3.6753449 3.6390711 3.6803433 3.6340727 15 P 0 ;0,1=62,2=90.000000
L 3.6753449 3.6490679 3.6753449 3.6390711 15 P 0 ;0,1=62,2=90.000000
L 3.6753449 3.6840565 3.6803433 3.6740598 15 P 0 ;0,1=62,2=90.000000
L 3.6768474 3.9205606 3.6668506 3.9205606 15 P 0 ;0,1=63,2=0.000000
L 3.6803433 3.6240759 3.69034 3.6240759 15 P 0 ;0,1=62,2=90.000000
L 3.6803433 3.6540662 3.6753449 3.6490679 15 P 0 ;0,1=62,2=90.000000
L 3.6803433 3.6740598 3.69034 3.664063 15 P 0 ;0,1=62,2=90.000000
L 3.6808377 3.390063 3.685836 3.3950614 15 P 0 ;0,1=104,2=0.000000
L 3.6808377 3.4200533 3.6708409 3.4200533 15 P 0 ;0,1=104,2=0.000000
L 3.6818457 3.8905703 3.6618522 3.8905703 15 P 0 ;0,1=63,2=0.000000
L 3.6818457 3.9105638 3.6818457 3.9155622 15 P 0 ;0,1=63,2=0.000000
L 3.6818457 3.9155622 3.6768474 3.9205606 15 P 0 ;0,1=63,2=0.000000
L 3.6844488 4.0987008 3.6844488 4.1737008 10 P 0
L 3.6853417 3.6540662 3.6803433 3.6540662 15 P 0 ;0,1=62,2=90.000000
L 3.685836 3.4150549 3.6808377 3.4200533 15 P 0 ;0,1=104,2=0.000000
L 3.69034 3.6240759 3.6953384 3.6190776 15 P 0 ;0,1=62,2=90.000000
L 3.69034 3.664063 3.7003368 3.664063 15 P 0 ;0,1=62,2=90.000000
L 3.69034 3.6790582 3.69034 3.664063 15 P 0 ;0,1=62,2=90.000000
L 3.6918425 3.9055655 3.7018393 3.9105638 15 P 0 ;0,1=63,2=0.000000
L 3.6918425 3.9205606 3.6918425 3.9055655 15 P 0 ;0,1=63,2=0.000000
L 3.6953384 3.6140792 3.7053352 3.6240759 15 P 0 ;0,1=62,2=90.000000
L 3.6953384 3.6190776 3.6953384 3.6040824 15 P 0 ;0,1=62,2=90.000000
L 3.6953384 3.6840565 3.69034 3.6790582 15 P 0 ;0,1=62,2=90.000000
L 3.6958328 3.3950614 3.7008312 3.390063 15 P 0 ;0,1=104,2=0.000000
L 3.6958328 3.4050582 3.6958328 3.3950614 15 P 0 ;0,1=104,2=0.000000
L 3.6968409 3.8905703 3.6918425 3.8955687 15 P 0 ;0,1=63,2=0.000000
L 3.7003368 3.664063 3.7053352 3.6690614 15 P 0 ;0,1=62,2=90.000000
L 3.7003368 3.6840565 3.6953384 3.6840565 15 P 0 ;0,1=62,2=90.000000
L 3.7008312 3.390063 3.710828 3.390063 15 P 0 ;0,1=104,2=0.000000
L 3.7018393 3.9105638 3.7068377 3.9105638 15 P 0 ;0,1=63,2=0.000000
L 3.7053352 3.6040824 3.6753449 3.6040824 15 P 0 ;0,1=62,2=90.000000
L 3.7053352 3.6340727 3.6853417 3.6540662 15 P 0 ;0,1=62,2=90.000000
L 3.7053352 3.6540662 3.7053352 3.6340727 15 P 0 ;0,1=62,2=90.000000
L 3.7053352 3.6690614 3.7053352 3.6790582 15 P 0 ;0,1=62,2=90.000000
L 3.7053352 3.6790582 3.7003368 3.6840565 15 P 0 ;0,1=62,2=90.000000
L 3.7058296 3.4150549 3.6958328 3.4050582 15 P 0 ;0,1=104,2=0.000000
L 3.7068377 3.8905703 3.6968409 3.8905703 15 P 0 ;0,1=63,2=0.000000
L 3.7068377 3.9105638 3.711836 3.9055655 15 P 0 ;0,1=63,2=0.000000
L 3.710828 3.390063 3.7158263 3.3950614 15 P 0 ;0,1=104,2=0.000000
L 3.710828 3.4050582 3.6958328 3.4050582 15 P 0 ;0,1=104,2=0.000000
L 3.711836 3.8955687 3.7068377 3.8905703 15 P 0 ;0,1=63,2=0.000000
L 3.711836 3.9055655 3.711836 3.8955687 15 P 0 ;0,1=63,2=0.000000
L 3.711836 3.9205606 3.6918425 3.9205606 15 P 0 ;0,1=63,2=0.000000
L 3.7158263 3.3950614 3.7158263 3.4000598 15 P 0 ;0,1=104,2=0.000000
L 3.7158263 3.4000598 3.710828 3.4050582 15 P 0 ;0,1=104,2=0.000000
L 3.7158263 3.4200533 3.7058296 3.4150549 15 P 0 ;0,1=104,2=0.000000
L 3.7161925 0.815533 3.7161925 2.587193 8 P 0
L 3.7168425 3.273063 3.7168425 3.323063 10 P 0
L 3.7258231 3.3950614 3.7258231 3.390063 15 P 0 ;0,1=104,2=0.000000
L 3.7258231 3.4200533 3.7458166 3.4200533 15 P 0 ;0,1=104,2=0.000000
L 3.7318425 3.123063 3.7318425 3.183063 10 P 0
L 3.7458166 3.4150549 3.7258231 3.3950614 15 P 0 ;0,1=104,2=0.000000
L 3.7458166 3.4200533 3.7458166 3.4150549 15 P 0 ;0,1=104,2=0.000000
L 3.7528619 3.1095687 3.7578603 3.1045703 15 P 0 ;0,1=106,2=0.000000
L 3.7528619 3.1295622 3.7528619 3.1095687 15 P 0 ;0,1=106,2=0.000000
L 3.7578603 3.1045703 3.7678571 3.1045703 15 P 0 ;0,1=106,2=0.000000
L 3.7578603 3.1345606 3.7528619 3.1295622 15 P 0 ;0,1=106,2=0.000000
L 3.7608619 0.6185687 3.7658603 0.6135703 15 P 0 ;0,1=107,2=0.000000
L 3.7608619 0.6385622 3.7608619 0.6185687 15 P 0 ;0,1=107,2=0.000000
L 3.7658603 0.6135703 3.7758571 0.6135703 15 P 0 ;0,1=107,2=0.000000
L 3.7658603 0.6435606 3.7608619 0.6385622 15 P 0 ;0,1=107,2=0.000000
L 3.7678571 3.1045703 3.7728554 3.1095687 15 P 0 ;0,1=106,2=0.000000
L 3.7678571 3.1345606 3.7578603 3.1345606 15 P 0 ;0,1=106,2=0.000000
L 3.7678619 2.7985687 3.7728603 2.7935703 15 P 0 ;0,1=20,2=0.000000
L 3.7678619 2.8185622 3.7678619 2.7985687 15 P 0 ;0,1=20,2=0.000000
L 3.7728554 3.1295622 3.7678571 3.1345606 15 P 0 ;0,1=106,2=0.000000
L 3.7728603 2.7935703 3.7828571 2.7935703 15 P 0 ;0,1=20,2=0.000000
L 3.7728603 2.8235606 3.7678619 2.8185622 15 P 0 ;0,1=20,2=0.000000
L 3.7758571 0.6135703 3.7808554 0.6185687 15 P 0 ;0,1=107,2=0.000000
L 3.7758571 0.6435606 3.7658603 0.6435606 15 P 0 ;0,1=107,2=0.000000
L 3.7789398 0.6898312 3.7789398 2.6898312 3 P 0
L 3.7789398 0.6898312 5.7789398 0.6898312 3 P 0
L 3.7789398 2.6898312 5.7789398 2.6898312 3 P 0
L 3.7808554 0.6385622 3.7758571 0.6435606 15 P 0 ;0,1=107,2=0.000000
L 3.7828522 3.1095687 3.7878506 3.1045703 15 P 0 ;0,1=106,2=0.000000
L 3.7828522 3.1195655 3.7828522 3.1095687 15 P 0 ;0,1=106,2=0.000000
L 3.7828571 2.7935703 3.7878554 2.7985687 15 P 0 ;0,1=20,2=0.000000
L 3.7828571 2.8235606 3.7728603 2.8235606 15 P 0 ;0,1=20,2=0.000000
L 3.7868619 3.2905687 3.7918603 3.2855703 15 P 0 ;0,1=105,2=0.000000
L 3.7868619 3.3105622 3.7868619 3.2905687 15 P 0 ;0,1=105,2=0.000000
L 3.7878506 3.1045703 3.7978474 3.1045703 15 P 0 ;0,1=106,2=0.000000
L 3.7878554 2.8185622 3.7828571 2.8235606 15 P 0 ;0,1=20,2=0.000000
L 3.7908522 0.6185687 3.7958506 0.6135703 15 P 0 ;0,1=107,2=0.000000
L 3.7908522 0.6285655 3.7908522 0.6185687 15 P 0 ;0,1=107,2=0.000000
L 3.7918603 3.2855703 3.8018571 3.2855703 15 P 0 ;0,1=105,2=0.000000
L 3.7918603 3.3155606 3.7868619 3.3105622 15 P 0 ;0,1=105,2=0.000000
L 3.792849 3.1295622 3.7828522 3.1195655 15 P 0 ;0,1=106,2=0.000000
L 3.7958506 0.6135703 3.8058474 0.6135703 15 P 0 ;0,1=107,2=0.000000
L 3.7978474 3.1045703 3.8028457 3.1095687 15 P 0 ;0,1=106,2=0.000000
L 3.7978474 3.1195655 3.7828522 3.1195655 15 P 0 ;0,1=106,2=0.000000
L 3.7978522 2.7985687 3.7978522 2.7935703 15 P 0 ;0,1=20,2=0.000000
L 3.7978522 2.8235606 3.8178457 2.8235606 15 P 0 ;0,1=20,2=0.000000
L 3.800849 0.6385622 3.7908522 0.6285655 15 P 0 ;0,1=107,2=0.000000
L 3.8018571 3.2855703 3.8068554 3.2905687 15 P 0 ;0,1=105,2=0.000000
L 3.8018571 3.3155606 3.7918603 3.3155606 15 P 0 ;0,1=105,2=0.000000
L 3.8028457 3.1095687 3.8028457 3.1145671 15 P 0 ;0,1=106,2=0.000000
L 3.8028457 3.1145671 3.7978474 3.1195655 15 P 0 ;0,1=106,2=0.000000
L 3.8028457 3.1345606 3.792849 3.1295622 15 P 0 ;0,1=106,2=0.000000
L 3.8058474 0.6135703 3.8108457 0.6185687 15 P 0 ;0,1=107,2=0.000000
L 3.8058474 0.6285655 3.7908522 0.6285655 15 P 0 ;0,1=107,2=0.000000
L 3.8068554 3.3105622 3.8018571 3.3155606 15 P 0 ;0,1=105,2=0.000000
L 3.8108457 0.6185687 3.8108457 0.6235671 15 P 0 ;0,1=107,2=0.000000
L 3.8108457 0.6235671 3.8058474 0.6285655 15 P 0 ;0,1=107,2=0.000000
L 3.8108457 0.6435606 3.800849 0.6385622 15 P 0 ;0,1=107,2=0.000000
L 3.8128425 3.1195655 3.8228393 3.1245638 15 P 0 ;0,1=106,2=0.000000
L 3.8128425 3.1345606 3.8128425 3.1195655 15 P 0 ;0,1=106,2=0.000000
L 3.8168503 3.6726378 3.8168503 3.8694882 6 P 0
L 3.8168503 3.6726378 3.9428346 3.6726378 6 P 0
L 3.8168503 3.8694882 3.9428346 3.8694882 6 P 0
L 3.8168522 3.2905687 3.8218506 3.2855703 15 P 0 ;0,1=105,2=0.000000
L 3.8168522 3.3005655 3.8168522 3.2905687 15 P 0 ;0,1=105,2=0.000000
L 3.8178409 3.1045703 3.8128425 3.1095687 15 P 0 ;0,1=106,2=0.000000
L 3.8178457 2.8185622 3.7978522 2.7985687 15 P 0 ;0,1=20,2=0.000000
L 3.8178457 2.8235606 3.8178457 2.8185622 15 P 0 ;0,1=20,2=0.000000
L 3.8208425 0.6385622 3.8258409 0.6435606 15 P 0 ;0,1=107,2=0.000000
L 3.8218506 3.2855703 3.8318474 3.2855703 15 P 0 ;0,1=105,2=0.000000
L 3.8228393 3.1245638 3.8278377 3.1245638 15 P 0 ;0,1=106,2=0.000000
L 3.8258409 0.6135703 3.8208425 0.6185687 15 P 0 ;0,1=107,2=0.000000
L 3.8258409 0.6435606 3.8358377 0.6435606 15 P 0 ;0,1=107,2=0.000000
L 3.826849 3.3105622 3.8168522 3.3005655 15 P 0 ;0,1=105,2=0.000000
L 3.8278377 3.1045703 3.8178409 3.1045703 15 P 0 ;0,1=106,2=0.000000
L 3.8278377 3.1245638 3.832836 3.1195655 15 P 0 ;0,1=106,2=0.000000
L 3.8278425 2.8085655 3.847836 2.8085655 15 P 0 ;0,1=20,2=0.000000
L 3.8308393 0.6285655 3.8358377 0.6285655 15 P 0 ;0,1=107,2=0.000000
L 3.8318474 3.2855703 3.8368457 3.2905687 15 P 0 ;0,1=105,2=0.000000
L 3.8318474 3.3005655 3.8168522 3.3005655 15 P 0 ;0,1=105,2=0.000000
L 3.832836 3.1095687 3.8278377 3.1045703 15 P 0 ;0,1=106,2=0.000000
L 3.832836 3.1195655 3.832836 3.1095687 15 P 0 ;0,1=106,2=0.000000
L 3.832836 3.1345606 3.8128425 3.1345606 15 P 0 ;0,1=106,2=0.000000
L 3.8358377 0.6135703 3.8258409 0.6135703 15 P 0 ;0,1=107,2=0.000000
L 3.8358377 0.6285655 3.8308393 0.6285655 15 P 0 ;0,1=107,2=0.000000
L 3.8358377 0.6285655 3.840836 0.6235671 15 P 0 ;0,1=107,2=0.000000
L 3.8358377 0.6435606 3.840836 0.6385622 15 P 0 ;0,1=107,2=0.000000
L 3.8368457 3.2905687 3.8368457 3.2955671 15 P 0 ;0,1=105,2=0.000000
L 3.8368457 3.2955671 3.8318474 3.3005655 15 P 0 ;0,1=105,2=0.000000
L 3.8368457 3.3155606 3.826849 3.3105622 15 P 0 ;0,1=105,2=0.000000
L 3.840836 0.6185687 3.8358377 0.6135703 15 P 0 ;0,1=107,2=0.000000
L 3.840836 0.6235671 3.840836 0.6185687 15 P 0 ;0,1=107,2=0.000000
L 3.840836 0.6335638 3.8358377 0.6285655 15 P 0 ;0,1=107,2=0.000000
L 3.840836 0.6385622 3.840836 0.6335638 15 P 0 ;0,1=107,2=0.000000
L 3.8413546 3.6085687 3.846353 3.6035703 15 P 0 ;0,1=46,2=0.000000
L 3.8413546 3.6335606 3.8413546 3.6085687 15 P 0 ;0,1=46,2=0.000000
L 3.8428377 2.7935703 3.8428377 2.8235606 15 P 0 ;0,1=20,2=0.000000
L 3.8428377 2.8235606 3.8278425 2.8085655 15 P 0 ;0,1=20,2=0.000000
L 3.846353 3.6035703 3.8563498 3.6035703 15 P 0 ;0,1=46,2=0.000000
L 3.8468425 3.2905687 3.8518409 3.2855703 15 P 0 ;0,1=105,2=0.000000
L 3.8468425 3.3005655 3.8468425 3.2905687 15 P 0 ;0,1=105,2=0.000000
L 3.8518409 3.2855703 3.8618377 3.2855703 15 P 0 ;0,1=105,2=0.000000
L 3.8563498 3.6035703 3.8613481 3.6085687 15 P 0 ;0,1=46,2=0.000000
L 3.8568393 3.3105622 3.8468425 3.3005655 15 P 0 ;0,1=105,2=0.000000
L 3.8613481 3.6085687 3.8613481 3.6335606 15 P 0 ;0,1=46,2=0.000000
L 3.8618377 3.2855703 3.866836 3.2905687 15 P 0 ;0,1=105,2=0.000000
L 3.8618377 3.3005655 3.8468425 3.3005655 15 P 0 ;0,1=105,2=0.000000
L 3.866836 3.2905687 3.866836 3.2955671 15 P 0 ;0,1=105,2=0.000000
L 3.866836 3.2955671 3.8618377 3.3005655 15 P 0 ;0,1=105,2=0.000000
L 3.866836 3.3155606 3.8568393 3.3105622 15 P 0 ;0,1=105,2=0.000000
L 3.8713449 3.6085687 3.8763433 3.6035703 15 P 0 ;0,1=46,2=0.000000
L 3.8713449 3.6185655 3.8713449 3.6085687 15 P 0 ;0,1=46,2=0.000000
L 3.8763433 3.6035703 3.8863401 3.6035703 15 P 0 ;0,1=46,2=0.000000
L 3.8813417 3.6285622 3.8713449 3.6185655 15 P 0 ;0,1=46,2=0.000000
L 3.8863401 3.6035703 3.8913384 3.6085687 15 P 0 ;0,1=46,2=0.000000
L 3.8863401 3.6185655 3.8713449 3.6185655 15 P 0 ;0,1=46,2=0.000000
L 3.8913384 3.6085687 3.8913384 3.6135671 15 P 0 ;0,1=46,2=0.000000
L 3.8913384 3.6135671 3.8863401 3.6185655 15 P 0 ;0,1=46,2=0.000000
L 3.8913384 3.6335606 3.8813417 3.6285622 15 P 0 ;0,1=46,2=0.000000
L 3.9218425 2.786063 3.9218425 2.846063 10 P 0
L 3.9428346 3.6726378 3.9428346 3.8694882 6 P 0
L 3.9522931 3.1939748 3.9572915 3.1889764 15 P 0 ;0,1=22,2=90.000000
L 3.9522931 3.2039716 3.9522931 3.1939748 15 P 0 ;0,1=22,2=90.000000
L 3.9522931 3.2189667 3.9522931 3.2389602 15 P 0 ;0,1=22,2=90.000000
L 3.9522931 3.2389602 3.9572915 3.2389602 15 P 0 ;0,1=22,2=90.000000
L 3.9522931 3.2689505 3.9572915 3.2589538 15 P 0 ;0,1=22,2=90.000000
L 3.9572915 3.1889764 3.977285 3.1889764 15 P 0 ;0,1=22,2=90.000000
L 3.9572915 3.2089699 3.9522931 3.2039716 15 P 0 ;0,1=22,2=90.000000
L 3.9572915 3.2389602 3.977285 3.2189667 15 P 0 ;0,1=22,2=90.000000
L 3.9572915 3.2589538 3.9672882 3.248957 15 P 0 ;0,1=22,2=90.000000
L 3.9644553 3.9737008 3.974452 3.9737008 3 P 0 ;0,1=12,2=180.000000
L 3.9672882 3.248957 3.977285 3.248957 15 P 0 ;0,1=22,2=90.000000
L 3.9672882 3.2639522 3.9672882 3.248957 15 P 0 ;0,1=22,2=90.000000
L 3.9722866 3.2689505 3.9672882 3.2639522 15 P 0 ;0,1=22,2=90.000000
L 3.974452 3.9137202 3.9844488 3.923717 3 P 0 ;0,1=12,2=180.000000
L 3.974452 3.9737008 3.974452 3.9137202 3 P 0 ;0,1=12,2=180.000000
L 3.977285 3.1889764 3.9822834 3.1939748 15 P 0 ;0,1=22,2=90.000000
L 3.977285 3.2189667 3.9822834 3.2189667 15 P 0 ;0,1=22,2=90.000000
L 3.977285 3.248957 3.9822834 3.2539554 15 P 0 ;0,1=22,2=90.000000
L 3.977285 3.2689505 3.9722866 3.2689505 15 P 0 ;0,1=22,2=90.000000
L 3.9818619 2.9165687 3.9868603 2.9115703 15 P 0 ;0,1=21,2=0.000000
L 3.9818619 2.9365622 3.9818619 2.9165687 15 P 0 ;0,1=21,2=0.000000
L 3.9822834 3.1939748 3.9822834 3.2039716 15 P 0 ;0,1=22,2=90.000000
L 3.9822834 3.2039716 3.977285 3.2089699 15 P 0 ;0,1=22,2=90.000000
L 3.9822834 3.2539554 3.9822834 3.2639522 15 P 0 ;0,1=22,2=90.000000
L 3.9822834 3.2639522 3.977285 3.2689505 15 P 0 ;0,1=22,2=90.000000
L 3.9844488 3.9737008 3.9644553 3.9737008 3 P 0 ;0,1=12,2=180.000000
L 3.9868603 2.9115703 3.9968571 2.9115703 15 P 0 ;0,1=21,2=0.000000
L 3.9868603 2.9415606 3.9818619 2.9365622 15 P 0 ;0,1=21,2=0.000000
L 3.9968571 2.9115703 4.0018554 2.9165687 15 P 0 ;0,1=21,2=0.000000
L 3.9968571 2.9415606 3.9868603 2.9415606 15 P 0 ;0,1=21,2=0.000000
L 3.9978425 2.786063 3.9978425 2.846063 10 P 0
L 4.0018554 2.9365622 3.9968571 2.9415606 15 P 0 ;0,1=21,2=0.000000
L 4.006427 3.1939748 4.0114254 3.1889764 15 P 0 ;0,1=23,2=90.000000
L 4.006427 3.2039716 4.006427 3.1939748 15 P 0 ;0,1=23,2=90.000000
L 4.006427 3.2189667 4.006427 3.2389602 15 P 0 ;0,1=23,2=90.000000
L 4.006427 3.2389602 4.0114254 3.2389602 15 P 0 ;0,1=23,2=90.000000
L 4.006427 3.248957 4.006427 3.2689505 15 P 0 ;0,1=23,2=90.000000
L 4.006427 3.2689505 4.0114254 3.2689505 15 P 0 ;0,1=23,2=90.000000
L 4.0114254 3.1889764 4.0314189 3.1889764 15 P 0 ;0,1=23,2=90.000000
L 4.0114254 3.2089699 4.006427 3.2039716 15 P 0 ;0,1=23,2=90.000000
L 4.0114254 3.2389602 4.0314189 3.2189667 15 P 0 ;0,1=23,2=90.000000
L 4.0114254 3.2689505 4.0314189 3.248957 15 P 0 ;0,1=23,2=90.000000
L 4.0118425 3.036063 4.0118425 3.086063 10 P 0
L 4.0118522 2.9165687 4.0118522 2.9115703 15 P 0 ;0,1=21,2=0.000000
L 4.0118522 2.9415606 4.0318457 2.9415606 15 P 0 ;0,1=21,2=0.000000
L 4.0268425 2.786063 4.0268425 2.846063 10 P 0
L 4.0314189 3.1889764 4.0364173 3.1939748 15 P 0 ;0,1=23,2=90.000000
L 4.0314189 3.2189667 4.0364173 3.2189667 15 P 0 ;0,1=23,2=90.000000
L 4.0314189 3.248957 4.0364173 3.248957 15 P 0 ;0,1=23,2=90.000000
L 4.0318457 2.9365622 4.0118522 2.9165687 15 P 0 ;0,1=21,2=0.000000
L 4.0318457 2.9415606 4.0318457 2.9365622 15 P 0 ;0,1=21,2=0.000000
L 4.0364173 3.1939748 4.0364173 3.2039716 15 P 0 ;0,1=23,2=90.000000
L 4.0364173 3.2039716 4.0314189 3.2089699 15 P 0 ;0,1=23,2=90.000000
L 4.0418425 2.9265655 4.0518393 2.9315638 15 P 0 ;0,1=21,2=0.000000
L 4.0418425 2.9415606 4.0418425 2.9265655 15 P 0 ;0,1=21,2=0.000000
L 4.0468409 2.9115703 4.0418425 2.9165687 15 P 0 ;0,1=21,2=0.000000
L 4.0518393 2.9315638 4.0568377 2.9315638 15 P 0 ;0,1=21,2=0.000000
L 4.0568377 2.9115703 4.0468409 2.9115703 15 P 0 ;0,1=21,2=0.000000
L 4.0568377 2.9315638 4.061836 2.9265655 15 P 0 ;0,1=21,2=0.000000
L 4.0594488 4.0987008 4.0594488 4.1737008 10 P 0
L 4.061836 2.9165687 4.0568377 2.9115703 15 P 0 ;0,1=21,2=0.000000
L 4.061836 2.9265655 4.061836 2.9165687 15 P 0 ;0,1=21,2=0.000000
L 4.061836 2.9415606 4.0418425 2.9415606 15 P 0 ;0,1=21,2=0.000000
L 4.0644979 3.1929905 4.0694963 3.1879921 15 P 0 ;0,1=24,2=90.000000
L 4.0644979 3.2029873 4.0644979 3.1929905 15 P 0 ;0,1=24,2=90.000000
L 4.0644979 3.2179824 4.0644979 3.2379759 15 P 0 ;0,1=24,2=90.000000
L 4.0644979 3.2379759 4.0694963 3.2379759 15 P 0 ;0,1=24,2=90.000000
L 4.0644979 3.2529711 4.0644979 3.2629679 15 P 0 ;0,1=24,2=90.000000
L 4.0644979 3.2629679 4.0694963 3.2679662 15 P 0 ;0,1=24,2=90.000000
L 4.0668425 3.776063 4.0668425 3.836063 10 P 0
L 4.0678425 3.036063 4.0678425 3.086063 10 P 0
L 4.0694963 3.1879921 4.0894898 3.1879921 15 P 0 ;0,1=24,2=90.000000
L 4.0694963 3.2079856 4.0644979 3.2029873 15 P 0 ;0,1=24,2=90.000000
L 4.0694963 3.2379759 4.0894898 3.2179824 15 P 0 ;0,1=24,2=90.000000
L 4.0694963 3.2479727 4.0644979 3.2529711 15 P 0 ;0,1=24,2=90.000000
L 4.0694963 3.2679662 4.0744947 3.2679662 15 P 0 ;0,1=24,2=90.000000
L 4.0744947 3.2479727 4.0694963 3.2479727 15 P 0 ;0,1=24,2=90.000000
L 4.0744947 3.2679662 4.079493 3.2629679 15 P 0 ;0,1=24,2=90.000000
L 4.079493 3.2529711 4.0744947 3.2479727 15 P 0 ;0,1=24,2=90.000000
L 4.079493 3.2529711 4.079493 3.2629679 15 P 0 ;0,1=24,2=90.000000
L 4.079493 3.2629679 4.0844914 3.2679662 15 P 0 ;0,1=24,2=90.000000
L 4.0844914 3.2479727 4.079493 3.2529711 15 P 0 ;0,1=24,2=90.000000
L 4.0844914 3.2679662 4.0894898 3.2679662 15 P 0 ;0,1=24,2=90.000000
L 4.0894898 3.1879921 4.0944882 3.1929905 15 P 0 ;0,1=24,2=90.000000
L 4.0894898 3.2179824 4.0944882 3.2179824 15 P 0 ;0,1=24,2=90.000000
L 4.0894898 3.2479727 4.0844914 3.2479727 15 P 0 ;0,1=24,2=90.000000
L 4.0894898 3.2679662 4.0944882 3.2629679 15 P 0 ;0,1=24,2=90.000000
L 4.0944882 3.1929905 4.0944882 3.2029873 15 P 0 ;0,1=24,2=90.000000
L 4.0944882 3.2029873 4.0894898 3.2079856 15 P 0 ;0,1=24,2=90.000000
L 4.0944882 3.2529711 4.0894898 3.2479727 15 P 0 ;0,1=24,2=90.000000
L 4.0944882 3.2629679 4.0944882 3.2529711 15 P 0 ;0,1=24,2=90.000000
L 4.1028425 2.786063 4.1028425 2.846063 10 P 0
L 4.1206002 3.1929905 4.1255986 3.1879921 15 P 0 ;0,1=25,2=90.000000
L 4.1206002 3.2029873 4.1206002 3.1929905 15 P 0 ;0,1=25,2=90.000000
L 4.1206002 3.2179824 4.1206002 3.2379759 15 P 0 ;0,1=25,2=90.000000
L 4.1206002 3.2379759 4.1255986 3.2379759 15 P 0 ;0,1=25,2=90.000000
L 4.1206002 3.2529711 4.1255986 3.2479727 15 P 0 ;0,1=25,2=90.000000
L 4.1206002 3.2629679 4.1206002 3.2529711 15 P 0 ;0,1=25,2=90.000000
L 4.121353 4.2365703 4.1163546 4.2415687 15 P 0 ;0,1=80,2=0.000000
L 4.1255986 3.1879921 4.1455921 3.1879921 15 P 0 ;0,1=25,2=90.000000
L 4.1255986 3.2079856 4.1206002 3.2029873 15 P 0 ;0,1=25,2=90.000000
L 4.1255986 3.2379759 4.1455921 3.2179824 15 P 0 ;0,1=25,2=90.000000
L 4.1255986 3.2479727 4.130597 3.2479727 15 P 0 ;0,1=25,2=90.000000
L 4.1255986 3.2679662 4.1206002 3.2629679 15 P 0 ;0,1=25,2=90.000000
L 4.1263514 4.2365703 4.121353 4.2365703 15 P 0 ;0,1=80,2=0.000000
L 4.1263514 4.2665606 4.1313498 4.2665606 15 P 0 ;0,1=80,2=0.000000
L 4.1273449 3.8930808 4.1323433 3.8880824 15 P 0 ;0,1=116,2=90.000000
L 4.1273449 3.9030776 4.1273449 3.8930808 15 P 0 ;0,1=116,2=90.000000
L 4.1273449 3.9180727 4.14234 3.9180727 15 P 0 ;0,1=116,2=90.000000
L 4.1273449 3.9380662 4.1273449 3.9180727 15 P 0 ;0,1=116,2=90.000000
L 4.1273449 3.9630582 4.14234 3.948063 15 P 0 ;0,1=116,2=90.000000
L 4.130597 3.2479727 4.1355953 3.2529711 15 P 0 ;0,1=25,2=90.000000
L 4.1313498 4.2415687 4.1263514 4.2365703 15 P 0 ;0,1=80,2=0.000000
L 4.1313498 4.2665606 4.1313498 4.2415687 15 P 0 ;0,1=80,2=0.000000
L 4.1323433 3.8880824 4.1523368 3.8880824 15 P 0 ;0,1=116,2=90.000000
L 4.1323433 3.9080759 4.1273449 3.9030776 15 P 0 ;0,1=116,2=90.000000
L 4.1327559 0.8574803 4.1327559 2.4574803 6 P 0
L 4.1327559 0.8574803 5.5227559 0.8574803 6 P 0
L 4.1327559 2.4574803 5.5227559 2.4574803 6 P 0
L 4.1355953 3.2529711 4.1355953 3.2679662 15 P 0 ;0,1=25,2=90.000000
L 4.1363481 4.2665606 4.1263514 4.2665606 15 P 0 ;0,1=80,2=0.000000
L 4.1373417 3.9280695 4.1373417 3.9330679 15 P 0 ;0,1=116,2=90.000000
L 4.1373417 3.9330679 4.14234 3.9380662 15 P 0 ;0,1=116,2=90.000000
L 4.1378425 2.4970614 4.1428409 2.492063 3 P 0 ;0,1=1,2=0.000000
L 4.1378425 2.5220533 4.1378425 2.4970614 3 P 0 ;0,1=1,2=0.000000
L 4.1378425 3.660063 4.1378425 3.6900533 15 P 0 ;0,1=3,2=0.000000
L 4.1378425 3.6900533 4.1528377 3.6900533 15 P 0 ;0,1=3,2=0.000000
L 4.1398425 3.681378 4.1398425 3.720748 10 P 0
L 4.14234 3.9180727 4.1373417 3.9280695 15 P 0 ;0,1=116,2=90.000000
L 4.14234 3.9380662 4.1523368 3.9380662 15 P 0 ;0,1=116,2=90.000000
L 4.14234 3.948063 4.14234 3.9680565 15 P 0 ;0,1=116,2=90.000000
L 4.1428409 2.492063 4.1528377 2.492063 3 P 0 ;0,1=1,2=0.000000
L 4.1428425 3.776063 4.1428425 3.836063 10 P 0
L 4.1443449 2.8870824 4.15934 2.8870824 15 P 0 ;0,1=83,2=90.000000
L 4.1443449 2.9070759 4.1443449 2.8870824 15 P 0 ;0,1=83,2=90.000000
L 4.1443449 2.9170727 4.1743352 2.9170727 15 P 0 ;0,1=83,2=90.000000
L 4.1443449 2.9320679 4.1443449 2.9170727 15 P 0 ;0,1=83,2=90.000000
L 4.1443449 2.9520614 4.1443449 2.9620582 15 P 0 ;0,1=83,2=90.000000
L 4.1443449 2.9620582 4.1493433 2.9670565 15 P 0 ;0,1=83,2=90.000000
L 4.1455921 3.1879921 4.1505905 3.1929905 15 P 0 ;0,1=25,2=90.000000
L 4.1455921 3.2179824 4.1505905 3.2179824 15 P 0 ;0,1=25,2=90.000000
L 4.1455921 3.2479727 4.1505905 3.2529711 15 P 0 ;0,1=25,2=90.000000
L 4.1455921 3.2679662 4.1255986 3.2679662 15 P 0 ;0,1=25,2=90.000000
L 4.1463449 4.2615622 4.1513433 4.2665606 15 P 0 ;0,1=80,2=0.000000
L 4.1478393 3.6700598 4.157836 3.660063 15 P 0 ;0,1=3,2=0.000000
L 4.1493433 2.9370662 4.1443449 2.9320679 15 P 0 ;0,1=83,2=90.000000
L 4.1493433 2.947063 4.1443449 2.9520614 15 P 0 ;0,1=83,2=90.000000
L 4.1493433 2.9670565 4.1543417 2.9670565 15 P 0 ;0,1=83,2=90.000000
L 4.1505905 3.1929905 4.1505905 3.2029873 15 P 0 ;0,1=25,2=90.000000
L 4.1505905 3.2029873 4.1455921 3.2079856 15 P 0 ;0,1=25,2=90.000000
L 4.1505905 3.2529711 4.1505905 3.2629679 15 P 0 ;0,1=25,2=90.000000
L 4.1505905 3.2629679 4.1455921 3.2679662 15 P 0 ;0,1=25,2=90.000000
L 4.1513433 4.2365703 4.1463449 4.2415687 15 P 0 ;0,1=80,2=0.000000
L 4.1513433 4.2665606 4.1613401 4.2665606 15 P 0 ;0,1=80,2=0.000000
L 4.1523368 3.8880824 4.1573352 3.8930808 15 P 0 ;0,1=116,2=90.000000
L 4.1523368 3.9380662 4.1573352 3.9330679 15 P 0 ;0,1=116,2=90.000000
L 4.1528377 2.492063 4.157836 2.4970614 3 P 0 ;0,1=1,2=0.000000
L 4.1528377 3.6700598 4.1378425 3.6700598 15 P 0 ;0,1=3,2=0.000000
L 4.1528377 3.6900533 4.157836 3.6850549 15 P 0 ;0,1=3,2=0.000000
L 4.1543417 2.9370662 4.1493433 2.9370662 15 P 0 ;0,1=83,2=90.000000
L 4.1543417 2.9670565 4.15934 2.9620582 15 P 0 ;0,1=83,2=90.000000
L 4.1563417 4.2515655 4.1613401 4.2515655 15 P 0 ;0,1=80,2=0.000000
L 4.1573352 3.8930808 4.1573352 3.9030776 15 P 0 ;0,1=116,2=90.000000
L 4.1573352 3.9030776 4.1523368 3.9080759 15 P 0 ;0,1=116,2=90.000000
L 4.1573352 3.9230711 4.1523368 3.9180727 15 P 0 ;0,1=116,2=90.000000
L 4.1573352 3.9330679 4.1573352 3.9230711 15 P 0 ;0,1=116,2=90.000000
L 4.1573352 3.9630582 4.1273449 3.9630582 15 P 0 ;0,1=116,2=90.000000
L 4.157836 2.4970614 4.157836 2.5220533 3 P 0 ;0,1=1,2=0.000000
L 4.157836 3.6750582 4.1528377 3.6700598 15 P 0 ;0,1=3,2=0.000000
L 4.157836 3.6850549 4.157836 3.6750582 15 P 0 ;0,1=3,2=0.000000
L 4.15934 2.8870824 4.15934 2.8970792 15 P 0 ;0,1=83,2=90.000000
L 4.15934 2.8870824 4.1743352 2.8870824 15 P 0 ;0,1=83,2=90.000000
L 4.15934 2.8970792 4.15934 2.8870824 15 P 0 ;0,1=83,2=90.000000
L 4.15934 2.9170727 4.15934 2.9320679 15 P 0 ;0,1=83,2=90.000000
L 4.15934 2.9320679 4.1543417 2.9370662 15 P 0 ;0,1=83,2=90.000000
L 4.15934 2.9320679 4.15934 2.9170727 15 P 0 ;0,1=83,2=90.000000
L 4.15934 2.9570598 4.15934 2.9620582 15 P 0 ;0,1=83,2=90.000000
L 4.15934 2.9620582 4.15934 2.9570598 15 P 0 ;0,1=83,2=90.000000
L 4.15934 2.9620582 4.1643384 2.9670565 15 P 0 ;0,1=83,2=90.000000
L 4.1613401 4.2365703 4.1513433 4.2365703 15 P 0 ;0,1=80,2=0.000000
L 4.1613401 4.2515655 4.1563417 4.2515655 15 P 0 ;0,1=80,2=0.000000
L 4.1613401 4.2515655 4.1663384 4.2465671 15 P 0 ;0,1=80,2=0.000000
L 4.1613401 4.2665606 4.1663384 4.2615622 15 P 0 ;0,1=80,2=0.000000
L 4.1643384 2.9370662 4.15934 2.9320679 15 P 0 ;0,1=83,2=90.000000
L 4.1643384 2.9670565 4.1693368 2.9670565 15 P 0 ;0,1=83,2=90.000000
L 4.1663384 4.2415687 4.1613401 4.2365703 15 P 0 ;0,1=80,2=0.000000
L 4.1663384 4.2465671 4.1663384 4.2415687 15 P 0 ;0,1=80,2=0.000000
L 4.1663384 4.2565638 4.1613401 4.2515655 15 P 0 ;0,1=80,2=0.000000
L 4.1663384 4.2615622 4.1663384 4.2565638 15 P 0 ;0,1=80,2=0.000000
L 4.1668425 3.781063 4.1668425 3.831063 10 P 0
L 4.1678328 2.492063 4.1778296 2.492063 3 P 0 ;0,1=1,2=0.000000
L 4.1678328 3.660063 4.1778296 3.660063 15 P 0 ;0,1=3,2=0.000000
L 4.1693368 2.9370662 4.1643384 2.9370662 15 P 0 ;0,1=83,2=90.000000
L 4.1693368 2.9670565 4.1743352 2.9620582 15 P 0 ;0,1=83,2=90.000000
L 4.1728312 2.492063 4.1728312 2.5220533 3 P 0 ;0,1=1,2=0.000000
L 4.1728312 2.5220533 4.1678328 2.5170549 3 P 0 ;0,1=1,2=0.000000
L 4.1728312 3.660063 4.1728312 3.6900533 15 P 0 ;0,1=3,2=0.000000
L 4.1728312 3.6900533 4.1678328 3.6850549 15 P 0 ;0,1=3,2=0.000000
L 4.1743352 2.9170727 4.1743352 2.9320679 15 P 0 ;0,1=83,2=90.000000
L 4.1743352 2.9320679 4.1693368 2.9370662 15 P 0 ;0,1=83,2=90.000000
L 4.1743352 2.9520614 4.1693368 2.947063 15 P 0 ;0,1=83,2=90.000000
L 4.1743352 2.9620582 4.1743352 2.9520614 15 P 0 ;0,1=83,2=90.000000
L 4.1777559 3.5836615 4.1777559 3.6230315 10 P 0
L 4.1778296 2.492063 4.1728312 2.492063 3 P 0 ;0,1=1,2=0.000000
L 4.1778296 3.660063 4.1728312 3.660063 15 P 0 ;0,1=3,2=0.000000
L 4.1808425 3.3210614 4.1858409 3.316063 15 P 0 ;0,1=30,2=0.000000
L 4.1808425 3.3410549 4.1808425 3.3210614 15 P 0 ;0,1=30,2=0.000000
L 4.1858409 3.316063 4.1958377 3.316063 15 P 0 ;0,1=30,2=0.000000
L 4.1858409 3.3460533 4.1808425 3.3410549 15 P 0 ;0,1=30,2=0.000000
L 4.1928247 2.4970614 4.1928247 2.5170549 3 P 0 ;0,1=1,2=0.000000
L 4.1928247 2.5170549 4.1978231 2.5220533 3 P 0 ;0,1=1,2=0.000000
L 4.1958377 3.316063 4.200836 3.3210614 15 P 0 ;0,1=30,2=0.000000
L 4.1958377 3.3460533 4.1858409 3.3460533 15 P 0 ;0,1=30,2=0.000000
L 4.1968425 2.786063 4.1968425 2.846063 10 P 0
L 4.1978231 2.492063 4.1928247 2.4970614 3 P 0 ;0,1=1,2=0.000000
L 4.1978231 2.5220533 4.2078199 2.5220533 3 P 0 ;0,1=1,2=0.000000
L 4.200836 3.3410549 4.1958377 3.3460533 15 P 0 ;0,1=30,2=0.000000
L 4.2068619 3.6785703 4.2068619 3.7085606 15 P 0 ;0,1=61,2=0.000000
L 4.2068619 3.7085606 4.2218571 3.7085606 15 P 0 ;0,1=61,2=0.000000
L 4.2078199 2.492063 4.1978231 2.492063 3 P 0 ;0,1=1,2=0.000000
L 4.2078199 2.5220533 4.2128182 2.5170549 3 P 0 ;0,1=1,2=0.000000
L 4.2108328 3.3210614 4.2108328 3.3260598 15 P 0 ;0,1=30,2=0.000000
L 4.2108328 3.3260598 4.2158312 3.3310582 15 P 0 ;0,1=30,2=0.000000
L 4.2108328 3.3360565 4.2108328 3.3410549 15 P 0 ;0,1=30,2=0.000000
L 4.2108328 3.3410549 4.2158312 3.3460533 15 P 0 ;0,1=30,2=0.000000
L 4.2128182 2.4970614 4.2078199 2.492063 3 P 0 ;0,1=1,2=0.000000
L 4.2128182 2.5170549 4.2128182 2.4970614 3 P 0 ;0,1=1,2=0.000000
L 4.2148425 3.208063 4.2748425 3.208063 10 P 0
L 4.2148425 3.284063 4.2748425 3.284063 10 P 0
L 4.2158312 3.316063 4.2108328 3.3210614 15 P 0 ;0,1=30,2=0.000000
L 4.2158312 3.3310582 4.2108328 3.3360565 15 P 0 ;0,1=30,2=0.000000
L 4.2158312 3.3310582 4.225828 3.3310582 15 P 0 ;0,1=30,2=0.000000
L 4.2158312 3.3460533 4.225828 3.3460533 15 P 0 ;0,1=30,2=0.000000
L 4.2168587 3.6885671 4.2268554 3.6785703 15 P 0 ;0,1=61,2=0.000000
L 4.2218571 3.6885671 4.2068619 3.6885671 15 P 0 ;0,1=61,2=0.000000
L 4.2218571 3.7085606 4.2268554 3.7035622 15 P 0 ;0,1=61,2=0.000000
L 4.222815 2.492063 4.222815 2.5120565 3 P 0 ;0,1=1,2=0.000000
L 4.222815 2.5120565 4.2328118 2.5220533 3 P 0 ;0,1=1,2=0.000000
L 4.2228425 3.781063 4.2228425 3.831063 10 P 0
L 4.225828 3.316063 4.2158312 3.316063 15 P 0 ;0,1=30,2=0.000000
L 4.225828 3.3310582 4.2308263 3.3260598 15 P 0 ;0,1=30,2=0.000000
L 4.225828 3.3460533 4.2308263 3.3410549 15 P 0 ;0,1=30,2=0.000000
L 4.2268554 3.6935655 4.2218571 3.6885671 15 P 0 ;0,1=61,2=0.000000
L 4.2268554 3.7035622 4.2268554 3.6935655 15 P 0 ;0,1=61,2=0.000000
L 4.2303449 2.9000808 4.2353433 2.8950824 15 P 0 ;0,1=19,2=90.000000
L 4.2303449 2.9100776 4.2303449 2.9000808 15 P 0 ;0,1=19,2=90.000000
L 4.2303449 2.9250727 4.2303449 2.9450662 15 P 0 ;0,1=19,2=90.000000
L 4.2303449 2.9450662 4.2353433 2.9450662 15 P 0 ;0,1=19,2=90.000000
L 4.2303449 2.9600614 4.2303449 2.9700582 15 P 0 ;0,1=19,2=90.000000
L 4.2303449 2.9700582 4.2353433 2.9750565 15 P 0 ;0,1=19,2=90.000000
L 4.2308263 3.3210614 4.225828 3.316063 15 P 0 ;0,1=30,2=0.000000
L 4.2308263 3.3260598 4.2308263 3.3210614 15 P 0 ;0,1=30,2=0.000000
L 4.2308263 3.3360565 4.225828 3.3310582 15 P 0 ;0,1=30,2=0.000000
L 4.2308263 3.3410549 4.2308263 3.3360565 15 P 0 ;0,1=30,2=0.000000
L 4.2328118 2.5220533 4.2428085 2.5120565 3 P 0 ;0,1=1,2=0.000000
L 4.2353433 2.8950824 4.2553368 2.8950824 15 P 0 ;0,1=19,2=90.000000
L 4.2353433 2.9150759 4.2303449 2.9100776 15 P 0 ;0,1=19,2=90.000000
L 4.2353433 2.9450662 4.2553368 2.9250727 15 P 0 ;0,1=19,2=90.000000
L 4.2353433 2.955063 4.2303449 2.9600614 15 P 0 ;0,1=19,2=90.000000
L 4.2353433 2.9750565 4.2403417 2.9750565 15 P 0 ;0,1=19,2=90.000000
L 4.2368522 3.6785703 4.2568457 3.6985638 15 P 0 ;0,1=61,2=0.000000
L 4.2403417 2.9750565 4.24534 2.9700582 15 P 0 ;0,1=19,2=90.000000
L 4.2408231 3.3310582 4.2608166 3.3310582 15 P 0 ;0,1=30,2=0.000000
L 4.2418506 3.7085606 4.2368522 3.7035622 15 P 0 ;0,1=61,2=0.000000
L 4.2428085 2.492063 4.2428085 2.5070582 3 P 0 ;0,1=1,2=0.000000
L 4.2428085 2.5070582 4.222815 2.5070582 3 P 0 ;0,1=1,2=0.000000
L 4.2428085 2.5120565 4.2428085 2.492063 3 P 0 ;0,1=1,2=0.000000
L 4.24534 2.9650598 4.24534 2.9700582 15 P 0 ;0,1=19,2=90.000000
L 4.24534 2.9700582 4.24534 2.9650598 15 P 0 ;0,1=19,2=90.000000
L 4.24534 2.9700582 4.2503384 2.9750565 15 P 0 ;0,1=19,2=90.000000
L 4.2503384 2.9750565 4.2553368 2.9750565 15 P 0 ;0,1=19,2=90.000000
L 4.2518474 3.7085606 4.2418506 3.7085606 15 P 0 ;0,1=61,2=0.000000
L 4.2528053 2.492063 4.2727988 2.492063 3 P 0 ;0,1=1,2=0.000000
L 4.2528053 2.5220533 4.2528053 2.492063 3 P 0 ;0,1=1,2=0.000000
L 4.2553368 2.8950824 4.2603352 2.9000808 15 P 0 ;0,1=19,2=90.000000
L 4.2553368 2.9250727 4.2603352 2.9250727 15 P 0 ;0,1=19,2=90.000000
L 4.2553368 2.9750565 4.2603352 2.9700582 15 P 0 ;0,1=19,2=90.000000
L 4.2558183 3.316063 4.2558183 3.3460533 15 P 0 ;0,1=30,2=0.000000
L 4.2558183 3.3460533 4.2408231 3.3310582 15 P 0 ;0,1=30,2=0.000000
L 4.2568457 3.6785703 4.2368522 3.6785703 15 P 0 ;0,1=61,2=0.000000
L 4.2568457 3.6985638 4.2568457 3.7035622 15 P 0 ;0,1=61,2=0.000000
L 4.2568457 3.7035622 4.2518474 3.7085606 15 P 0 ;0,1=61,2=0.000000
L 4.2603352 2.9000808 4.2603352 2.9100776 15 P 0 ;0,1=19,2=90.000000
L 4.2603352 2.9100776 4.2553368 2.9150759 15 P 0 ;0,1=19,2=90.000000
L 4.2603352 2.9600614 4.2553368 2.955063 15 P 0 ;0,1=19,2=90.000000
L 4.2603352 2.9700582 4.2603352 2.9600614 15 P 0 ;0,1=19,2=90.000000
L 4.2668425 3.6835687 4.2668425 3.6785703 15 P 0 ;0,1=61,2=0.000000
L 4.2668425 3.7085606 4.286836 3.7085606 15 P 0 ;0,1=61,2=0.000000
L 4.2683449 3.8100808 4.2733433 3.8050824 15 P 0 ;0,1=115,2=90.000000
L 4.2683449 3.8200776 4.2683449 3.8100808 15 P 0 ;0,1=115,2=90.000000
L 4.2683449 3.8350727 4.28334 3.8350727 15 P 0 ;0,1=115,2=90.000000
L 4.2683449 3.8550662 4.2683449 3.8350727 15 P 0 ;0,1=115,2=90.000000
L 4.2683449 3.865063 4.28334 3.865063 15 P 0 ;0,1=115,2=90.000000
L 4.2683449 3.8850565 4.2683449 3.865063 15 P 0 ;0,1=115,2=90.000000
L 4.2728425 2.786063 4.2728425 2.846063 10 P 0
L 4.2733433 3.8050824 4.2933368 3.8050824 15 P 0 ;0,1=115,2=90.000000
L 4.2733433 3.8250759 4.2683449 3.8200776 15 P 0 ;0,1=115,2=90.000000
L 4.2783417 3.8450695 4.2783417 3.8500679 15 P 0 ;0,1=115,2=90.000000
L 4.2783417 3.8500679 4.28334 3.8550662 15 P 0 ;0,1=115,2=90.000000
L 4.2783417 3.8750598 4.2783417 3.8800582 15 P 0 ;0,1=115,2=90.000000
L 4.2783417 3.8800582 4.28334 3.8850565 15 P 0 ;0,1=115,2=90.000000
L 4.28334 3.8350727 4.2783417 3.8450695 15 P 0 ;0,1=115,2=90.000000
L 4.28334 3.8550662 4.2933368 3.8550662 15 P 0 ;0,1=115,2=90.000000
L 4.28334 3.865063 4.2783417 3.8750598 15 P 0 ;0,1=115,2=90.000000
L 4.28334 3.8850565 4.2933368 3.8850565 15 P 0 ;0,1=115,2=90.000000
L 4.286836 3.7035622 4.2668425 3.6835687 15 P 0 ;0,1=61,2=0.000000
L 4.286836 3.7085606 4.286836 3.7035622 15 P 0 ;0,1=61,2=0.000000
L 4.2933368 3.8050824 4.2983352 3.8100808 15 P 0 ;0,1=115,2=90.000000
L 4.2933368 3.8550662 4.2983352 3.8500679 15 P 0 ;0,1=115,2=90.000000
L 4.2933368 3.8850565 4.2983352 3.8800582 15 P 0 ;0,1=115,2=90.000000
L 4.2983352 3.8100808 4.2983352 3.8200776 15 P 0 ;0,1=115,2=90.000000
L 4.2983352 3.8200776 4.2933368 3.8250759 15 P 0 ;0,1=115,2=90.000000
L 4.2983352 3.8400711 4.2933368 3.8350727 15 P 0 ;0,1=115,2=90.000000
L 4.2983352 3.8500679 4.2983352 3.8400711 15 P 0 ;0,1=115,2=90.000000
L 4.2983352 3.8700614 4.2933368 3.865063 15 P 0 ;0,1=115,2=90.000000
L 4.2983352 3.8800582 4.2983352 3.8700614 15 P 0 ;0,1=115,2=90.000000
L 4.3018425 2.786063 4.3018425 2.846063 10 P 0
L 4.3248031 3.6338583 4.3397983 3.6338583 15 P 0 ;0,1=100,2=0.000000
L 4.3248031 3.6638486 4.3248031 3.6338583 15 P 0 ;0,1=100,2=0.000000
L 4.3333449 2.8990808 4.3383433 2.8940824 15 P 0 ;0,1=18,2=90.000000
L 4.3333449 2.9090776 4.3333449 2.8990808 15 P 0 ;0,1=18,2=90.000000
L 4.3333449 2.9240727 4.3333449 2.9440662 15 P 0 ;0,1=18,2=90.000000
L 4.3333449 2.9440662 4.3383433 2.9440662 15 P 0 ;0,1=18,2=90.000000
L 4.3333449 2.9590614 4.3383433 2.954063 15 P 0 ;0,1=18,2=90.000000
L 4.3333449 2.9690582 4.3333449 2.9590614 15 P 0 ;0,1=18,2=90.000000
L 4.3341829 3.2156283 4.3391813 3.2106299 15 P 0 ;0,1=26,2=90.000000
L 4.3341829 3.2256251 4.3341829 3.2156283 15 P 0 ;0,1=26,2=90.000000
L 4.3341829 3.2456186 4.3341829 3.2556154 15 P 0 ;0,1=26,2=90.000000
L 4.3341829 3.2556154 4.3391813 3.2606137 15 P 0 ;0,1=26,2=90.000000
L 4.3341829 3.2756089 4.3341829 3.2856057 15 P 0 ;0,1=26,2=90.000000
L 4.3341829 3.2856057 4.3391813 3.290604 15 P 0 ;0,1=26,2=90.000000
L 4.3383433 2.8940824 4.3583368 2.8940824 15 P 0 ;0,1=18,2=90.000000
L 4.3383433 2.9140759 4.3333449 2.9090776 15 P 0 ;0,1=18,2=90.000000
L 4.3383433 2.9440662 4.3583368 2.9240727 15 P 0 ;0,1=18,2=90.000000
L 4.3383433 2.9740565 4.3333449 2.9690582 15 P 0 ;0,1=18,2=90.000000
L 4.3391813 3.2106299 4.3591748 3.2106299 15 P 0 ;0,1=26,2=90.000000
L 4.3391813 3.2306234 4.3341829 3.2256251 15 P 0 ;0,1=26,2=90.000000
L 4.3391813 3.2406202 4.3341829 3.2456186 15 P 0 ;0,1=26,2=90.000000
L 4.3391813 3.2606137 4.3441797 3.2606137 15 P 0 ;0,1=26,2=90.000000
L 4.3391813 3.2706105 4.3341829 3.2756089 15 P 0 ;0,1=26,2=90.000000
L 4.3391813 3.290604 4.3591748 3.290604 15 P 0 ;0,1=26,2=90.000000
L 4.3397983 3.6338583 4.3447966 3.6388567 15 P 0 ;0,1=100,2=0.000000
L 4.3397983 3.6638486 4.3248031 3.6638486 15 P 0 ;0,1=100,2=0.000000
L 4.3433417 2.9740565 4.3383433 2.9740565 15 P 0 ;0,1=18,2=90.000000
L 4.3441797 3.2406202 4.3391813 3.2406202 15 P 0 ;0,1=26,2=90.000000
L 4.3441797 3.2606137 4.349178 3.2556154 15 P 0 ;0,1=26,2=90.000000
L 4.3447966 3.6388567 4.3447966 3.6588502 15 P 0 ;0,1=100,2=0.000000
L 4.3447966 3.6588502 4.3397983 3.6638486 15 P 0 ;0,1=100,2=0.000000
L 4.349178 3.2456186 4.3441797 3.2406202 15 P 0 ;0,1=26,2=90.000000
L 4.349178 3.2456186 4.349178 3.2556154 15 P 0 ;0,1=26,2=90.000000
L 4.349178 3.2556154 4.3541764 3.2606137 15 P 0 ;0,1=26,2=90.000000
L 4.3541764 3.2406202 4.349178 3.2456186 15 P 0 ;0,1=26,2=90.000000
L 4.3541764 3.2606137 4.3591748 3.2606137 15 P 0 ;0,1=26,2=90.000000
L 4.3547934 3.6488535 4.3747869 3.6488535 15 P 0 ;0,1=100,2=0.000000
L 4.3583368 2.8940824 4.3633352 2.8990808 15 P 0 ;0,1=18,2=90.000000
L 4.3583368 2.9240727 4.3633352 2.9240727 15 P 0 ;0,1=18,2=90.000000
L 4.3591748 3.2106299 4.3641732 3.2156283 15 P 0 ;0,1=26,2=90.000000
L 4.3591748 3.2406202 4.3541764 3.2406202 15 P 0 ;0,1=26,2=90.000000
L 4.3591748 3.2606137 4.3641732 3.2556154 15 P 0 ;0,1=26,2=90.000000
L 4.3591748 3.2706105 4.3391813 3.2706105 15 P 0 ;0,1=26,2=90.000000
L 4.3591748 3.290604 4.3641732 3.2856057 15 P 0 ;0,1=26,2=90.000000
L 4.3633352 2.8990808 4.3633352 2.9090776 15 P 0 ;0,1=18,2=90.000000
L 4.3633352 2.9090776 4.3583368 2.9140759 15 P 0 ;0,1=18,2=90.000000
L 4.3633352 2.954063 4.3433417 2.9740565 15 P 0 ;0,1=18,2=90.000000
L 4.3633352 2.9740565 4.3633352 2.954063 15 P 0 ;0,1=18,2=90.000000
L 4.3641732 3.2156283 4.3641732 3.2256251 15 P 0 ;0,1=26,2=90.000000
L 4.3641732 3.2256251 4.3591748 3.2306234 15 P 0 ;0,1=26,2=90.000000
L 4.3641732 3.2456186 4.3591748 3.2406202 15 P 0 ;0,1=26,2=90.000000
L 4.3641732 3.2556154 4.3641732 3.2456186 15 P 0 ;0,1=26,2=90.000000
L 4.3641732 3.2756089 4.3591748 3.2706105 15 P 0 ;0,1=26,2=90.000000
L 4.3641732 3.2856057 4.3641732 3.2756089 15 P 0 ;0,1=26,2=90.000000
L 4.3697886 3.6338583 4.3697886 3.6638486 15 P 0 ;0,1=100,2=0.000000
L 4.3697886 3.6638486 4.3547934 3.6488535 15 P 0 ;0,1=100,2=0.000000
L 4.3778425 2.786063 4.3778425 2.846063 10 P 0
L 4.3843798 3.2156283 4.3893782 3.2106299 15 P 0 ;0,1=27,2=90.000000
L 4.3843798 3.2256251 4.3843798 3.2156283 15 P 0 ;0,1=27,2=90.000000
L 4.3843798 3.2456186 4.3843798 3.2556154 15 P 0 ;0,1=27,2=90.000000
L 4.3843798 3.2556154 4.3893782 3.2606137 15 P 0 ;0,1=27,2=90.000000
L 4.3843798 3.2756089 4.3893782 3.2706105 15 P 0 ;0,1=27,2=90.000000
L 4.3893782 3.2106299 4.4093717 3.2106299 15 P 0 ;0,1=27,2=90.000000
L 4.3893782 3.2306234 4.3843798 3.2256251 15 P 0 ;0,1=27,2=90.000000
L 4.3893782 3.2406202 4.3843798 3.2456186 15 P 0 ;0,1=27,2=90.000000
L 4.3893782 3.2606137 4.3943766 3.2606137 15 P 0 ;0,1=27,2=90.000000
L 4.3943766 3.2406202 4.3893782 3.2406202 15 P 0 ;0,1=27,2=90.000000
L 4.3943766 3.2606137 4.3993749 3.2556154 15 P 0 ;0,1=27,2=90.000000
L 4.3993749 3.2456186 4.3943766 3.2406202 15 P 0 ;0,1=27,2=90.000000
L 4.3993749 3.2456186 4.3993749 3.2556154 15 P 0 ;0,1=27,2=90.000000
L 4.3993749 3.2556154 4.4043733 3.2606137 15 P 0 ;0,1=27,2=90.000000
L 4.4043733 3.2406202 4.3993749 3.2456186 15 P 0 ;0,1=27,2=90.000000
L 4.4043733 3.2606137 4.4093717 3.2606137 15 P 0 ;0,1=27,2=90.000000
L 4.4068425 4.3170565 4.4118409 4.3120582 15 P 0 ;0,1=52,2=0.000000
L 4.4068425 4.3220549 4.4068425 4.3170565 15 P 0 ;0,1=52,2=0.000000
L 4.4093717 3.2106299 4.4143701 3.2156283 15 P 0 ;0,1=27,2=90.000000
L 4.4093717 3.2406202 4.4043733 3.2406202 15 P 0 ;0,1=27,2=90.000000
L 4.4093717 3.2606137 4.4143701 3.2556154 15 P 0 ;0,1=27,2=90.000000
L 4.4098425 4.151063 4.4098425 4.161063 12 P 0
L 4.4098425 4.151063 4.5898425 4.151063 12 P 0
L 4.4098425 4.251063 4.4098425 4.261063 12 P 0
L 4.4098425 4.261063 4.5898425 4.261063 12 P 0
L 4.4118409 4.297063 4.4068425 4.3020614 15 P 0 ;0,1=52,2=0.000000
L 4.4118409 4.3120582 4.4218377 4.3120582 15 P 0 ;0,1=52,2=0.000000
L 4.4118409 4.3270533 4.4068425 4.3220549 15 P 0 ;0,1=52,2=0.000000
L 4.4143701 3.2156283 4.4143701 3.2256251 15 P 0 ;0,1=27,2=90.000000
L 4.4143701 3.2256251 4.4093717 3.2306234 15 P 0 ;0,1=27,2=90.000000
L 4.4143701 3.2456186 4.4093717 3.2406202 15 P 0 ;0,1=27,2=90.000000
L 4.4143701 3.2556154 4.4143701 3.2456186 15 P 0 ;0,1=27,2=90.000000
L 4.4143701 3.2706105 4.4143701 3.2806073 15 P 0 ;0,1=27,2=90.000000
L 4.4143701 3.2756089 4.3843798 3.2756089 15 P 0 ;0,1=27,2=90.000000
L 4.4143701 3.2806073 4.4143701 3.2756089 15 P 0 ;0,1=27,2=90.000000
L 4.4218377 4.297063 4.4118409 4.297063 15 P 0 ;0,1=52,2=0.000000
L 4.4218377 4.3120582 4.426836 4.3070598 15 P 0 ;0,1=52,2=0.000000
L 4.4218377 4.3270533 4.4118409 4.3270533 15 P 0 ;0,1=52,2=0.000000
L 4.426836 4.3020614 4.4218377 4.297063 15 P 0 ;0,1=52,2=0.000000
L 4.426836 4.3070598 4.426836 4.3020614 15 P 0 ;0,1=52,2=0.000000
L 4.426836 4.3220549 4.4218377 4.3270533 15 P 0 ;0,1=52,2=0.000000
L 4.4335924 3.2107071 4.4385908 3.2057087 15 P 0 ;0,1=28,2=90.000000
L 4.4335924 3.2207039 4.4335924 3.2107071 15 P 0 ;0,1=28,2=90.000000
L 4.4335924 3.2406974 4.4335924 3.2506942 15 P 0 ;0,1=28,2=90.000000
L 4.4335924 3.2506942 4.4385908 3.2556925 15 P 0 ;0,1=28,2=90.000000
L 4.4335924 3.2706877 4.4385908 3.2656893 15 P 0 ;0,1=28,2=90.000000
L 4.4335924 3.2806845 4.4335924 3.2706877 15 P 0 ;0,1=28,2=90.000000
L 4.4368328 4.3120582 4.4468296 4.3170565 15 P 0 ;0,1=52,2=0.000000
L 4.4368328 4.3270533 4.4368328 4.3120582 15 P 0 ;0,1=52,2=0.000000
L 4.4385908 3.2057087 4.4585843 3.2057087 15 P 0 ;0,1=28,2=90.000000
L 4.4385908 3.2257022 4.4335924 3.2207039 15 P 0 ;0,1=28,2=90.000000
L 4.4385908 3.235699 4.4335924 3.2406974 15 P 0 ;0,1=28,2=90.000000
L 4.4385908 3.2556925 4.4435892 3.2556925 15 P 0 ;0,1=28,2=90.000000
L 4.4385908 3.2856828 4.4335924 3.2806845 15 P 0 ;0,1=28,2=90.000000
L 4.4418312 4.297063 4.4368328 4.3020614 15 P 0 ;0,1=52,2=0.000000
L 4.4435892 3.235699 4.4385908 3.235699 15 P 0 ;0,1=28,2=90.000000
L 4.4435892 3.2556925 4.4485875 3.2506942 15 P 0 ;0,1=28,2=90.000000
L 4.4435892 3.2856828 4.4385908 3.2856828 15 P 0 ;0,1=28,2=90.000000
L 4.4468296 4.3170565 4.451828 4.3170565 15 P 0 ;0,1=52,2=0.000000
L 4.4485875 3.2406974 4.4435892 3.235699 15 P 0 ;0,1=28,2=90.000000
L 4.4485875 3.2406974 4.4485875 3.2506942 15 P 0 ;0,1=28,2=90.000000
L 4.4485875 3.2506942 4.4535859 3.2556925 15 P 0 ;0,1=28,2=90.000000
L 4.451828 4.297063 4.4418312 4.297063 15 P 0 ;0,1=52,2=0.000000
L 4.451828 4.3170565 4.4568263 4.3120582 15 P 0 ;0,1=52,2=0.000000
L 4.4535859 3.235699 4.4485875 3.2406974 15 P 0 ;0,1=28,2=90.000000
L 4.4535859 3.2556925 4.4585843 3.2556925 15 P 0 ;0,1=28,2=90.000000
L 4.4568263 4.3020614 4.451828 4.297063 15 P 0 ;0,1=52,2=0.000000
L 4.4568263 4.3120582 4.4568263 4.3020614 15 P 0 ;0,1=52,2=0.000000
L 4.4568263 4.3270533 4.4368328 4.3270533 15 P 0 ;0,1=52,2=0.000000
L 4.4581215 3.8806742 4.4731167 3.8806742 3 P 0 ;0,1=0,2=0.000000
L 4.4581215 3.8956694 4.4731167 3.8956694 3 P 0 ;0,1=0,2=0.000000
L 4.4581215 3.9106645 4.4581215 3.8806742 3 P 0 ;0,1=0,2=0.000000
L 4.4585843 3.2057087 4.4635827 3.2107071 15 P 0 ;0,1=28,2=90.000000
L 4.4585843 3.235699 4.4535859 3.235699 15 P 0 ;0,1=28,2=90.000000
L 4.4585843 3.2556925 4.4635827 3.2506942 15 P 0 ;0,1=28,2=90.000000
L 4.4635827 3.2107071 4.4635827 3.2207039 15 P 0 ;0,1=28,2=90.000000
L 4.4635827 3.2207039 4.4585843 3.2257022 15 P 0 ;0,1=28,2=90.000000
L 4.4635827 3.2406974 4.4585843 3.235699 15 P 0 ;0,1=28,2=90.000000
L 4.4635827 3.2506942 4.4635827 3.2406974 15 P 0 ;0,1=28,2=90.000000
L 4.4635827 3.2656893 4.4435892 3.2856828 15 P 0 ;0,1=28,2=90.000000
L 4.4635827 3.2856828 4.4635827 3.2656893 15 P 0 ;0,1=28,2=90.000000
L 4.4731167 3.8806742 4.478115 3.8856726 3 P 0 ;0,1=0,2=0.000000
L 4.4731167 3.8956694 4.4581215 3.8956694 3 P 0 ;0,1=0,2=0.000000
L 4.4731167 3.8956694 4.478115 3.9006677 3 P 0 ;0,1=0,2=0.000000
L 4.4731167 3.9106645 4.4581215 3.9106645 3 P 0 ;0,1=0,2=0.000000
L 4.478115 3.8856726 4.478115 3.890671 3 P 0 ;0,1=0,2=0.000000
L 4.478115 3.890671 4.4731167 3.8956694 3 P 0 ;0,1=0,2=0.000000
L 4.478115 3.9006677 4.478115 3.9056661 3 P 0 ;0,1=0,2=0.000000
L 4.478115 3.9056661 4.4731167 3.9106645 3 P 0 ;0,1=0,2=0.000000
L 4.482805 3.1703527 4.4878034 3.1653543 15 P 0 ;0,1=29,2=90.000000
L 4.482805 3.1803495 4.482805 3.1703527 15 P 0 ;0,1=29,2=90.000000
L 4.482805 3.200343 4.482805 3.2103398 15 P 0 ;0,1=29,2=90.000000
L 4.482805 3.2103398 4.4878034 3.2153381 15 P 0 ;0,1=29,2=90.000000
L 4.482805 3.2303333 4.482805 3.2403301 15 P 0 ;0,1=29,2=90.000000
L 4.482805 3.2403301 4.4878034 3.2453284 15 P 0 ;0,1=29,2=90.000000
L 4.4878034 3.1653543 4.5077969 3.1653543 15 P 0 ;0,1=29,2=90.000000
L 4.4878034 3.1853478 4.482805 3.1803495 15 P 0 ;0,1=29,2=90.000000
L 4.4878034 3.1953446 4.482805 3.200343 15 P 0 ;0,1=29,2=90.000000
L 4.4878034 3.2153381 4.4928018 3.2153381 15 P 0 ;0,1=29,2=90.000000
L 4.4878034 3.2253349 4.482805 3.2303333 15 P 0 ;0,1=29,2=90.000000
L 4.4878034 3.2453284 4.4928018 3.2453284 15 P 0 ;0,1=29,2=90.000000
L 4.4881118 3.9106645 4.5081053 3.9106645 3 P 0 ;0,1=0,2=0.000000
L 4.4928018 3.1953446 4.4878034 3.1953446 15 P 0 ;0,1=29,2=90.000000
L 4.4928018 3.2153381 4.4978001 3.2103398 15 P 0 ;0,1=29,2=90.000000
L 4.4928018 3.2453284 4.4978001 3.2403301 15 P 0 ;0,1=29,2=90.000000
L 4.4963449 2.8340824 4.51134 2.8340824 15 P 0 ;0,1=84,2=90.000000
L 4.4963449 2.8540759 4.4963449 2.8340824 15 P 0 ;0,1=84,2=90.000000
L 4.4963449 2.8640727 4.5263352 2.8640727 15 P 0 ;0,1=84,2=90.000000
L 4.4963449 2.8790679 4.4963449 2.8640727 15 P 0 ;0,1=84,2=90.000000
L 4.4963449 2.8990614 4.5013433 2.894063 15 P 0 ;0,1=84,2=90.000000
L 4.4963449 2.9090582 4.4963449 2.8990614 15 P 0 ;0,1=84,2=90.000000
L 4.4978001 3.200343 4.4928018 3.1953446 15 P 0 ;0,1=29,2=90.000000
L 4.4978001 3.200343 4.4978001 3.2103398 15 P 0 ;0,1=29,2=90.000000
L 4.4978001 3.2103398 4.5027985 3.2153381 15 P 0 ;0,1=29,2=90.000000
L 4.4978001 3.2353317 4.4978001 3.2403301 15 P 0 ;0,1=29,2=90.000000
L 4.4978001 3.2403301 4.4978001 3.2353317 15 P 0 ;0,1=29,2=90.000000
L 4.4978001 3.2403301 4.5027985 3.2453284 15 P 0 ;0,1=29,2=90.000000
L 4.4981086 3.9106645 4.4981086 3.8806742 3 P 0 ;0,1=0,2=0.000000
L 4.5013433 2.8840662 4.4963449 2.8790679 15 P 0 ;0,1=84,2=90.000000
L 4.5013433 2.9140565 4.4963449 2.9090582 15 P 0 ;0,1=84,2=90.000000
L 4.5027985 3.1953446 4.4978001 3.200343 15 P 0 ;0,1=29,2=90.000000
L 4.5027985 3.2153381 4.5077969 3.2153381 15 P 0 ;0,1=29,2=90.000000
L 4.5027985 3.2453284 4.5077969 3.2453284 15 P 0 ;0,1=29,2=90.000000
L 4.5063417 2.8840662 4.5013433 2.8840662 15 P 0 ;0,1=84,2=90.000000
L 4.5063417 2.9140565 4.5013433 2.9140565 15 P 0 ;0,1=84,2=90.000000
L 4.5077969 3.1653543 4.5127953 3.1703527 15 P 0 ;0,1=29,2=90.000000
L 4.5077969 3.1953446 4.5027985 3.1953446 15 P 0 ;0,1=29,2=90.000000
L 4.5077969 3.2153381 4.5127953 3.2103398 15 P 0 ;0,1=29,2=90.000000
L 4.5077969 3.2453284 4.5127953 3.2403301 15 P 0 ;0,1=29,2=90.000000
L 4.5081053 3.9106645 4.4981086 3.9106645 3 P 0 ;0,1=0,2=0.000000
L 4.51134 2.8340824 4.51134 2.8440792 15 P 0 ;0,1=84,2=90.000000
L 4.51134 2.8340824 4.5263352 2.8340824 15 P 0 ;0,1=84,2=90.000000
L 4.51134 2.8440792 4.51134 2.8340824 15 P 0 ;0,1=84,2=90.000000
L 4.51134 2.8640727 4.51134 2.8790679 15 P 0 ;0,1=84,2=90.000000
L 4.51134 2.8790679 4.5063417 2.8840662 15 P 0 ;0,1=84,2=90.000000
L 4.51134 2.8790679 4.51134 2.8640727 15 P 0 ;0,1=84,2=90.000000
L 4.5127953 3.1703527 4.5127953 3.1803495 15 P 0 ;0,1=29,2=90.000000
L 4.5127953 3.1803495 4.5077969 3.1853478 15 P 0 ;0,1=29,2=90.000000
L 4.5127953 3.200343 4.5077969 3.1953446 15 P 0 ;0,1=29,2=90.000000
L 4.5127953 3.2103398 4.5127953 3.200343 15 P 0 ;0,1=29,2=90.000000
L 4.5127953 3.2303333 4.5077969 3.2253349 15 P 0 ;0,1=29,2=90.000000
L 4.5127953 3.2403301 4.5127953 3.2303333 15 P 0 ;0,1=29,2=90.000000
L 4.5163384 2.8840662 4.51134 2.8790679 15 P 0 ;0,1=84,2=90.000000
L 4.5181021 3.8806742 4.5280989 3.8806742 3 P 0 ;0,1=0,2=0.000000
L 4.5213368 2.8840662 4.5163384 2.8840662 15 P 0 ;0,1=84,2=90.000000
L 4.5231005 3.8806742 4.5231005 3.9106645 3 P 0 ;0,1=0,2=0.000000
L 4.5231005 3.9106645 4.5181021 3.9056661 3 P 0 ;0,1=0,2=0.000000
L 4.5263352 2.8640727 4.5263352 2.8790679 15 P 0 ;0,1=84,2=90.000000
L 4.5263352 2.8790679 4.5213368 2.8840662 15 P 0 ;0,1=84,2=90.000000
L 4.5263352 2.894063 4.5063417 2.9140565 15 P 0 ;0,1=84,2=90.000000
L 4.5263352 2.9140565 4.5263352 2.894063 15 P 0 ;0,1=84,2=90.000000
L 4.5280989 3.8806742 4.5231005 3.8806742 3 P 0 ;0,1=0,2=0.000000
L 4.5846457 2.8120079 4.5846457 3.9576771 6 P 0
L 4.5846457 2.8120079 4.8120079 2.8120079 6 P 0
L 4.5846457 3.9576771 4.8120079 3.9576771 6 P 0
L 4.5898425 4.151063 4.5898425 4.161063 12 P 0
L 4.5898425 4.251063 4.5898425 4.261063 12 P 0
L 4.6398425 4.263063 4.6398425 4.2930533 15 P 0 ;0,1=56,2=0.000000
L 4.6398425 4.2930533 4.6548377 4.2930533 15 P 0 ;0,1=56,2=0.000000
L 4.644685 4.0580709 4.644685 4.0880612 15 P 0 ;0,1=54,2=0.000000
L 4.644685 4.0880612 4.6596802 4.0880612 15 P 0 ;0,1=54,2=0.000000
L 4.6498393 4.2730598 4.659836 4.263063 15 P 0 ;0,1=56,2=0.000000
L 4.6546818 4.0680677 4.6646785 4.0580709 15 P 0 ;0,1=54,2=0.000000
L 4.6548377 4.2730598 4.6398425 4.2730598 15 P 0 ;0,1=56,2=0.000000
L 4.6548377 4.2930533 4.659836 4.2880549 15 P 0 ;0,1=56,2=0.000000
L 4.6596802 4.0680677 4.644685 4.0680677 15 P 0 ;0,1=54,2=0.000000
L 4.6596802 4.0880612 4.6646785 4.0830628 15 P 0 ;0,1=54,2=0.000000
L 4.659836 4.2780582 4.6548377 4.2730598 15 P 0 ;0,1=56,2=0.000000
L 4.659836 4.2880549 4.659836 4.2780582 15 P 0 ;0,1=56,2=0.000000
L 4.6646785 4.0730661 4.6596802 4.0680677 15 P 0 ;0,1=54,2=0.000000
L 4.6646785 4.0830628 4.6646785 4.0730661 15 P 0 ;0,1=54,2=0.000000
L 4.6698328 4.2880549 4.6748312 4.2930533 15 P 0 ;0,1=56,2=0.000000
L 4.6746753 4.0830628 4.6796737 4.0880612 15 P 0 ;0,1=54,2=0.000000
L 4.6748312 4.263063 4.6698328 4.2680614 15 P 0 ;0,1=56,2=0.000000
L 4.6748312 4.2930533 4.684828 4.2930533 15 P 0 ;0,1=56,2=0.000000
L 4.6796737 4.0580709 4.6746753 4.0630693 15 P 0 ;0,1=54,2=0.000000
L 4.6796737 4.0880612 4.6896705 4.0880612 15 P 0 ;0,1=54,2=0.000000
L 4.6798296 4.2780582 4.684828 4.2780582 15 P 0 ;0,1=56,2=0.000000
L 4.6798425 4.101378 4.6798425 4.140748 10 P 0
L 4.6798425 4.186378 4.6798425 4.225748 10 P 0
L 4.6846721 4.0730661 4.6896705 4.0730661 15 P 0 ;0,1=54,2=0.000000
L 4.684828 4.263063 4.6748312 4.263063 15 P 0 ;0,1=56,2=0.000000
L 4.684828 4.2780582 4.6798296 4.2780582 15 P 0 ;0,1=56,2=0.000000
L 4.684828 4.2780582 4.6898263 4.2730598 15 P 0 ;0,1=56,2=0.000000
L 4.684828 4.2930533 4.6898263 4.2880549 15 P 0 ;0,1=56,2=0.000000
L 4.6896705 4.0580709 4.6796737 4.0580709 15 P 0 ;0,1=54,2=0.000000
L 4.6896705 4.0730661 4.6846721 4.0730661 15 P 0 ;0,1=54,2=0.000000
L 4.6896705 4.0730661 4.6946688 4.0680677 15 P 0 ;0,1=54,2=0.000000
L 4.6896705 4.0880612 4.6946688 4.0830628 15 P 0 ;0,1=54,2=0.000000
L 4.6898263 4.2680614 4.684828 4.263063 15 P 0 ;0,1=56,2=0.000000
L 4.6898263 4.2730598 4.6898263 4.2680614 15 P 0 ;0,1=56,2=0.000000
L 4.6898263 4.2830565 4.684828 4.2780582 15 P 0 ;0,1=56,2=0.000000
L 4.6898263 4.2880549 4.6898263 4.2830565 15 P 0 ;0,1=56,2=0.000000
L 4.6946688 4.0630693 4.6896705 4.0580709 15 P 0 ;0,1=54,2=0.000000
L 4.6946688 4.0680677 4.6946688 4.0630693 15 P 0 ;0,1=54,2=0.000000
L 4.6946688 4.0780644 4.6896705 4.0730661 15 P 0 ;0,1=54,2=0.000000
L 4.6946688 4.0830628 4.6946688 4.0780644 15 P 0 ;0,1=54,2=0.000000
L 4.6998231 4.263063 4.7198166 4.2830565 15 P 0 ;0,1=56,2=0.000000
L 4.7046656 4.0730661 4.7246591 4.0730661 15 P 0 ;0,1=54,2=0.000000
L 4.7048215 4.2930533 4.6998231 4.2880549 15 P 0 ;0,1=56,2=0.000000
L 4.7148183 4.2930533 4.7048215 4.2930533 15 P 0 ;0,1=56,2=0.000000
L 4.7196608 4.0580709 4.7196608 4.0880612 15 P 0 ;0,1=54,2=0.000000
L 4.7196608 4.0880612 4.7046656 4.0730661 15 P 0 ;0,1=54,2=0.000000
L 4.7198166 4.263063 4.6998231 4.263063 15 P 0 ;0,1=56,2=0.000000
L 4.7198166 4.2830565 4.7198166 4.2880549 15 P 0 ;0,1=56,2=0.000000
L 4.7198166 4.2880549 4.7148183 4.2930533 15 P 0 ;0,1=56,2=0.000000
L 4.8976378 2.7037401 4.9212598 2.7037401 6 P 0
L 4.9094488 2.6919291 4.9094488 2.7155512 6 P 0
L 4.9318425 4.3170565 4.9368409 4.3120582 15 P 0 ;0,1=51,2=0.000000
L 4.9318425 4.3220549 4.9318425 4.3170565 15 P 0 ;0,1=51,2=0.000000
L 4.9348425 4.151063 4.9348425 4.161063 12 P 0
L 4.9348425 4.151063 5.1148425 4.151063 12 P 0
L 4.9348425 4.251063 4.9348425 4.261063 12 P 0
L 4.9348425 4.261063 5.1148425 4.261063 12 P 0
L 4.9368409 4.297063 4.9318425 4.3020614 15 P 0 ;0,1=51,2=0.000000
L 4.9368409 4.3120582 4.9468377 4.3120582 15 P 0 ;0,1=51,2=0.000000
L 4.9368409 4.3270533 4.9318425 4.3220549 15 P 0 ;0,1=51,2=0.000000
L 4.9468377 4.297063 4.9368409 4.297063 15 P 0 ;0,1=51,2=0.000000
L 4.9468377 4.3120582 4.951836 4.3070598 15 P 0 ;0,1=51,2=0.000000
L 4.9468377 4.3270533 4.9368409 4.3270533 15 P 0 ;0,1=51,2=0.000000
L 4.951836 4.3020614 4.9468377 4.297063 15 P 0 ;0,1=51,2=0.000000
L 4.951836 4.3070598 4.951836 4.3020614 15 P 0 ;0,1=51,2=0.000000
L 4.951836 4.3220549 4.9468377 4.3270533 15 P 0 ;0,1=51,2=0.000000
L 4.9618328 4.3020614 4.9668312 4.297063 15 P 0 ;0,1=51,2=0.000000
L 4.9618328 4.3120582 4.9618328 4.3020614 15 P 0 ;0,1=51,2=0.000000
L 4.9668312 4.297063 4.976828 4.297063 15 P 0 ;0,1=51,2=0.000000
L 4.9718296 4.3220549 4.9618328 4.3120582 15 P 0 ;0,1=51,2=0.000000
L 4.976828 4.297063 4.9818263 4.3020614 15 P 0 ;0,1=51,2=0.000000
L 4.976828 4.3120582 4.9618328 4.3120582 15 P 0 ;0,1=51,2=0.000000
L 4.9818263 4.3020614 4.9818263 4.3070598 15 P 0 ;0,1=51,2=0.000000
L 4.9818263 4.3070598 4.976828 4.3120582 15 P 0 ;0,1=51,2=0.000000
L 4.9818263 4.3270533 4.9718296 4.3220549 15 P 0 ;0,1=51,2=0.000000
L 5.0068897 2.8120079 5.2342519 2.8120079 6 P 0
L 5.0068897 3.9576771 5.2342519 3.9576771 6 P 0
L 5.1013779 4.0944882 5.1013779 4.1244785 15 P 0 ;0,1=53,2=0.000000
L 5.1013779 4.1244785 5.1163731 4.1244785 15 P 0 ;0,1=53,2=0.000000
L 5.1113747 4.104485 5.1213714 4.0944882 15 P 0 ;0,1=53,2=0.000000
L 5.1148425 4.151063 5.1148425 4.161063 12 P 0
L 5.1148425 4.251063 5.1148425 4.261063 12 P 0
L 5.1163731 4.104485 5.1013779 4.104485 15 P 0 ;0,1=53,2=0.000000
L 5.1163731 4.1244785 5.1213714 4.1194801 15 P 0 ;0,1=53,2=0.000000
L 5.1213714 4.1094834 5.1163731 4.104485 15 P 0 ;0,1=53,2=0.000000
L 5.1213714 4.1194801 5.1213714 4.1094834 15 P 0 ;0,1=53,2=0.000000
L 5.1313682 4.1194801 5.1363666 4.1244785 15 P 0 ;0,1=53,2=0.000000
L 5.1363666 4.0944882 5.1313682 4.0994866 15 P 0 ;0,1=53,2=0.000000
L 5.1363666 4.1244785 5.1463634 4.1244785 15 P 0 ;0,1=53,2=0.000000
L 5.141365 4.1094834 5.1463634 4.1094834 15 P 0 ;0,1=53,2=0.000000
L 5.1463634 4.0944882 5.1363666 4.0944882 15 P 0 ;0,1=53,2=0.000000
L 5.1463634 4.1094834 5.141365 4.1094834 15 P 0 ;0,1=53,2=0.000000
L 5.1463634 4.1094834 5.1513617 4.104485 15 P 0 ;0,1=53,2=0.000000
L 5.1463634 4.1244785 5.1513617 4.1194801 15 P 0 ;0,1=53,2=0.000000
L 5.1513617 4.0994866 5.1463634 4.0944882 15 P 0 ;0,1=53,2=0.000000
L 5.1513617 4.104485 5.1513617 4.0994866 15 P 0 ;0,1=53,2=0.000000
L 5.1513617 4.1144817 5.1463634 4.1094834 15 P 0 ;0,1=53,2=0.000000
L 5.1513617 4.1194801 5.1513617 4.1144817 15 P 0 ;0,1=53,2=0.000000
L 5.1613585 4.1094834 5.1713553 4.1144817 15 P 0 ;0,1=53,2=0.000000
L 5.1613585 4.1244785 5.1613585 4.1094834 15 P 0 ;0,1=53,2=0.000000
L 5.1663569 4.0944882 5.1613585 4.0994866 15 P 0 ;0,1=53,2=0.000000
L 5.1713553 4.1144817 5.1763537 4.1144817 15 P 0 ;0,1=53,2=0.000000
L 5.1763537 4.0944882 5.1663569 4.0944882 15 P 0 ;0,1=53,2=0.000000
L 5.1763537 4.1144817 5.181352 4.1094834 15 P 0 ;0,1=53,2=0.000000
L 5.181352 4.0994866 5.1763537 4.0944882 15 P 0 ;0,1=53,2=0.000000
L 5.181352 4.1094834 5.181352 4.0994866 15 P 0 ;0,1=53,2=0.000000
L 5.181352 4.1244785 5.1613585 4.1244785 15 P 0 ;0,1=53,2=0.000000
L 5.1998425 4.263063 5.1998425 4.2930533 15 P 0 ;0,1=55,2=0.000000
L 5.1998425 4.2930533 5.2148377 4.2930533 15 P 0 ;0,1=55,2=0.000000
L 5.2098393 4.2730598 5.219836 4.263063 15 P 0 ;0,1=55,2=0.000000
L 5.2148377 4.2730598 5.1998425 4.2730598 15 P 0 ;0,1=55,2=0.000000
L 5.2148377 4.2930533 5.219836 4.2880549 15 P 0 ;0,1=55,2=0.000000
L 5.219836 4.2780582 5.2148377 4.2730598 15 P 0 ;0,1=55,2=0.000000
L 5.219836 4.2880549 5.219836 4.2780582 15 P 0 ;0,1=55,2=0.000000
L 5.2298328 4.2880549 5.2348312 4.2930533 15 P 0 ;0,1=55,2=0.000000
L 5.2342519 2.8120079 5.2342519 3.9576771 6 P 0
L 5.2348312 4.263063 5.2298328 4.2680614 15 P 0 ;0,1=55,2=0.000000
L 5.2348312 4.2930533 5.244828 4.2930533 15 P 0 ;0,1=55,2=0.000000
L 5.2398296 4.2780582 5.244828 4.2780582 15 P 0 ;0,1=55,2=0.000000
L 5.2398425 4.106378 5.2398425 4.145748 10 P 0
L 5.2398425 4.186378 5.2398425 4.225748 10 P 0
L 5.244828 4.263063 5.2348312 4.263063 15 P 0 ;0,1=55,2=0.000000
L 5.244828 4.2780582 5.2398296 4.2780582 15 P 0 ;0,1=55,2=0.000000
L 5.244828 4.2780582 5.2498263 4.2730598 15 P 0 ;0,1=55,2=0.000000
L 5.244828 4.2930533 5.2498263 4.2880549 15 P 0 ;0,1=55,2=0.000000
L 5.2498263 4.2680614 5.244828 4.263063 15 P 0 ;0,1=55,2=0.000000
L 5.2498263 4.2730598 5.2498263 4.2680614 15 P 0 ;0,1=55,2=0.000000
L 5.2498263 4.2830565 5.244828 4.2780582 15 P 0 ;0,1=55,2=0.000000
L 5.2498263 4.2880549 5.2498263 4.2830565 15 P 0 ;0,1=55,2=0.000000
L 5.2598231 4.2880549 5.2648215 4.2930533 15 P 0 ;0,1=55,2=0.000000
L 5.2648215 4.263063 5.2598231 4.2680614 15 P 0 ;0,1=55,2=0.000000
L 5.2648215 4.2930533 5.2748183 4.2930533 15 P 0 ;0,1=55,2=0.000000
L 5.2698199 4.2780582 5.2748183 4.2780582 15 P 0 ;0,1=55,2=0.000000
L 5.2748183 4.263063 5.2648215 4.263063 15 P 0 ;0,1=55,2=0.000000
L 5.2748183 4.2780582 5.2698199 4.2780582 15 P 0 ;0,1=55,2=0.000000
L 5.2748183 4.2780582 5.2798166 4.2730598 15 P 0 ;0,1=55,2=0.000000
L 5.2748183 4.2930533 5.2798166 4.2880549 15 P 0 ;0,1=55,2=0.000000
L 5.2798166 4.2680614 5.2748183 4.263063 15 P 0 ;0,1=55,2=0.000000
L 5.2798166 4.2730598 5.2798166 4.2680614 15 P 0 ;0,1=55,2=0.000000
L 5.2798166 4.2830565 5.2748183 4.2780582 15 P 0 ;0,1=55,2=0.000000
L 5.2798166 4.2880549 5.2798166 4.2830565 15 P 0 ;0,1=55,2=0.000000
L 5.3917374 3.406989 5.3967358 3.4019907 15 P 0 ;0,1=50,2=0.000000
L 5.3917374 3.4119874 5.3917374 3.406989 15 P 0 ;0,1=50,2=0.000000
L 5.3967213 3.4644882 5.3967213 3.9824818 10 P 0
L 5.3967213 3.4644882 5.8312205 3.4644882 10 P 0
L 5.3967213 3.9824818 5.3967213 4.2244882 10 P 0
L 5.3967213 4.2244882 5.8312205 4.2244882 10 P 0
L 5.3967358 3.3869955 5.3917374 3.3919939 15 P 0 ;0,1=50,2=0.000000
L 5.3967358 3.4019907 5.4067326 3.4019907 15 P 0 ;0,1=50,2=0.000000
L 5.3967358 3.4169858 5.3917374 3.4119874 15 P 0 ;0,1=50,2=0.000000
L 5.4067326 3.3869955 5.3967358 3.3869955 15 P 0 ;0,1=50,2=0.000000
L 5.4067326 3.4019907 5.4117309 3.3969923 15 P 0 ;0,1=50,2=0.000000
L 5.4067326 3.4169858 5.3967358 3.4169858 15 P 0 ;0,1=50,2=0.000000
L 5.4117309 3.3919939 5.4067326 3.3869955 15 P 0 ;0,1=50,2=0.000000
L 5.4117309 3.3969923 5.4117309 3.3919939 15 P 0 ;0,1=50,2=0.000000
L 5.4117309 3.4119874 5.4067326 3.4169858 15 P 0 ;0,1=50,2=0.000000
L 5.4217277 3.3869955 5.4317245 3.3969923 15 P 0 ;0,1=50,2=0.000000
L 5.4217277 3.4169858 5.4217277 3.3869955 15 P 0 ;0,1=50,2=0.000000
L 5.4317245 3.3969923 5.4417212 3.3869955 15 P 0 ;0,1=50,2=0.000000
L 5.4417212 3.3869955 5.4417212 3.4169858 15 P 0 ;0,1=50,2=0.000000
L 5.451718 3.3869955 5.4617148 3.3869955 15 P 0 ;0,1=50,2=0.000000
L 5.4567164 3.3869955 5.4567164 3.4169858 15 P 0 ;0,1=50,2=0.000000
L 5.4567164 3.4169858 5.451718 3.4119874 15 P 0 ;0,1=50,2=0.000000
L 5.4617148 3.3869955 5.4567164 3.3869955 15 P 0 ;0,1=50,2=0.000000
L 5.5227559 0.8574803 5.5227559 2.4574803 6 P 0
L 5.60289 3.2467577 5.6078884 3.2417593 15 P 0 ;0,1=137,2=0.000000
L 5.60289 3.2667512 5.60289 3.2467577 15 P 0 ;0,1=137,2=0.000000
L 5.6078884 3.2417593 5.6178852 3.2417593 15 P 0 ;0,1=137,2=0.000000
L 5.6078884 3.2717496 5.60289 3.2667512 15 P 0 ;0,1=137,2=0.000000
L 5.6178852 3.2417593 5.6228835 3.2467577 15 P 0 ;0,1=137,2=0.000000
L 5.6178852 3.2717496 5.6078884 3.2717496 15 P 0 ;0,1=137,2=0.000000
L 5.6228835 3.2667512 5.6178852 3.2717496 15 P 0 ;0,1=137,2=0.000000
L 5.6328803 3.2417593 5.6528738 3.2617528 15 P 0 ;0,1=137,2=0.000000
L 5.6378787 3.2717496 5.6328803 3.2667512 15 P 0 ;0,1=137,2=0.000000
L 5.6478755 3.2717496 5.6378787 3.2717496 15 P 0 ;0,1=137,2=0.000000
L 5.6526107 2.7195687 5.6576091 2.7145703 15 P 0 ;0,1=43,2=0.000000
L 5.6526107 2.7445606 5.6526107 2.7195687 15 P 0 ;0,1=43,2=0.000000
L 5.6528738 3.2417593 5.6328803 3.2417593 15 P 0 ;0,1=137,2=0.000000
L 5.6528738 3.2617528 5.6528738 3.2667512 15 P 0 ;0,1=137,2=0.000000
L 5.6528738 3.2667512 5.6478755 3.2717496 15 P 0 ;0,1=137,2=0.000000
L 5.6576091 2.7145703 5.6676059 2.7145703 15 P 0 ;0,1=43,2=0.000000
L 5.6676059 2.7145703 5.6726042 2.7195687 15 P 0 ;0,1=43,2=0.000000
L 5.6726042 2.7195687 5.6726042 2.7445606 15 P 0 ;0,1=43,2=0.000000
L 5.682601 2.7145703 5.6925978 2.7145703 15 P 0 ;0,1=43,2=0.000000
L 5.6875994 2.7145703 5.6875994 2.7445606 15 P 0 ;0,1=43,2=0.000000
L 5.6875994 2.7445606 5.682601 2.7395622 15 P 0 ;0,1=43,2=0.000000
L 5.6925978 2.7145703 5.6875994 2.7145703 15 P 0 ;0,1=43,2=0.000000
L 5.7075929 2.7195687 5.7075929 2.7395622 15 P 0 ;0,1=43,2=0.000000
L 5.7075929 2.7395622 5.7125913 2.7445606 15 P 0 ;0,1=43,2=0.000000
L 5.7125913 2.7145703 5.7075929 2.7195687 15 P 0 ;0,1=43,2=0.000000
L 5.7125913 2.7445606 5.7225881 2.7445606 15 P 0 ;0,1=43,2=0.000000
L 5.7225881 2.7145703 5.7125913 2.7145703 15 P 0 ;0,1=43,2=0.000000
L 5.7225881 2.7445606 5.7275864 2.7395622 15 P 0 ;0,1=43,2=0.000000
L 5.7275864 2.7195687 5.7225881 2.7145703 15 P 0 ;0,1=43,2=0.000000
L 5.7275864 2.7395622 5.7275864 2.7195687 15 P 0 ;0,1=43,2=0.000000
L 5.7445845 3.2507262 5.7495829 3.2457278 15 P 0 ;0,1=138,2=0.000000
L 5.7445845 3.2707197 5.7445845 3.2507262 15 P 0 ;0,1=138,2=0.000000
L 5.7465748 3.3232205 5.8065748 3.3232205 10 P 0
L 5.7465748 3.3992205 5.8065748 3.3992205 10 P 0
L 5.7495829 3.2457278 5.7595797 3.2457278 15 P 0 ;0,1=138,2=0.000000
L 5.7495829 3.2757181 5.7445845 3.2707197 15 P 0 ;0,1=138,2=0.000000
L 5.7595797 3.2457278 5.764578 3.2507262 15 P 0 ;0,1=138,2=0.000000
L 5.7595797 3.2757181 5.7495829 3.2757181 15 P 0 ;0,1=138,2=0.000000
L 5.764578 3.2707197 5.7595797 3.2757181 15 P 0 ;0,1=138,2=0.000000
L 5.7745748 3.2457278 5.7845716 3.2457278 15 P 0 ;0,1=138,2=0.000000
L 5.7789398 0.6898312 5.7789398 2.6898312 3 P 0
L 5.7795732 3.2457278 5.7795732 3.2757181 15 P 0 ;0,1=138,2=0.000000
L 5.7795732 3.2757181 5.7745748 3.2707197 15 P 0 ;0,1=138,2=0.000000
L 5.7845716 3.2457278 5.7795732 3.2457278 15 P 0 ;0,1=138,2=0.000000
L 5.8312205 3.4644882 5.8312205 4.2244882 10 P 0
L 5.8988189 3.6636614 5.8988189 3.6685827 6 P 0
L 5.8988189 3.6636614 6.0208661 3.6636614 6 P 0
L 5.8988189 3.7335433 5.8988189 3.7384646 6 P 0
L 5.8988189 3.7384646 6.0208661 3.7384646 6 P 0
L 5.9098425 3.7922834 5.9098425 3.837559 12 P 0
L 5.9098425 3.7922834 6.0194488 3.7922834 12 P 0
L 5.9098425 4.0383464 5.9098425 4.2056693 12 P 0
L 5.9098425 4.2056693 6.3098425 4.2056693 12 P 0
L 5.9738522 1.8695703 5.9938457 1.8695703 15 P 0 ;0,1=79,2=0.000000
L 5.9738522 1.8995606 5.9738522 1.8695703 15 P 0 ;0,1=79,2=0.000000
L 5.9851575 2.366063 6.0245275 2.366063 10 P 0
L 5.986742 2.4616142 5.986742 2.4766094 15 P 0 ;0,1=71,2=90.000000
L 5.986742 2.4766094 5.9917404 2.4816077 15 P 0 ;0,1=71,2=90.000000
L 5.986742 2.4966029 5.9917404 2.4916045 15 P 0 ;0,1=71,2=90.000000
L 5.986742 2.5065997 5.986742 2.4966029 15 P 0 ;0,1=71,2=90.000000
L 5.9917404 2.4816077 6.0017371 2.4816077 15 P 0 ;0,1=71,2=90.000000
L 5.9917404 2.4916045 5.9967388 2.4916045 15 P 0 ;0,1=71,2=90.000000
L 5.9917404 2.511598 5.986742 2.5065997 15 P 0 ;0,1=71,2=90.000000
L 5.9967388 2.4916045 6.0017371 2.4966029 15 P 0 ;0,1=71,2=90.000000
L 6.0017371 2.4816077 6.0067355 2.4766094 15 P 0 ;0,1=71,2=90.000000
L 6.0017371 2.4966029 6.0017371 2.511598 15 P 0 ;0,1=71,2=90.000000
L 6.0038425 1.8695703 6.0138393 1.8695703 15 P 0 ;0,1=79,2=0.000000
L 6.0067355 2.471611 6.0167323 2.4816077 15 P 0 ;0,1=71,2=90.000000
L 6.0067355 2.4766094 6.0067355 2.4616142 15 P 0 ;0,1=71,2=90.000000
L 6.0088409 1.8695703 6.0088409 1.8995606 15 P 0 ;0,1=79,2=0.000000
L 6.0088409 1.8995606 6.0038425 1.8945622 15 P 0 ;0,1=79,2=0.000000
L 6.0117339 2.4916045 6.0167323 2.4966029 15 P 0 ;0,1=71,2=90.000000
L 6.0117339 2.511598 5.9917404 2.511598 15 P 0 ;0,1=71,2=90.000000
L 6.0133546 2.2355687 6.018353 2.2305703 15 P 0 ;0,1=48,2=0.000000
L 6.0133546 2.2605606 6.0133546 2.2355687 15 P 0 ;0,1=48,2=0.000000
L 6.0138393 1.8695703 6.0088409 1.8695703 15 P 0 ;0,1=79,2=0.000000
L 6.0167323 2.4616142 5.986742 2.4616142 15 P 0 ;0,1=71,2=90.000000
L 6.0167323 2.4966029 6.0167323 2.5065997 15 P 0 ;0,1=71,2=90.000000
L 6.0167323 2.5065997 6.0117339 2.511598 15 P 0 ;0,1=71,2=90.000000
L 6.018353 2.2305703 6.0283498 2.2305703 15 P 0 ;0,1=48,2=0.000000
L 6.0208661 3.6636614 6.0208661 3.6685827 6 P 0
L 6.0208661 3.7335433 6.0208661 3.7384646 6 P 0
L 6.0283498 2.2305703 6.0333481 2.2355687 15 P 0 ;0,1=48,2=0.000000
L 6.0333481 2.2355687 6.0333481 2.2605606 15 P 0 ;0,1=48,2=0.000000
L 6.0433449 2.2305703 6.0633384 2.2505638 15 P 0 ;0,1=48,2=0.000000
L 6.0467813 2.4242897 6.0517797 2.4192913 15 P 0 ;0,1=117,2=90.000000
L 6.0467813 2.4342865 6.0467813 2.4242897 15 P 0 ;0,1=117,2=90.000000
L 6.0467813 2.45428 6.0517797 2.4492816 15 P 0 ;0,1=117,2=90.000000
L 6.0467813 2.4642768 6.0467813 2.45428 15 P 0 ;0,1=117,2=90.000000
L 6.0467813 2.4842703 6.0517797 2.4792719 15 P 0 ;0,1=117,2=90.000000
L 6.0467813 2.4942671 6.0467813 2.4842703 15 P 0 ;0,1=117,2=90.000000
L 6.0483433 2.2605606 6.0433449 2.2555622 15 P 0 ;0,1=48,2=0.000000
L 6.0517797 2.4192913 6.0717732 2.4192913 15 P 0 ;0,1=117,2=90.000000
L 6.0517797 2.4392848 6.0467813 2.4342865 15 P 0 ;0,1=117,2=90.000000
L 6.0517797 2.4692751 6.0467813 2.4642768 15 P 0 ;0,1=117,2=90.000000
L 6.0517797 2.4992654 6.0467813 2.4942671 15 P 0 ;0,1=117,2=90.000000
L 6.0567781 2.4692751 6.0517797 2.4692751 15 P 0 ;0,1=117,2=90.000000
L 6.0567781 2.4992654 6.0517797 2.4992654 15 P 0 ;0,1=117,2=90.000000
L 6.0583401 2.2605606 6.0483433 2.2605606 15 P 0 ;0,1=48,2=0.000000
L 6.0628425 3.536378 6.0628425 3.575748 10 P 0
L 6.0633384 2.2305703 6.0433449 2.2305703 15 P 0 ;0,1=48,2=0.000000
L 6.0633384 2.2505638 6.0633384 2.2555622 15 P 0 ;0,1=48,2=0.000000
L 6.0633384 2.2555622 6.0583401 2.2605606 15 P 0 ;0,1=48,2=0.000000
L 6.067874 1.3880315 6.067874 1.9140945 3 P 0
L 6.067874 1.3880315 6.571811 1.3880315 3 P 0
L 6.067874 1.9140945 6.571811 1.9140945 3 P 0
L 6.0698522 3.6595703 6.0848474 3.6595703 15 P 0 ;0,1=103,2=0.000000
L 6.0698522 3.6895606 6.0698522 3.6595703 15 P 0 ;0,1=103,2=0.000000
L 6.0717732 2.4192913 6.0767716 2.4242897 15 P 0 ;0,1=117,2=90.000000
L 6.0767716 2.4242897 6.0767716 2.4342865 15 P 0 ;0,1=117,2=90.000000
L 6.0767716 2.4342865 6.0717732 2.4392848 15 P 0 ;0,1=117,2=90.000000
L 6.0767716 2.4492816 6.0567781 2.4692751 15 P 0 ;0,1=117,2=90.000000
L 6.0767716 2.4692751 6.0767716 2.4492816 15 P 0 ;0,1=117,2=90.000000
L 6.0767716 2.4792719 6.0567781 2.4992654 15 P 0 ;0,1=117,2=90.000000
L 6.0767716 2.4992654 6.0767716 2.4792719 15 P 0 ;0,1=117,2=90.000000
L 6.0816929 2.0935811 6.0866913 2.0885827 15 P 0 ;0,1=118,2=0.000000
L 6.0816929 2.1135746 6.0816929 2.0935811 15 P 0 ;0,1=118,2=0.000000
L 6.0848474 3.6595703 6.0898457 3.6645687 15 P 0 ;0,1=103,2=0.000000
L 6.0848474 3.6895606 6.0698522 3.6895606 15 P 0 ;0,1=103,2=0.000000
L 6.0866913 2.0885827 6.0966881 2.0885827 15 P 0 ;0,1=118,2=0.000000
L 6.0866913 2.118573 6.0816929 2.1135746 15 P 0 ;0,1=118,2=0.000000
L 6.0898457 3.6645687 6.0898457 3.6845622 15 P 0 ;0,1=103,2=0.000000
L 6.0898457 3.6845622 6.0848474 3.6895606 15 P 0 ;0,1=103,2=0.000000
L 6.0966881 2.0885827 6.1016864 2.0935811 15 P 0 ;0,1=118,2=0.000000
L 6.0966881 2.118573 6.0866913 2.118573 15 P 0 ;0,1=118,2=0.000000
L 6.0998425 2.143063 6.1498425 2.143063 10 P 0
L 6.0998425 2.199063 6.1498425 2.199063 10 P 0
L 6.0998425 3.6595703 6.1098393 3.6595703 15 P 0 ;0,1=103,2=0.000000
L 6.1016864 2.1135746 6.0966881 2.118573 15 P 0 ;0,1=118,2=0.000000
L 6.1031575 2.461063 6.1425275 2.461063 10 P 0
L 6.1048409 3.6595703 6.1048409 3.6895606 15 P 0 ;0,1=103,2=0.000000
L 6.1048409 3.6895606 6.0998425 3.6845622 15 P 0 ;0,1=103,2=0.000000
L 6.1048522 2.5255906 6.1048522 2.5405858 15 P 0 ;0,1=39,2=90.000000
L 6.1048522 2.5405858 6.1098506 2.5455841 15 P 0 ;0,1=39,2=90.000000
L 6.1048522 2.5555809 6.1198473 2.5555809 15 P 0 ;0,1=39,2=90.000000
L 6.1048522 2.5755744 6.1048522 2.5555809 15 P 0 ;0,1=39,2=90.000000
L 6.1098393 3.6595703 6.1048409 3.6595703 15 P 0 ;0,1=103,2=0.000000
L 6.1098506 2.5455841 6.1198473 2.5455841 15 P 0 ;0,1=39,2=90.000000
L 6.1116832 2.0885827 6.1316767 2.1085762 15 P 0 ;0,1=118,2=0.000000
L 6.114849 2.5655777 6.114849 2.5705761 15 P 0 ;0,1=39,2=90.000000
L 6.114849 2.5705761 6.1198473 2.5755744 15 P 0 ;0,1=39,2=90.000000
L 6.1166816 2.118573 6.1116832 2.1135746 15 P 0 ;0,1=118,2=0.000000
L 6.1198473 2.5455841 6.1248457 2.5405858 15 P 0 ;0,1=39,2=90.000000
L 6.1198473 2.5555809 6.114849 2.5655777 15 P 0 ;0,1=39,2=90.000000
L 6.1198473 2.5755744 6.1298441 2.5755744 15 P 0 ;0,1=39,2=90.000000
L 6.1218522 3.4195655 6.1218522 3.4045703 15 P 0 ;0,1=85,2=0.000000
L 6.1218522 3.4195655 6.131849 3.4195655 15 P 0 ;0,1=85,2=0.000000
L 6.1218522 3.4345606 6.1218522 3.4195655 15 P 0 ;0,1=85,2=0.000000
L 6.1248457 2.5355874 6.1348425 2.5455841 15 P 0 ;0,1=39,2=90.000000
L 6.1248457 2.5405858 6.1248457 2.5255906 15 P 0 ;0,1=39,2=90.000000
L 6.1266784 2.118573 6.1166816 2.118573 15 P 0 ;0,1=118,2=0.000000
L 6.1298441 2.5755744 6.1348425 2.5705761 15 P 0 ;0,1=39,2=90.000000
L 6.1316767 2.0885827 6.1116832 2.0885827 15 P 0 ;0,1=118,2=0.000000
L 6.1316767 2.1085762 6.1316767 2.1135746 15 P 0 ;0,1=118,2=0.000000
L 6.1316767 2.1135746 6.1266784 2.118573 15 P 0 ;0,1=118,2=0.000000
L 6.131849 3.4195655 6.1218522 3.4195655 15 P 0 ;0,1=85,2=0.000000
L 6.1348425 2.5255906 6.1048522 2.5255906 15 P 0 ;0,1=39,2=90.000000
L 6.1348425 2.5605793 6.1298441 2.5555809 15 P 0 ;0,1=39,2=90.000000
L 6.1348425 2.5705761 6.1348425 2.5605793 15 P 0 ;0,1=39,2=90.000000
L 6.1416735 2.0885827 6.1516703 2.0885827 15 P 0 ;0,1=118,2=0.000000
L 6.1418457 3.4345606 6.1218522 3.4345606 15 P 0 ;0,1=85,2=0.000000
L 6.1466719 2.0885827 6.1466719 2.118573 15 P 0 ;0,1=118,2=0.000000
L 6.1466719 2.118573 6.1416735 2.1135746 15 P 0 ;0,1=118,2=0.000000
L 6.1516703 2.0885827 6.1466719 2.0885827 15 P 0 ;0,1=118,2=0.000000
L 6.1518425 3.4045703 6.1618393 3.4045703 15 P 0 ;0,1=85,2=0.000000
L 6.1568409 3.4045703 6.1568409 3.4345606 15 P 0 ;0,1=85,2=0.000000
L 6.1568409 3.4345606 6.1518425 3.4295622 15 P 0 ;0,1=85,2=0.000000
L 6.1618393 3.4045703 6.1568409 3.4045703 15 P 0 ;0,1=85,2=0.000000
L 6.1747341 2.8888567 6.1797325 2.8838583 15 P 0 ;0,1=132,2=90.000000
L 6.1747341 2.8988535 6.1747341 2.8888567 15 P 0 ;0,1=132,2=90.000000
L 6.1747341 2.9138486 6.1747341 2.9338421 15 P 0 ;0,1=132,2=90.000000
L 6.1747341 2.9338421 6.1797325 2.9338421 15 P 0 ;0,1=132,2=90.000000
L 6.1761023 2.2176378 6.3887008 2.2176378 11 P 0
L 6.1761023 2.4144882 6.3335827 2.4144882 11 P 0
L 6.1771653 2.5325575 6.1821637 2.5275591 15 P 0 ;0,1=129,2=0.000000
L 6.1771653 2.552551 6.1771653 2.5325575 15 P 0 ;0,1=129,2=0.000000
L 6.1781496 2.5817701 6.183148 2.5767717 15 P 0 ;0,1=128,2=0.000000
L 6.1781496 2.6017636 6.1781496 2.5817701 15 P 0 ;0,1=128,2=0.000000
L 6.1791338 2.6309827 6.1841322 2.6259843 15 P 0 ;0,1=127,2=0.000000
L 6.1791338 2.6509762 6.1791338 2.6309827 15 P 0 ;0,1=127,2=0.000000
L 6.1791338 2.6821638 6.1841322 2.6771654 15 P 0 ;0,1=130,2=0.000000
L 6.1791338 2.7021573 6.1791338 2.6821638 15 P 0 ;0,1=130,2=0.000000
L 6.1797325 2.8838583 6.199726 2.8838583 15 P 0 ;0,1=132,2=90.000000
L 6.1797325 2.9038518 6.1747341 2.8988535 15 P 0 ;0,1=132,2=90.000000
L 6.1797325 2.9338421 6.199726 2.9138486 15 P 0 ;0,1=132,2=90.000000
L 6.1821637 2.5275591 6.1921605 2.5275591 15 P 0 ;0,1=129,2=0.000000
L 6.1821637 2.5575494 6.1771653 2.552551 15 P 0 ;0,1=129,2=0.000000
L 6.1830708 2.4409449 6.1830708 2.4709352 15 P 0 ;0,1=73,2=0.000000
L 6.1830708 2.4709352 6.198066 2.4709352 15 P 0 ;0,1=73,2=0.000000
L 6.183148 2.5767717 6.1931448 2.5767717 15 P 0 ;0,1=128,2=0.000000
L 6.183148 2.606762 6.1781496 2.6017636 15 P 0 ;0,1=128,2=0.000000
L 6.1841322 2.6259843 6.194129 2.6259843 15 P 0 ;0,1=127,2=0.000000
L 6.1841322 2.6559746 6.1791338 2.6509762 15 P 0 ;0,1=127,2=0.000000
L 6.1841322 2.6771654 6.194129 2.6771654 15 P 0 ;0,1=130,2=0.000000
L 6.1841322 2.7071557 6.1791338 2.7021573 15 P 0 ;0,1=130,2=0.000000
L 6.1921605 2.5275591 6.1971588 2.5325575 15 P 0 ;0,1=129,2=0.000000
L 6.1921605 2.5575494 6.1821637 2.5575494 15 P 0 ;0,1=129,2=0.000000
L 6.1930676 2.4509417 6.2030643 2.4409449 15 P 0 ;0,1=73,2=0.000000
L 6.1931448 2.5767717 6.1981431 2.5817701 15 P 0 ;0,1=128,2=0.000000
L 6.1931448 2.606762 6.183148 2.606762 15 P 0 ;0,1=128,2=0.000000
L 6.194129 2.6259843 6.1991273 2.6309827 15 P 0 ;0,1=127,2=0.000000
L 6.194129 2.6559746 6.1841322 2.6559746 15 P 0 ;0,1=127,2=0.000000
L 6.194129 2.6771654 6.1991273 2.6821638 15 P 0 ;0,1=130,2=0.000000
L 6.194129 2.7071557 6.1841322 2.7071557 15 P 0 ;0,1=130,2=0.000000
L 6.1971588 2.552551 6.1921605 2.5575494 15 P 0 ;0,1=129,2=0.000000
L 6.198066 2.4509417 6.1830708 2.4509417 15 P 0 ;0,1=73,2=0.000000
L 6.198066 2.4709352 6.2030643 2.4659368 15 P 0 ;0,1=73,2=0.000000
L 6.1981431 2.6017636 6.1931448 2.606762 15 P 0 ;0,1=128,2=0.000000
L 6.1991273 2.6509762 6.194129 2.6559746 15 P 0 ;0,1=127,2=0.000000
L 6.1991273 2.7021573 6.194129 2.7071557 15 P 0 ;0,1=130,2=0.000000
L 6.199726 2.8838583 6.2047244 2.8888567 15 P 0 ;0,1=132,2=90.000000
L 6.199726 2.9138486 6.2047244 2.9138486 15 P 0 ;0,1=132,2=90.000000
L 6.2030643 2.4559401 6.198066 2.4509417 15 P 0 ;0,1=73,2=0.000000
L 6.2030643 2.4659368 6.2030643 2.4559401 15 P 0 ;0,1=73,2=0.000000
L 6.2047244 2.8888567 6.2047244 2.8988535 15 P 0 ;0,1=132,2=90.000000
L 6.2047244 2.8988535 6.199726 2.9038518 15 P 0 ;0,1=132,2=90.000000
L 6.2063546 3.4505703 6.2213498 3.4505703 15 P 0 ;0,1=102,2=0.000000
L 6.2063546 3.4805606 6.2063546 3.4505703 15 P 0 ;0,1=102,2=0.000000
L 6.2071556 2.5275591 6.2171524 2.5275591 15 P 0 ;0,1=129,2=0.000000
L 6.2081399 2.5767717 6.2181367 2.5767717 15 P 0 ;0,1=128,2=0.000000
L 6.2088189 3.6636614 6.2088189 3.6685827 6 P 0
L 6.2088189 3.6636614 6.3308661 3.6636614 6 P 0
L 6.2088189 3.7335433 6.2088189 3.7384646 6 P 0
L 6.2088189 3.7384646 6.3308661 3.7384646 6 P 0
L 6.2091241 2.6259843 6.2191209 2.6259843 15 P 0 ;0,1=127,2=0.000000
L 6.2091241 2.6821638 6.2141225 2.6771654 15 P 0 ;0,1=130,2=0.000000
L 6.2091241 2.6971589 6.2141225 2.6921606 15 P 0 ;0,1=130,2=0.000000
L 6.2091241 2.7021573 6.2091241 2.6971589 15 P 0 ;0,1=130,2=0.000000
L 6.2096456 2.0580709 6.2096456 2.0880612 15 P 0 ;0,1=76,2=0.000000
L 6.2096456 2.0880612 6.2246408 2.0880612 15 P 0 ;0,1=76,2=0.000000
L 6.212154 2.5275591 6.212154 2.5575494 15 P 0 ;0,1=129,2=0.000000
L 6.212154 2.5575494 6.2071556 2.552551 15 P 0 ;0,1=129,2=0.000000
L 6.2130611 2.4459433 6.2130611 2.4409449 15 P 0 ;0,1=73,2=0.000000
L 6.2130611 2.4709352 6.2330546 2.4709352 15 P 0 ;0,1=73,2=0.000000
L 6.2131383 2.5767717 6.2131383 2.606762 15 P 0 ;0,1=128,2=0.000000
L 6.2131383 2.606762 6.2081399 2.6017636 15 P 0 ;0,1=128,2=0.000000
L 6.2138189 3.5286614 6.2138189 3.5335827 6 P 0
L 6.2138189 3.5286614 6.3358661 3.5286614 6 P 0
L 6.2138189 3.5985433 6.2138189 3.6034646 6 P 0
L 6.2138189 3.6034646 6.3358661 3.6034646 6 P 0
L 6.2141225 2.6259843 6.2141225 2.6559746 15 P 0 ;0,1=127,2=0.000000
L 6.2141225 2.6559746 6.2091241 2.6509762 15 P 0 ;0,1=127,2=0.000000
L 6.2141225 2.6771654 6.2241193 2.6771654 15 P 0 ;0,1=130,2=0.000000
L 6.2141225 2.6921606 6.2291176 2.6921606 15 P 0 ;0,1=130,2=0.000000
L 6.2141225 2.7071557 6.2091241 2.7021573 15 P 0 ;0,1=130,2=0.000000
L 6.2151575 2.156063 6.2545275 2.156063 10 P 0
L 6.215937 2.7613386 6.215937 2.8213386 10 P 0
L 6.2171524 2.5275591 6.212154 2.5275591 15 P 0 ;0,1=129,2=0.000000
L 6.2181367 2.5767717 6.2131383 2.5767717 15 P 0 ;0,1=128,2=0.000000
L 6.2191209 2.6259843 6.2141225 2.6259843 15 P 0 ;0,1=127,2=0.000000
L 6.2196424 2.0680677 6.2296391 2.0580709 15 P 0 ;0,1=76,2=0.000000
L 6.2213498 3.4505703 6.2263481 3.4555687 15 P 0 ;0,1=102,2=0.000000
L 6.2213498 3.4805606 6.2063546 3.4805606 15 P 0 ;0,1=102,2=0.000000
L 6.2241193 2.6771654 6.2291176 2.6821638 15 P 0 ;0,1=130,2=0.000000
L 6.2241193 2.7071557 6.2141225 2.7071557 15 P 0 ;0,1=130,2=0.000000
L 6.2241732 3.7922834 6.3098425 3.7922834 12 P 0
L 6.2246408 2.0680677 6.2096456 2.0680677 15 P 0 ;0,1=76,2=0.000000
L 6.2246408 2.0880612 6.2296391 2.0830628 15 P 0 ;0,1=76,2=0.000000
L 6.2263481 3.4555687 6.2263481 3.4755622 15 P 0 ;0,1=102,2=0.000000
L 6.2263481 3.4755622 6.2213498 3.4805606 15 P 0 ;0,1=102,2=0.000000
L 6.2291176 2.6821638 6.2291176 2.7021573 15 P 0 ;0,1=130,2=0.000000
L 6.2291176 2.7021573 6.2241193 2.7071557 15 P 0 ;0,1=130,2=0.000000
L 6.2296391 2.0730661 6.2246408 2.0680677 15 P 0 ;0,1=76,2=0.000000
L 6.2296391 2.0830628 6.2296391 2.0730661 15 P 0 ;0,1=76,2=0.000000
L 6.2321475 2.5325575 6.2321475 2.552551 15 P 0 ;0,1=129,2=0.000000
L 6.2321475 2.552551 6.2371459 2.5575494 15 P 0 ;0,1=129,2=0.000000
L 6.2330546 2.4659368 6.2130611 2.4459433 15 P 0 ;0,1=73,2=0.000000
L 6.2330546 2.4709352 6.2330546 2.4659368 15 P 0 ;0,1=73,2=0.000000
L 6.2331318 2.5767717 6.2431286 2.5767717 15 P 0 ;0,1=128,2=0.000000
L 6.234116 2.6259843 6.2541095 2.6459778 15 P 0 ;0,1=127,2=0.000000
L 6.2363449 3.4505703 6.2563384 3.4705638 15 P 0 ;0,1=102,2=0.000000
L 6.2371459 2.5275591 6.2321475 2.5325575 15 P 0 ;0,1=129,2=0.000000
L 6.2371459 2.5575494 6.2471427 2.5575494 15 P 0 ;0,1=129,2=0.000000
L 6.2381302 2.5767717 6.2381302 2.606762 15 P 0 ;0,1=128,2=0.000000
L 6.2381302 2.606762 6.2331318 2.6017636 15 P 0 ;0,1=128,2=0.000000
L 6.2391144 2.6559746 6.234116 2.6509762 15 P 0 ;0,1=127,2=0.000000
L 6.2396359 2.0830628 6.2446343 2.0880612 15 P 0 ;0,1=76,2=0.000000
L 6.2413433 3.4805606 6.2363449 3.4755622 15 P 0 ;0,1=102,2=0.000000
L 6.2431286 2.5767717 6.2381302 2.5767717 15 P 0 ;0,1=128,2=0.000000
L 6.2446343 2.0580709 6.2396359 2.0630693 15 P 0 ;0,1=76,2=0.000000
L 6.2446343 2.0880612 6.2546311 2.0880612 15 P 0 ;0,1=76,2=0.000000
L 6.2471427 2.5275591 6.2371459 2.5275591 15 P 0 ;0,1=129,2=0.000000
L 6.2471427 2.5575494 6.252141 2.552551 15 P 0 ;0,1=129,2=0.000000
L 6.2491112 2.6559746 6.2391144 2.6559746 15 P 0 ;0,1=127,2=0.000000
L 6.2496327 2.0730661 6.2546311 2.0730661 15 P 0 ;0,1=76,2=0.000000
L 6.2513401 3.4805606 6.2413433 3.4805606 15 P 0 ;0,1=102,2=0.000000
L 6.252141 2.5325575 6.2471427 2.5275591 15 P 0 ;0,1=129,2=0.000000
L 6.252141 2.552551 6.252141 2.5325575 15 P 0 ;0,1=129,2=0.000000
L 6.2541095 2.6259843 6.234116 2.6259843 15 P 0 ;0,1=127,2=0.000000
L 6.2541095 2.6459778 6.2541095 2.6509762 15 P 0 ;0,1=127,2=0.000000
L 6.2541095 2.6509762 6.2491112 2.6559746 15 P 0 ;0,1=127,2=0.000000
L 6.2546311 2.0580709 6.2446343 2.0580709 15 P 0 ;0,1=76,2=0.000000
L 6.2546311 2.0730661 6.2496327 2.0730661 15 P 0 ;0,1=76,2=0.000000
L 6.2546311 2.0730661 6.2596294 2.0680677 15 P 0 ;0,1=76,2=0.000000
L 6.2546311 2.0880612 6.2596294 2.0830628 15 P 0 ;0,1=76,2=0.000000
L 6.2563384 3.4505703 6.2363449 3.4505703 15 P 0 ;0,1=102,2=0.000000
L 6.2563384 3.4705638 6.2563384 3.4755622 15 P 0 ;0,1=102,2=0.000000
L 6.2563384 3.4755622 6.2513401 3.4805606 15 P 0 ;0,1=102,2=0.000000
L 6.2596294 2.0630693 6.2546311 2.0580709 15 P 0 ;0,1=76,2=0.000000
L 6.2596294 2.0680677 6.2596294 2.0630693 15 P 0 ;0,1=76,2=0.000000
L 6.2596294 2.0780644 6.2546311 2.0730661 15 P 0 ;0,1=76,2=0.000000
L 6.2596294 2.0830628 6.2596294 2.0780644 15 P 0 ;0,1=76,2=0.000000
L 6.2698619 3.0485687 6.2748603 3.0435703 15 P 0 ;0,1=114,2=0.000000
L 6.2698619 3.0685622 6.2698619 3.0485687 15 P 0 ;0,1=114,2=0.000000
L 6.2748603 3.0435703 6.2848571 3.0435703 15 P 0 ;0,1=114,2=0.000000
L 6.2748603 3.0735606 6.2698619 3.0685622 15 P 0 ;0,1=114,2=0.000000
L 6.2848571 3.0435703 6.2898554 3.0485687 15 P 0 ;0,1=114,2=0.000000
L 6.2848571 3.0735606 6.2748603 3.0735606 15 P 0 ;0,1=114,2=0.000000
L 6.2898554 3.0685622 6.2848571 3.0735606 15 P 0 ;0,1=114,2=0.000000
L 6.291937 2.7613386 6.291937 2.8213386 10 P 0
L 6.2968425 2.116063 6.2968425 2.176063 10 P 0
L 6.2998522 3.0585655 6.309849 3.0635638 15 P 0 ;0,1=114,2=0.000000
L 6.2998522 3.0735606 6.2998522 3.0585655 15 P 0 ;0,1=114,2=0.000000
L 6.3048506 3.0435703 6.2998522 3.0485687 15 P 0 ;0,1=114,2=0.000000
L 6.3061023 2.0374787 6.3111007 2.0324803 15 P 0 ;0,1=134,2=0.000000
L 6.3061023 2.0574722 6.3061023 2.0374787 15 P 0 ;0,1=134,2=0.000000
L 6.3076081 2.8859039 6.3126065 2.8809055 15 P 0 ;0,1=131,2=90.000000
L 6.3076081 2.8959007 6.3076081 2.8859039 15 P 0 ;0,1=131,2=90.000000
L 6.3076081 2.9158942 6.3076081 2.925891 15 P 0 ;0,1=131,2=90.000000
L 6.3076081 2.925891 6.3126065 2.9308893 15 P 0 ;0,1=131,2=90.000000
L 6.3098425 3.7922834 6.3098425 4.2056693 12 P 0
L 6.309849 3.0635638 6.3148474 3.0635638 15 P 0 ;0,1=114,2=0.000000
L 6.3111007 2.0324803 6.3210975 2.0324803 15 P 0 ;0,1=134,2=0.000000
L 6.3111007 2.0624706 6.3061023 2.0574722 15 P 0 ;0,1=134,2=0.000000
L 6.3126065 2.8809055 6.3326 2.8809055 15 P 0 ;0,1=131,2=90.000000
L 6.3126065 2.900899 6.3076081 2.8959007 15 P 0 ;0,1=131,2=90.000000
L 6.3126065 2.9108958 6.3076081 2.9158942 15 P 0 ;0,1=131,2=90.000000
L 6.3126065 2.9308893 6.3176049 2.9308893 15 P 0 ;0,1=131,2=90.000000
L 6.3148474 3.0435703 6.3048506 3.0435703 15 P 0 ;0,1=114,2=0.000000
L 6.3148474 3.0635638 6.3198457 3.0585655 15 P 0 ;0,1=114,2=0.000000
L 6.3176049 2.9108958 6.3126065 2.9108958 15 P 0 ;0,1=131,2=90.000000
L 6.3176049 2.9308893 6.3226032 2.925891 15 P 0 ;0,1=131,2=90.000000
L 6.3198457 3.0485687 6.3148474 3.0435703 15 P 0 ;0,1=114,2=0.000000
L 6.3198457 3.0585655 6.3198457 3.0485687 15 P 0 ;0,1=114,2=0.000000
L 6.3198457 3.0735606 6.2998522 3.0735606 15 P 0 ;0,1=114,2=0.000000
L 6.3210975 2.0324803 6.3260958 2.0374787 15 P 0 ;0,1=134,2=0.000000
L 6.3210975 2.0624706 6.3111007 2.0624706 15 P 0 ;0,1=134,2=0.000000
L 6.3226032 2.9158942 6.3176049 2.9108958 15 P 0 ;0,1=131,2=90.000000
L 6.3226032 2.9158942 6.3226032 2.925891 15 P 0 ;0,1=131,2=90.000000
L 6.3226032 2.925891 6.3276016 2.9308893 15 P 0 ;0,1=131,2=90.000000
L 6.3260958 2.0574722 6.3210975 2.0624706 15 P 0 ;0,1=134,2=0.000000
L 6.3276016 2.9108958 6.3226032 2.9158942 15 P 0 ;0,1=131,2=90.000000
L 6.3276016 2.9308893 6.3326 2.9308893 15 P 0 ;0,1=131,2=90.000000
L 6.3298425 3.0485687 6.3348409 3.0435703 15 P 0 ;0,1=114,2=0.000000
L 6.3298425 3.0585655 6.3298425 3.0485687 15 P 0 ;0,1=114,2=0.000000
L 6.3308661 3.6636614 6.3308661 3.6685827 6 P 0
L 6.3308661 3.7335433 6.3308661 3.7384646 6 P 0
L 6.3326 2.8809055 6.3375984 2.8859039 15 P 0 ;0,1=131,2=90.000000
L 6.3326 2.9108958 6.3276016 2.9108958 15 P 0 ;0,1=131,2=90.000000
L 6.3326 2.9308893 6.3375984 2.925891 15 P 0 ;0,1=131,2=90.000000
L 6.3340472 2.7613386 6.3340472 2.8213386 10 P 0
L 6.3348409 3.0435703 6.3448377 3.0435703 15 P 0 ;0,1=114,2=0.000000
L 6.3358661 3.5286614 6.3358661 3.5335827 6 P 0
L 6.3358661 3.5985433 6.3358661 3.6034646 6 P 0
L 6.3360926 2.0474755 6.3460894 2.0524738 15 P 0 ;0,1=134,2=0.000000
L 6.3360926 2.0624706 6.3360926 2.0474755 15 P 0 ;0,1=134,2=0.000000
L 6.3368506 4.1585703 6.3318522 4.1635687 15 P 0 ;0,1=82,2=0.000000
L 6.3375984 2.8859039 6.3375984 2.8959007 15 P 0 ;0,1=131,2=90.000000
L 6.3375984 2.8959007 6.3326 2.900899 15 P 0 ;0,1=131,2=90.000000
L 6.3375984 2.9158942 6.3326 2.9108958 15 P 0 ;0,1=131,2=90.000000
L 6.3375984 2.925891 6.3375984 2.9158942 15 P 0 ;0,1=131,2=90.000000
L 6.3398393 3.0685622 6.3298425 3.0585655 15 P 0 ;0,1=114,2=0.000000
L 6.3398425 2.431378 6.3398425 2.470748 10 P 0
L 6.341091 2.0324803 6.3360926 2.0374787 15 P 0 ;0,1=134,2=0.000000
L 6.3413546 3.7585703 6.3563498 3.7585703 15 P 0 ;0,1=101,2=0.000000
L 6.3413546 3.7885606 6.3413546 3.7585703 15 P 0 ;0,1=101,2=0.000000
L 6.341849 4.1585703 6.3368506 4.1585703 15 P 0 ;0,1=82,2=0.000000
L 6.341849 4.1885606 6.3468474 4.1885606 15 P 0 ;0,1=82,2=0.000000
L 6.3448377 3.0435703 6.349836 3.0485687 15 P 0 ;0,1=114,2=0.000000
L 6.3448377 3.0585655 6.3298425 3.0585655 15 P 0 ;0,1=114,2=0.000000
L 6.3460894 2.0524738 6.3510878 2.0524738 15 P 0 ;0,1=134,2=0.000000
L 6.3468474 4.1635687 6.341849 4.1585703 15 P 0 ;0,1=82,2=0.000000
L 6.3468474 4.1885606 6.3468474 4.1635687 15 P 0 ;0,1=82,2=0.000000
L 6.349836 3.0485687 6.349836 3.0535671 15 P 0 ;0,1=114,2=0.000000
L 6.349836 3.0535671 6.3448377 3.0585655 15 P 0 ;0,1=114,2=0.000000
L 6.349836 3.0735606 6.3398393 3.0685622 15 P 0 ;0,1=114,2=0.000000
L 6.3510878 2.0324803 6.341091 2.0324803 15 P 0 ;0,1=134,2=0.000000
L 6.3510878 2.0524738 6.3560861 2.0474755 15 P 0 ;0,1=134,2=0.000000
L 6.3518457 4.1885606 6.341849 4.1885606 15 P 0 ;0,1=82,2=0.000000
L 6.3560861 2.0374787 6.3510878 2.0324803 15 P 0 ;0,1=134,2=0.000000
L 6.3560861 2.0474755 6.3560861 2.0374787 15 P 0 ;0,1=134,2=0.000000
L 6.3560861 2.0624706 6.3360926 2.0624706 15 P 0 ;0,1=134,2=0.000000
L 6.3563498 3.7585703 6.3613481 3.7635687 15 P 0 ;0,1=101,2=0.000000
L 6.3563498 3.7885606 6.3413546 3.7885606 15 P 0 ;0,1=101,2=0.000000
L 6.3613481 3.7635687 6.3613481 3.7835622 15 P 0 ;0,1=101,2=0.000000
L 6.3613481 3.7835622 6.3563498 3.7885606 15 P 0 ;0,1=101,2=0.000000
L 6.3618425 4.1585703 6.3718393 4.1585703 15 P 0 ;0,1=82,2=0.000000
L 6.3648425 3.131063 6.3648425 3.351063 3 P 0
L 6.3648425 3.131063 6.5346456 3.131063 3 P 0
L 6.3648425 3.351063 6.5346456 3.351063 3 P 0
L 6.3668409 4.1585703 6.3668409 4.1885606 15 P 0 ;0,1=82,2=0.000000
L 6.3668409 4.1885606 6.3618425 4.1835622 15 P 0 ;0,1=82,2=0.000000
L 6.3688425 3.3900614 6.3738409 3.385063 15 P 0 ;0,1=45,2=0.000000
L 6.3688425 3.4150533 6.3688425 3.3900614 15 P 0 ;0,1=45,2=0.000000
L 6.3713449 3.7835622 6.3763433 3.7885606 15 P 0 ;0,1=101,2=0.000000
L 6.3718393 4.1585703 6.3668409 4.1585703 15 P 0 ;0,1=82,2=0.000000
L 6.3728425 2.116063 6.3728425 2.176063 10 P 0
L 6.3738409 3.385063 6.3838377 3.385063 15 P 0 ;0,1=45,2=0.000000
L 6.3763433 3.7585703 6.3713449 3.7635687 15 P 0 ;0,1=101,2=0.000000
L 6.3763433 3.7885606 6.3863401 3.7885606 15 P 0 ;0,1=101,2=0.000000
L 6.3813417 3.7735655 6.3863401 3.7735655 15 P 0 ;0,1=101,2=0.000000
L 6.3838377 3.385063 6.388836 3.3900614 15 P 0 ;0,1=45,2=0.000000
L 6.3863401 3.7585703 6.3763433 3.7585703 15 P 0 ;0,1=101,2=0.000000
L 6.3863401 3.7735655 6.3813417 3.7735655 15 P 0 ;0,1=101,2=0.000000
L 6.3863401 3.7735655 6.3913384 3.7685671 15 P 0 ;0,1=101,2=0.000000
L 6.3863401 3.7885606 6.3913384 3.7835622 15 P 0 ;0,1=101,2=0.000000
L 6.388836 3.3900614 6.388836 3.4150533 15 P 0 ;0,1=45,2=0.000000
L 6.3913384 3.7635687 6.3863401 3.7585703 15 P 0 ;0,1=101,2=0.000000
L 6.3913384 3.7685671 6.3913384 3.7635687 15 P 0 ;0,1=101,2=0.000000
L 6.3913384 3.7785638 6.3863401 3.7735655 15 P 0 ;0,1=101,2=0.000000
L 6.3913384 3.7835622 6.3913384 3.7785638 15 P 0 ;0,1=101,2=0.000000
L 6.3988328 3.3900614 6.3988328 3.3950598 15 P 0 ;0,1=45,2=0.000000
L 6.3988328 3.3950598 6.4038312 3.4000582 15 P 0 ;0,1=45,2=0.000000
L 6.3988328 3.4050565 6.3988328 3.4100549 15 P 0 ;0,1=45,2=0.000000
L 6.3988328 3.4100549 6.4038312 3.4150533 15 P 0 ;0,1=45,2=0.000000
L 6.4038312 3.385063 6.3988328 3.3900614 15 P 0 ;0,1=45,2=0.000000
L 6.4038312 3.4000582 6.3988328 3.4050565 15 P 0 ;0,1=45,2=0.000000
L 6.4038312 3.4000582 6.413828 3.4000582 15 P 0 ;0,1=45,2=0.000000
L 6.4038312 3.4150533 6.413828 3.4150533 15 P 0 ;0,1=45,2=0.000000
L 6.4100472 2.7613386 6.4100472 2.8213386 10 P 0
L 6.413828 3.385063 6.4038312 3.385063 15 P 0 ;0,1=45,2=0.000000
L 6.413828 3.4000582 6.4188263 3.3950598 15 P 0 ;0,1=45,2=0.000000
L 6.413828 3.4150533 6.4188263 3.4100549 15 P 0 ;0,1=45,2=0.000000
L 6.4188263 3.3900614 6.413828 3.385063 15 P 0 ;0,1=45,2=0.000000
L 6.4188263 3.3950598 6.4188263 3.3900614 15 P 0 ;0,1=45,2=0.000000
L 6.4188263 3.4050565 6.413828 3.4000582 15 P 0 ;0,1=45,2=0.000000
L 6.4188263 3.4100549 6.4188263 3.4050565 15 P 0 ;0,1=45,2=0.000000
L 6.427874 2.3480315 6.427874 2.8740945 3 P 0
L 6.427874 2.3480315 6.931811 2.3480315 3 P 0
L 6.427874 2.8740945 6.931811 2.8740945 3 P 0
L 6.4418425 2.246063 6.4418425 2.296063 10 P 0
L 6.4444882 3.5295276 6.4444882 4.3569484 12 P 0
L 6.4444882 3.5295276 7.0035442 3.5295276 12 P 0
L 6.4448425 3.033063 6.5048425 3.033063 10 P 0
L 6.4448425 3.109063 6.5048425 3.109063 10 P 0
L 6.4562302 2.151652 6.4612286 2.1466536 15 P 0 ;0,1=136,2=90.000000
L 6.4562302 2.1616488 6.4562302 2.151652 15 P 0 ;0,1=136,2=90.000000
L 6.4562302 2.1816423 6.4562302 2.1916391 15 P 0 ;0,1=136,2=90.000000
L 6.4562302 2.1916391 6.4612286 2.1966374 15 P 0 ;0,1=136,2=90.000000
L 6.4612286 2.1466536 6.4812221 2.1466536 15 P 0 ;0,1=136,2=90.000000
L 6.4612286 2.1666471 6.4562302 2.1616488 15 P 0 ;0,1=136,2=90.000000
L 6.4612286 2.1766439 6.4562302 2.1816423 15 P 0 ;0,1=136,2=90.000000
L 6.4612286 2.1966374 6.466227 2.1966374 15 P 0 ;0,1=136,2=90.000000
L 6.466227 2.1966374 6.4712253 2.1916391 15 P 0 ;0,1=136,2=90.000000
L 6.4712253 2.1866407 6.4712253 2.1916391 15 P 0 ;0,1=136,2=90.000000
L 6.4712253 2.1916391 6.4712253 2.1866407 15 P 0 ;0,1=136,2=90.000000
L 6.4712253 2.1916391 6.4762237 2.1966374 15 P 0 ;0,1=136,2=90.000000
L 6.4762237 2.1966374 6.4812221 2.1966374 15 P 0 ;0,1=136,2=90.000000
L 6.4812221 2.1466536 6.4862205 2.151652 15 P 0 ;0,1=136,2=90.000000
L 6.4812221 2.1966374 6.4862205 2.1916391 15 P 0 ;0,1=136,2=90.000000
L 6.4862205 2.151652 6.4862205 2.1616488 15 P 0 ;0,1=136,2=90.000000
L 6.4862205 2.1616488 6.4812221 2.1666471 15 P 0 ;0,1=136,2=90.000000
L 6.4862205 2.1816423 6.4812221 2.1766439 15 P 0 ;0,1=136,2=90.000000
L 6.4862205 2.1916391 6.4862205 2.1816423 15 P 0 ;0,1=136,2=90.000000
L 6.4918425 1.961063 6.4918425 2.011063 10 P 0
L 6.4978425 2.246063 6.4978425 2.296063 10 P 0
L 6.5005215 2.0709433 6.5055199 2.0659449 15 P 0 ;0,1=135,2=90.000000
L 6.5005215 2.0809401 6.5005215 2.0709433 15 P 0 ;0,1=135,2=90.000000
L 6.5005215 2.1109304 6.5155166 2.0959352 15 P 0 ;0,1=135,2=90.000000
L 6.5055199 2.0659449 6.5255134 2.0659449 15 P 0 ;0,1=135,2=90.000000
L 6.5055199 2.0859384 6.5005215 2.0809401 15 P 0 ;0,1=135,2=90.000000
L 6.5155166 2.0959352 6.5155166 2.1159287 15 P 0 ;0,1=135,2=90.000000
L 6.5255134 2.0659449 6.5305118 2.0709433 15 P 0 ;0,1=135,2=90.000000
L 6.5305118 2.0709433 6.5305118 2.0809401 15 P 0 ;0,1=135,2=90.000000
L 6.5305118 2.0809401 6.5255134 2.0859384 15 P 0 ;0,1=135,2=90.000000
L 6.5305118 2.1109304 6.5005215 2.1109304 15 P 0 ;0,1=135,2=90.000000
L 6.5346456 3.131063 6.5346456 3.351063 3 P 0
L 6.5478425 1.961063 6.5478425 2.011063 10 P 0
L 6.5610236 2.0817701 6.566022 2.0767717 15 P 0 ;0,1=49,2=0.000000
L 6.5610236 2.106762 6.5610236 2.0817701 15 P 0 ;0,1=49,2=0.000000
L 6.566022 2.0767717 6.5760188 2.0767717 15 P 0 ;0,1=49,2=0.000000
L 6.571811 1.3880315 6.571811 1.9140945 3 P 0
L 6.5748619 2.9625687 6.5798603 2.9575703 15 P 0 ;0,1=113,2=0.000000
L 6.5748619 2.9825622 6.5748619 2.9625687 15 P 0 ;0,1=113,2=0.000000
L 6.5760188 2.0767717 6.5810171 2.0817701 15 P 0 ;0,1=49,2=0.000000
L 6.5768425 3.136063 6.5768425 3.186063 10 P 0
L 6.5768425 3.271063 6.5768425 3.321063 10 P 0
L 6.5798603 2.9575703 6.5898571 2.9575703 15 P 0 ;0,1=113,2=0.000000
L 6.5798603 2.9875606 6.5748619 2.9825622 15 P 0 ;0,1=113,2=0.000000
L 6.5810171 2.0817701 6.5810171 2.106762 15 P 0 ;0,1=49,2=0.000000
L 6.5858619 3.3795687 6.5908603 3.3745703 15 P 0 ;0,1=32,2=0.000000
L 6.5858619 3.3995622 6.5858619 3.3795687 15 P 0 ;0,1=32,2=0.000000
L 6.5898571 2.9575703 6.5948554 2.9625687 15 P 0 ;0,1=113,2=0.000000
L 6.5898571 2.9875606 6.5798603 2.9875606 15 P 0 ;0,1=113,2=0.000000
L 6.5908603 3.3745703 6.6008571 3.3745703 15 P 0 ;0,1=32,2=0.000000
L 6.5908603 3.4045606 6.5858619 3.3995622 15 P 0 ;0,1=32,2=0.000000
L 6.5910139 2.0767717 6.6010107 2.0767717 15 P 0 ;0,1=49,2=0.000000
L 6.5948554 2.9825622 6.5898571 2.9875606 15 P 0 ;0,1=113,2=0.000000
L 6.5960123 2.0767717 6.5960123 2.106762 15 P 0 ;0,1=49,2=0.000000
L 6.5960123 2.106762 6.5910139 2.1017636 15 P 0 ;0,1=49,2=0.000000
L 6.6008571 3.3745703 6.6058554 3.3795687 15 P 0 ;0,1=32,2=0.000000
L 6.6008571 3.4045606 6.5908603 3.4045606 15 P 0 ;0,1=32,2=0.000000
L 6.6009842 2.0544882 6.8135827 2.0544882 11 P 0
L 6.6010107 2.0767717 6.5960123 2.0767717 15 P 0 ;0,1=49,2=0.000000
L 6.6048522 2.9725655 6.614849 2.9775638 15 P 0 ;0,1=113,2=0.000000
L 6.6048522 2.9875606 6.6048522 2.9725655 15 P 0 ;0,1=113,2=0.000000
L 6.6058554 3.3995622 6.6008571 3.4045606 15 P 0 ;0,1=32,2=0.000000
L 6.6098506 2.9575703 6.6048522 2.9625687 15 P 0 ;0,1=113,2=0.000000
L 6.614849 2.9775638 6.6198474 2.9775638 15 P 0 ;0,1=113,2=0.000000
L 6.6158522 3.3795687 6.6158522 3.3845671 15 P 0 ;0,1=32,2=0.000000
L 6.6158522 3.3845671 6.6208506 3.3895655 15 P 0 ;0,1=32,2=0.000000
L 6.6158522 3.3945638 6.6158522 3.3995622 15 P 0 ;0,1=32,2=0.000000
L 6.6158522 3.3995622 6.6208506 3.4045606 15 P 0 ;0,1=32,2=0.000000
L 6.6198474 2.9575703 6.6098506 2.9575703 15 P 0 ;0,1=113,2=0.000000
L 6.6198474 2.9775638 6.6248457 2.9725655 15 P 0 ;0,1=113,2=0.000000
L 6.6208506 3.3745703 6.6158522 3.3795687 15 P 0 ;0,1=32,2=0.000000
L 6.6208506 3.3895655 6.6158522 3.3945638 15 P 0 ;0,1=32,2=0.000000
L 6.6208506 3.3895655 6.6308474 3.3895655 15 P 0 ;0,1=32,2=0.000000
L 6.6208506 3.4045606 6.6308474 3.4045606 15 P 0 ;0,1=32,2=0.000000
L 6.621063 1.8070866 6.621063 1.8370769 15 P 0 ;0,1=74,2=0.000000
L 6.621063 1.8370769 6.6360582 1.8370769 15 P 0 ;0,1=74,2=0.000000
L 6.6218425 2.101063 6.6218425 2.161063 10 P 0
L 6.6248457 2.9625687 6.6198474 2.9575703 15 P 0 ;0,1=113,2=0.000000
L 6.6248457 2.9725655 6.6248457 2.9625687 15 P 0 ;0,1=113,2=0.000000
L 6.6248457 2.9875606 6.6048522 2.9875606 15 P 0 ;0,1=113,2=0.000000
L 6.6308474 3.3745703 6.6208506 3.3745703 15 P 0 ;0,1=32,2=0.000000
L 6.6308474 3.3895655 6.6358457 3.3845671 15 P 0 ;0,1=32,2=0.000000
L 6.6308474 3.4045606 6.6358457 3.3995622 15 P 0 ;0,1=32,2=0.000000
L 6.6310598 1.8170834 6.6410565 1.8070866 15 P 0 ;0,1=74,2=0.000000
L 6.6328425 3.136063 6.6328425 3.186063 10 P 0
L 6.6328425 3.271063 6.6328425 3.321063 10 P 0
L 6.6348425 1.383063 6.6948425 1.383063 10 P 0
L 6.6348425 1.459063 6.6948425 1.459063 10 P 0
L 6.6348425 1.493063 6.6948425 1.493063 10 P 0
L 6.6348425 1.569063 6.6948425 1.569063 10 P 0
L 6.6348425 2.9625687 6.6348425 2.9575703 15 P 0 ;0,1=113,2=0.000000
L 6.6348425 2.9875606 6.654836 2.9875606 15 P 0 ;0,1=113,2=0.000000
L 6.6348619 3.0565687 6.6398603 3.0515703 15 P 0 ;0,1=31,2=0.000000
L 6.6348619 3.0765622 6.6348619 3.0565687 15 P 0 ;0,1=31,2=0.000000
L 6.6358457 3.3795687 6.6308474 3.3745703 15 P 0 ;0,1=32,2=0.000000
L 6.6358457 3.3845671 6.6358457 3.3795687 15 P 0 ;0,1=32,2=0.000000
L 6.6358457 3.3945638 6.6308474 3.3895655 15 P 0 ;0,1=32,2=0.000000
L 6.6358457 3.3995622 6.6358457 3.3945638 15 P 0 ;0,1=32,2=0.000000
L 6.6360582 1.8170834 6.621063 1.8170834 15 P 0 ;0,1=74,2=0.000000
L 6.6360582 1.8370769 6.6410565 1.8320785 15 P 0 ;0,1=74,2=0.000000
L 6.6398603 3.0515703 6.6498571 3.0515703 15 P 0 ;0,1=31,2=0.000000
L 6.6398603 3.0815606 6.6348619 3.0765622 15 P 0 ;0,1=31,2=0.000000
L 6.6410565 1.8220818 6.6360582 1.8170834 15 P 0 ;0,1=74,2=0.000000
L 6.6410565 1.8320785 6.6410565 1.8220818 15 P 0 ;0,1=74,2=0.000000
L 6.6452065 2.2166126 6.6502049 2.2116142 15 P 0 ;0,1=133,2=90.000000
L 6.6452065 2.2266094 6.6452065 2.2166126 15 P 0 ;0,1=133,2=90.000000
L 6.6452065 2.261598 6.6502049 2.2516013 15 P 0 ;0,1=133,2=90.000000
L 6.6458425 3.3795687 6.6508409 3.3745703 15 P 0 ;0,1=32,2=0.000000
L 6.6458425 3.3895655 6.6458425 3.3795687 15 P 0 ;0,1=32,2=0.000000
L 6.6498571 3.0515703 6.6548554 3.0565687 15 P 0 ;0,1=31,2=0.000000
L 6.6498571 3.0815606 6.6398603 3.0815606 15 P 0 ;0,1=31,2=0.000000
L 6.6502049 2.2116142 6.6701984 2.2116142 15 P 0 ;0,1=133,2=90.000000
L 6.6502049 2.2316077 6.6452065 2.2266094 15 P 0 ;0,1=133,2=90.000000
L 6.6502049 2.2516013 6.6602016 2.2416045 15 P 0 ;0,1=133,2=90.000000
L 6.6508409 3.3745703 6.6608377 3.3745703 15 P 0 ;0,1=32,2=0.000000
L 6.6510533 1.812085 6.6560517 1.8070866 15 P 0 ;0,1=74,2=0.000000
L 6.6510533 1.8220818 6.6510533 1.812085 15 P 0 ;0,1=74,2=0.000000
L 6.654836 2.9825622 6.6348425 2.9625687 15 P 0 ;0,1=113,2=0.000000
L 6.654836 2.9875606 6.654836 2.9825622 15 P 0 ;0,1=113,2=0.000000
L 6.6548554 3.0765622 6.6498571 3.0815606 15 P 0 ;0,1=31,2=0.000000
L 6.6558393 3.3995622 6.6458425 3.3895655 15 P 0 ;0,1=32,2=0.000000
L 6.6560517 1.8070866 6.6660485 1.8070866 15 P 0 ;0,1=74,2=0.000000
L 6.6561023 1.8576378 6.8135827 1.8576378 11 P 0
L 6.6598425 3.156063 6.6598425 3.306063 10 P 0
L 6.6598425 3.156063 6.6748425 3.156063 10 P 0
L 6.6598425 3.306063 6.6748425 3.306063 10 P 0
L 6.6602016 2.2416045 6.6701984 2.2416045 15 P 0 ;0,1=133,2=90.000000
L 6.6602016 2.2565997 6.6602016 2.2416045 15 P 0 ;0,1=133,2=90.000000
L 6.6608377 3.3745703 6.665836 3.3795687 15 P 0 ;0,1=32,2=0.000000
L 6.6608377 3.3895655 6.6458425 3.3895655 15 P 0 ;0,1=32,2=0.000000
L 6.6610501 1.8320785 6.6510533 1.8220818 15 P 0 ;0,1=74,2=0.000000
L 6.6648522 3.0565687 6.6648522 3.0615671 15 P 0 ;0,1=31,2=0.000000
L 6.6648522 3.0615671 6.6698506 3.0665655 15 P 0 ;0,1=31,2=0.000000
L 6.6648522 3.0715638 6.6648522 3.0765622 15 P 0 ;0,1=31,2=0.000000
L 6.6648522 3.0765622 6.6698506 3.0815606 15 P 0 ;0,1=31,2=0.000000
L 6.6652 2.261598 6.6602016 2.2565997 15 P 0 ;0,1=133,2=90.000000
L 6.665836 3.3795687 6.665836 3.3845671 15 P 0 ;0,1=32,2=0.000000
L 6.665836 3.3845671 6.6608377 3.3895655 15 P 0 ;0,1=32,2=0.000000
L 6.665836 3.4045606 6.6558393 3.3995622 15 P 0 ;0,1=32,2=0.000000
L 6.6660485 1.8070866 6.6710468 1.812085 15 P 0 ;0,1=74,2=0.000000
L 6.6660485 1.8220818 6.6510533 1.8220818 15 P 0 ;0,1=74,2=0.000000
L 6.6698506 3.0515703 6.6648522 3.0565687 15 P 0 ;0,1=31,2=0.000000
L 6.6698506 3.0665655 6.6648522 3.0715638 15 P 0 ;0,1=31,2=0.000000
L 6.6698506 3.0665655 6.6798474 3.0665655 15 P 0 ;0,1=31,2=0.000000
L 6.6698506 3.0815606 6.6798474 3.0815606 15 P 0 ;0,1=31,2=0.000000
L 6.6701984 2.2116142 6.6751968 2.2166126 15 P 0 ;0,1=133,2=90.000000
L 6.6701984 2.2416045 6.6751968 2.2466029 15 P 0 ;0,1=133,2=90.000000
L 6.6701984 2.261598 6.6652 2.261598 15 P 0 ;0,1=133,2=90.000000
L 6.6710468 1.812085 6.6710468 1.8170834 15 P 0 ;0,1=74,2=0.000000
L 6.6710468 1.8170834 6.6660485 1.8220818 15 P 0 ;0,1=74,2=0.000000
L 6.6710468 1.8370769 6.6610501 1.8320785 15 P 0 ;0,1=74,2=0.000000
L 6.6751968 2.2166126 6.6751968 2.2266094 15 P 0 ;0,1=133,2=90.000000
L 6.6751968 2.2266094 6.6701984 2.2316077 15 P 0 ;0,1=133,2=90.000000
L 6.6751968 2.2466029 6.6751968 2.2565997 15 P 0 ;0,1=133,2=90.000000
L 6.6751968 2.2565997 6.6701984 2.261598 15 P 0 ;0,1=133,2=90.000000
L 6.6798474 3.0515703 6.6698506 3.0515703 15 P 0 ;0,1=31,2=0.000000
L 6.6798474 3.0665655 6.6848457 3.0615671 15 P 0 ;0,1=31,2=0.000000
L 6.6798474 3.0815606 6.6848457 3.0765622 15 P 0 ;0,1=31,2=0.000000
L 6.6848425 3.181063 6.6848425 3.281063 10 P 0
L 6.6848457 3.0565687 6.6798474 3.0515703 15 P 0 ;0,1=31,2=0.000000
L 6.6848457 3.0615671 6.6848457 3.0565687 15 P 0 ;0,1=31,2=0.000000
L 6.6848457 3.0715638 6.6798474 3.0665655 15 P 0 ;0,1=31,2=0.000000
L 6.6848457 3.0765622 6.6848457 3.0715638 15 P 0 ;0,1=31,2=0.000000
L 6.6948425 3.0665655 6.7048393 3.0715638 15 P 0 ;0,1=31,2=0.000000
L 6.6948425 3.0815606 6.6948425 3.0665655 15 P 0 ;0,1=31,2=0.000000
L 6.6978425 2.101063 6.6978425 2.161063 10 P 0
L 6.6998409 3.0515703 6.6948425 3.0565687 15 P 0 ;0,1=31,2=0.000000
L 6.7048393 3.0715638 6.7098377 3.0715638 15 P 0 ;0,1=31,2=0.000000
L 6.7076107 1.6085687 6.7126091 1.6035703 15 P 0 ;0,1=123,2=0.000000
L 6.7076107 1.6285622 6.7076107 1.6085687 15 P 0 ;0,1=123,2=0.000000
L 6.7076107 1.7385687 6.7126091 1.7335703 15 P 0 ;0,1=121,2=0.000000
L 6.7076107 1.7585622 6.7076107 1.7385687 15 P 0 ;0,1=121,2=0.000000
L 6.7086107 1.6735687 6.7136091 1.6685703 15 P 0 ;0,1=122,2=0.000000
L 6.7086107 1.6935622 6.7086107 1.6735687 15 P 0 ;0,1=122,2=0.000000
L 6.7098377 3.0515703 6.6998409 3.0515703 15 P 0 ;0,1=31,2=0.000000
L 6.7098377 3.0715638 6.714836 3.0665655 15 P 0 ;0,1=31,2=0.000000
L 6.7126091 1.6035703 6.7226059 1.6035703 15 P 0 ;0,1=123,2=0.000000
L 6.7126091 1.6335606 6.7076107 1.6285622 15 P 0 ;0,1=123,2=0.000000
L 6.7126091 1.7335703 6.7226059 1.7335703 15 P 0 ;0,1=121,2=0.000000
L 6.7126091 1.7635606 6.7076107 1.7585622 15 P 0 ;0,1=121,2=0.000000
L 6.7136091 1.6685703 6.7236059 1.6685703 15 P 0 ;0,1=122,2=0.000000
L 6.7136091 1.6985606 6.7086107 1.6935622 15 P 0 ;0,1=122,2=0.000000
L 6.714836 3.0565687 6.7098377 3.0515703 15 P 0 ;0,1=31,2=0.000000
L 6.714836 3.0665655 6.714836 3.0565687 15 P 0 ;0,1=31,2=0.000000
L 6.714836 3.0815606 6.6948425 3.0815606 15 P 0 ;0,1=31,2=0.000000
L 6.7226059 1.6035703 6.7276042 1.6085687 15 P 0 ;0,1=123,2=0.000000
L 6.7226059 1.6335606 6.7126091 1.6335606 15 P 0 ;0,1=123,2=0.000000
L 6.7226059 1.7335703 6.7276042 1.7385687 15 P 0 ;0,1=121,2=0.000000
L 6.7226059 1.7635606 6.7126091 1.7635606 15 P 0 ;0,1=121,2=0.000000
L 6.7236059 1.6685703 6.7286042 1.6735687 15 P 0 ;0,1=122,2=0.000000
L 6.7236059 1.6985606 6.7136091 1.6985606 15 P 0 ;0,1=122,2=0.000000
L 6.7276042 1.6285622 6.7226059 1.6335606 15 P 0 ;0,1=123,2=0.000000
L 6.7276042 1.7585622 6.7226059 1.7635606 15 P 0 ;0,1=121,2=0.000000
L 6.7286042 1.6935622 6.7236059 1.6985606 15 P 0 ;0,1=122,2=0.000000
L 6.7301575 2.116063 6.7695275 2.116063 10 P 0
L 6.736742 2.1742126 6.736742 2.1892078 15 P 0 ;0,1=77,2=90.000000
L 6.736742 2.1892078 6.7417404 2.1942061 15 P 0 ;0,1=77,2=90.000000
L 6.736742 2.2092013 6.7417404 2.2042029 15 P 0 ;0,1=77,2=90.000000
L 6.736742 2.2191981 6.736742 2.2092013 15 P 0 ;0,1=77,2=90.000000
L 6.737601 1.6035703 6.7475978 1.6035703 15 P 0 ;0,1=123,2=0.000000
L 6.737601 1.7335703 6.7475978 1.7335703 15 P 0 ;0,1=121,2=0.000000
L 6.738601 1.6685703 6.7485978 1.6685703 15 P 0 ;0,1=122,2=0.000000
L 6.7416107 1.4025687 6.7466091 1.3975703 15 P 0 ;0,1=126,2=0.000000
L 6.7416107 1.4225622 6.7416107 1.4025687 15 P 0 ;0,1=126,2=0.000000
L 6.7416107 1.5425687 6.7466091 1.5375703 15 P 0 ;0,1=124,2=0.000000
L 6.7416107 1.5625622 6.7416107 1.5425687 15 P 0 ;0,1=124,2=0.000000
L 6.7417404 2.1942061 6.7517371 2.1942061 15 P 0 ;0,1=77,2=90.000000
L 6.7417404 2.2241964 6.736742 2.2191981 15 P 0 ;0,1=77,2=90.000000
L 6.7425994 1.6035703 6.7425994 1.6335606 15 P 0 ;0,1=123,2=0.000000
L 6.7425994 1.6335606 6.737601 1.6285622 15 P 0 ;0,1=123,2=0.000000
L 6.7425994 1.7335703 6.7425994 1.7635606 15 P 0 ;0,1=121,2=0.000000
L 6.7425994 1.7635606 6.737601 1.7585622 15 P 0 ;0,1=121,2=0.000000
L 6.7426107 1.4765687 6.7476091 1.4715703 15 P 0 ;0,1=125,2=0.000000
L 6.7426107 1.4965622 6.7426107 1.4765687 15 P 0 ;0,1=125,2=0.000000
L 6.7435994 1.6685703 6.7435994 1.6985606 15 P 0 ;0,1=122,2=0.000000
L 6.7435994 1.6985606 6.738601 1.6935622 15 P 0 ;0,1=122,2=0.000000
L 6.7466091 1.3975703 6.7566059 1.3975703 15 P 0 ;0,1=126,2=0.000000
L 6.7466091 1.4275606 6.7416107 1.4225622 15 P 0 ;0,1=126,2=0.000000
L 6.7466091 1.5375703 6.7566059 1.5375703 15 P 0 ;0,1=124,2=0.000000
L 6.7466091 1.5675606 6.7416107 1.5625622 15 P 0 ;0,1=124,2=0.000000
L 6.7467388 2.2241964 6.7417404 2.2241964 15 P 0 ;0,1=77,2=90.000000
L 6.7475978 1.6035703 6.7425994 1.6035703 15 P 0 ;0,1=123,2=0.000000
L 6.7475978 1.7335703 6.7425994 1.7335703 15 P 0 ;0,1=121,2=0.000000
L 6.7476091 1.4715703 6.7576059 1.4715703 15 P 0 ;0,1=125,2=0.000000
L 6.7476091 1.5015606 6.7426107 1.4965622 15 P 0 ;0,1=125,2=0.000000
L 6.7485978 1.6685703 6.7435994 1.6685703 15 P 0 ;0,1=122,2=0.000000
L 6.7517371 2.1942061 6.7567355 2.1892078 15 P 0 ;0,1=77,2=90.000000
L 6.7548425 1.796378 6.7548425 1.835748 10 P 0
L 6.7566059 1.3975703 6.7616042 1.4025687 15 P 0 ;0,1=126,2=0.000000
L 6.7566059 1.4275606 6.7466091 1.4275606 15 P 0 ;0,1=126,2=0.000000
L 6.7566059 1.5375703 6.7616042 1.5425687 15 P 0 ;0,1=124,2=0.000000
L 6.7566059 1.5675606 6.7466091 1.5675606 15 P 0 ;0,1=124,2=0.000000
L 6.7567355 2.1842094 6.7667323 2.1942061 15 P 0 ;0,1=77,2=90.000000
L 6.7567355 2.1892078 6.7567355 2.1742126 15 P 0 ;0,1=77,2=90.000000
L 6.7576059 1.4715703 6.7626042 1.4765687 15 P 0 ;0,1=125,2=0.000000
L 6.7576059 1.5015606 6.7476091 1.5015606 15 P 0 ;0,1=125,2=0.000000
L 6.7616042 1.4225622 6.7566059 1.4275606 15 P 0 ;0,1=126,2=0.000000
L 6.7616042 1.5625622 6.7566059 1.5675606 15 P 0 ;0,1=124,2=0.000000
L 6.7625929 1.6085687 6.7675913 1.6035703 15 P 0 ;0,1=123,2=0.000000
L 6.7625929 1.6185655 6.7625929 1.6085687 15 P 0 ;0,1=123,2=0.000000
L 6.7625929 1.7385687 6.7625929 1.7435671 15 P 0 ;0,1=121,2=0.000000
L 6.7625929 1.7435671 6.7675913 1.7485655 15 P 0 ;0,1=121,2=0.000000
L 6.7625929 1.7535638 6.7625929 1.7585622 15 P 0 ;0,1=121,2=0.000000
L 6.7625929 1.7585622 6.7675913 1.7635606 15 P 0 ;0,1=121,2=0.000000
L 6.7626042 1.4965622 6.7576059 1.5015606 15 P 0 ;0,1=125,2=0.000000
L 6.7635929 1.6735687 6.7635929 1.6685703 15 P 0 ;0,1=122,2=0.000000
L 6.7635929 1.6985606 6.7835864 1.6985606 15 P 0 ;0,1=122,2=0.000000
L 6.7667323 2.1742126 6.736742 2.1742126 15 P 0 ;0,1=77,2=90.000000
L 6.7667323 2.2042029 6.7467388 2.2241964 15 P 0 ;0,1=77,2=90.000000
L 6.7667323 2.2241964 6.7667323 2.2042029 15 P 0 ;0,1=77,2=90.000000
L 6.7675913 1.6035703 6.7775881 1.6035703 15 P 0 ;0,1=123,2=0.000000
L 6.7675913 1.7335703 6.7625929 1.7385687 15 P 0 ;0,1=121,2=0.000000
L 6.7675913 1.7485655 6.7625929 1.7535638 15 P 0 ;0,1=121,2=0.000000
L 6.7675913 1.7485655 6.7775881 1.7485655 15 P 0 ;0,1=121,2=0.000000
L 6.7675913 1.7635606 6.7775881 1.7635606 15 P 0 ;0,1=121,2=0.000000
L 6.771601 1.3975703 6.7815978 1.3975703 15 P 0 ;0,1=126,2=0.000000
L 6.771601 1.5375703 6.7815978 1.5375703 15 P 0 ;0,1=124,2=0.000000
L 6.7725897 1.6285622 6.7625929 1.6185655 15 P 0 ;0,1=123,2=0.000000
L 6.772601 1.4715703 6.7825978 1.4715703 15 P 0 ;0,1=125,2=0.000000
L 6.7765994 1.3975703 6.7765994 1.4275606 15 P 0 ;0,1=126,2=0.000000
L 6.7765994 1.4275606 6.771601 1.4225622 15 P 0 ;0,1=126,2=0.000000
L 6.7765994 1.5375703 6.7765994 1.5675606 15 P 0 ;0,1=124,2=0.000000
L 6.7765994 1.5675606 6.771601 1.5625622 15 P 0 ;0,1=124,2=0.000000
L 6.7775881 1.6035703 6.7825864 1.6085687 15 P 0 ;0,1=123,2=0.000000
L 6.7775881 1.6185655 6.7625929 1.6185655 15 P 0 ;0,1=123,2=0.000000
L 6.7775881 1.7335703 6.7675913 1.7335703 15 P 0 ;0,1=121,2=0.000000
L 6.7775881 1.7485655 6.7825864 1.7435671 15 P 0 ;0,1=121,2=0.000000
L 6.7775881 1.7635606 6.7825864 1.7585622 15 P 0 ;0,1=121,2=0.000000
L 6.7775994 1.4715703 6.7775994 1.5015606 15 P 0 ;0,1=125,2=0.000000
L 6.7775994 1.5015606 6.772601 1.4965622 15 P 0 ;0,1=125,2=0.000000
L 6.7798425 3.156063 6.8898425 3.156063 10 P 0
L 6.7798425 3.306063 6.8898425 3.306063 10 P 0
L 6.7815978 1.3975703 6.7765994 1.3975703 15 P 0 ;0,1=126,2=0.000000
L 6.7815978 1.5375703 6.7765994 1.5375703 15 P 0 ;0,1=124,2=0.000000
L 6.7825864 1.6085687 6.7825864 1.6135671 15 P 0 ;0,1=123,2=0.000000
L 6.7825864 1.6135671 6.7775881 1.6185655 15 P 0 ;0,1=123,2=0.000000
L 6.7825864 1.6335606 6.7725897 1.6285622 15 P 0 ;0,1=123,2=0.000000
L 6.7825864 1.7385687 6.7775881 1.7335703 15 P 0 ;0,1=121,2=0.000000
L 6.7825864 1.7435671 6.7825864 1.7385687 15 P 0 ;0,1=121,2=0.000000
L 6.7825864 1.7535638 6.7775881 1.7485655 15 P 0 ;0,1=121,2=0.000000
L 6.7825864 1.7585622 6.7825864 1.7535638 15 P 0 ;0,1=121,2=0.000000
L 6.7825978 1.4715703 6.7775994 1.4715703 15 P 0 ;0,1=125,2=0.000000
L 6.7835864 1.6935622 6.7635929 1.6735687 15 P 0 ;0,1=122,2=0.000000
L 6.7835864 1.6985606 6.7835864 1.6935622 15 P 0 ;0,1=122,2=0.000000
L 6.7965929 1.4225622 6.8015913 1.4275606 15 P 0 ;0,1=126,2=0.000000
L 6.7965929 1.5525655 6.8065897 1.5575638 15 P 0 ;0,1=124,2=0.000000
L 6.7965929 1.5675606 6.7965929 1.5525655 15 P 0 ;0,1=124,2=0.000000
L 6.7975929 1.4865655 6.8175864 1.4865655 15 P 0 ;0,1=125,2=0.000000
L 6.8015913 1.3975703 6.7965929 1.4025687 15 P 0 ;0,1=126,2=0.000000
L 6.8015913 1.4275606 6.8115881 1.4275606 15 P 0 ;0,1=126,2=0.000000
L 6.8015913 1.5375703 6.7965929 1.5425687 15 P 0 ;0,1=124,2=0.000000
L 6.8065897 1.4125655 6.8115881 1.4125655 15 P 0 ;0,1=126,2=0.000000
L 6.8065897 1.5575638 6.8115881 1.5575638 15 P 0 ;0,1=124,2=0.000000
L 6.8115881 1.3975703 6.8015913 1.3975703 15 P 0 ;0,1=126,2=0.000000
L 6.8115881 1.4125655 6.8065897 1.4125655 15 P 0 ;0,1=126,2=0.000000
L 6.8115881 1.4125655 6.8165864 1.4075671 15 P 0 ;0,1=126,2=0.000000
L 6.8115881 1.4275606 6.8165864 1.4225622 15 P 0 ;0,1=126,2=0.000000
L 6.8115881 1.5375703 6.8015913 1.5375703 15 P 0 ;0,1=124,2=0.000000
L 6.8115881 1.5575638 6.8165864 1.5525655 15 P 0 ;0,1=124,2=0.000000
L 6.8125881 1.4715703 6.8125881 1.5015606 15 P 0 ;0,1=125,2=0.000000
L 6.8125881 1.5015606 6.7975929 1.4865655 15 P 0 ;0,1=125,2=0.000000
L 6.8165864 1.4025687 6.8115881 1.3975703 15 P 0 ;0,1=126,2=0.000000
L 6.8165864 1.4075671 6.8165864 1.4025687 15 P 0 ;0,1=126,2=0.000000
L 6.8165864 1.4175638 6.8115881 1.4125655 15 P 0 ;0,1=126,2=0.000000
L 6.8165864 1.4225622 6.8165864 1.4175638 15 P 0 ;0,1=126,2=0.000000
L 6.8165864 1.5425687 6.8115881 1.5375703 15 P 0 ;0,1=124,2=0.000000
L 6.8165864 1.5525655 6.8165864 1.5425687 15 P 0 ;0,1=124,2=0.000000
L 6.8165864 1.5675606 6.7965929 1.5675606 15 P 0 ;0,1=124,2=0.000000
L 6.8336614 2.1496834 6.8386598 2.144685 15 P 0 ;0,1=120,2=0.000000
L 6.8336614 2.1696769 6.8336614 2.1496834 15 P 0 ;0,1=120,2=0.000000
L 6.8386598 2.144685 6.8486566 2.144685 15 P 0 ;0,1=120,2=0.000000
L 6.8386598 2.1746753 6.8336614 2.1696769 15 P 0 ;0,1=120,2=0.000000
L 6.8454724 1.75 6.8454724 1.7799903 15 P 0 ;0,1=75,2=0.000000
L 6.8454724 1.7799903 6.8604676 1.7799903 15 P 0 ;0,1=75,2=0.000000
L 6.8486566 2.144685 6.8536549 2.1496834 15 P 0 ;0,1=120,2=0.000000
L 6.8486566 2.1746753 6.8386598 2.1746753 15 P 0 ;0,1=120,2=0.000000
L 6.8498425 2.068063 6.8998425 2.068063 10 P 0
L 6.8498425 2.124063 6.8998425 2.124063 10 P 0
L 6.8536549 2.1696769 6.8486566 2.1746753 15 P 0 ;0,1=120,2=0.000000
L 6.8554692 1.7599968 6.8654659 1.75 15 P 0 ;0,1=75,2=0.000000
L 6.8604676 1.7599968 6.8454724 1.7599968 15 P 0 ;0,1=75,2=0.000000
L 6.8604676 1.7799903 6.8654659 1.7749919 15 P 0 ;0,1=75,2=0.000000
L 6.8636517 2.144685 6.8736485 2.144685 15 P 0 ;0,1=120,2=0.000000
L 6.8654659 1.7649952 6.8604676 1.7599968 15 P 0 ;0,1=75,2=0.000000
L 6.8654659 1.7749919 6.8654659 1.7649952 15 P 0 ;0,1=75,2=0.000000
L 6.8663546 2.9095703 6.8863481 2.9095703 15 P 0 ;0,1=78,2=0.000000
L 6.8663546 2.9395606 6.8663546 2.9095703 15 P 0 ;0,1=78,2=0.000000
L 6.8686501 2.144685 6.8686501 2.1746753 15 P 0 ;0,1=120,2=0.000000
L 6.8686501 2.1746753 6.8636517 2.1696769 15 P 0 ;0,1=120,2=0.000000
L 6.8698425 1.796378 6.8698425 1.835748 10 P 0
L 6.8736485 2.144685 6.8686501 2.144685 15 P 0 ;0,1=120,2=0.000000
L 6.8754627 1.7649952 6.8954562 1.7649952 15 P 0 ;0,1=75,2=0.000000
L 6.8886436 2.1496834 6.893642 2.144685 15 P 0 ;0,1=120,2=0.000000
L 6.8886436 2.1646785 6.893642 2.1596802 15 P 0 ;0,1=120,2=0.000000
L 6.8886436 2.1696769 6.8886436 2.1646785 15 P 0 ;0,1=120,2=0.000000
L 6.8904579 1.75 6.8904579 1.7799903 15 P 0 ;0,1=75,2=0.000000
L 6.8904579 1.7799903 6.8754627 1.7649952 15 P 0 ;0,1=75,2=0.000000
L 6.893642 2.144685 6.9036388 2.144685 15 P 0 ;0,1=120,2=0.000000
L 6.893642 2.1596802 6.9086371 2.1596802 15 P 0 ;0,1=120,2=0.000000
L 6.893642 2.1746753 6.8886436 2.1696769 15 P 0 ;0,1=120,2=0.000000
L 6.8963449 2.9095703 6.9163384 2.9295638 15 P 0 ;0,1=78,2=0.000000
L 6.9013433 2.9395606 6.8963449 2.9345622 15 P 0 ;0,1=78,2=0.000000
L 6.9036388 2.144685 6.9086371 2.1496834 15 P 0 ;0,1=120,2=0.000000
L 6.9036388 2.1746753 6.893642 2.1746753 15 P 0 ;0,1=120,2=0.000000
L 6.9086371 2.1496834 6.9086371 2.1696769 15 P 0 ;0,1=120,2=0.000000
L 6.9086371 2.1696769 6.9036388 2.1746753 15 P 0 ;0,1=120,2=0.000000
L 6.9113401 2.9395606 6.9013433 2.9395606 15 P 0 ;0,1=78,2=0.000000
L 6.9163384 2.9095703 6.8963449 2.9095703 15 P 0 ;0,1=78,2=0.000000
L 6.9163384 2.9295638 6.9163384 2.9345622 15 P 0 ;0,1=78,2=0.000000
L 6.9163384 2.9345622 6.9113401 2.9395606 15 P 0 ;0,1=78,2=0.000000
L 6.9198128 1.9636598 6.9248112 1.9586614 15 P 0 ;0,1=119,2=90.000000
L 6.9198128 1.9736566 6.9198128 1.9636598 15 P 0 ;0,1=119,2=90.000000
L 6.9198128 1.9936501 6.9248112 1.9886517 15 P 0 ;0,1=119,2=90.000000
L 6.9198128 2.0036469 6.9198128 1.9936501 15 P 0 ;0,1=119,2=90.000000
L 6.9198128 2.0236404 6.9198128 2.0336372 15 P 0 ;0,1=119,2=90.000000
L 6.9198128 2.0336372 6.9248112 2.0386355 15 P 0 ;0,1=119,2=90.000000
L 6.9248112 1.9586614 6.9448047 1.9586614 15 P 0 ;0,1=119,2=90.000000
L 6.9248112 1.9786549 6.9198128 1.9736566 15 P 0 ;0,1=119,2=90.000000
L 6.9248112 2.0086452 6.9198128 2.0036469 15 P 0 ;0,1=119,2=90.000000
L 6.9248112 2.018642 6.9198128 2.0236404 15 P 0 ;0,1=119,2=90.000000
L 6.9248112 2.0386355 6.9448047 2.0386355 15 P 0 ;0,1=119,2=90.000000
L 6.9298096 2.0086452 6.9248112 2.0086452 15 P 0 ;0,1=119,2=90.000000
L 6.931811 2.3480315 6.931811 2.8740945 3 P 0
L 6.9361007 3.4694882 6.9311023 3.4744866 15 P 0 ;0,1=81,2=0.000000
L 6.9410991 3.4694882 6.9361007 3.4694882 15 P 0 ;0,1=81,2=0.000000
L 6.9410991 3.4994785 6.9460975 3.4994785 15 P 0 ;0,1=81,2=0.000000
L 6.9448047 1.9586614 6.9498031 1.9636598 15 P 0 ;0,1=119,2=90.000000
L 6.9448047 2.018642 6.9248112 2.018642 15 P 0 ;0,1=119,2=90.000000
L 6.9448047 2.0386355 6.9498031 2.0336372 15 P 0 ;0,1=119,2=90.000000
L 6.9460975 3.4744866 6.9410991 3.4694882 15 P 0 ;0,1=81,2=0.000000
L 6.9460975 3.4994785 6.9460975 3.4744866 15 P 0 ;0,1=81,2=0.000000
L 6.9498031 1.9636598 6.9498031 1.9736566 15 P 0 ;0,1=119,2=90.000000
L 6.9498031 1.9736566 6.9448047 1.9786549 15 P 0 ;0,1=119,2=90.000000
L 6.9498031 1.9886517 6.9298096 2.0086452 15 P 0 ;0,1=119,2=90.000000
L 6.9498031 2.0086452 6.9498031 1.9886517 15 P 0 ;0,1=119,2=90.000000
L 6.9498031 2.0236404 6.9448047 2.018642 15 P 0 ;0,1=119,2=90.000000
L 6.9498031 2.0336372 6.9498031 2.0236404 15 P 0 ;0,1=119,2=90.000000
L 6.9510958 3.4994785 6.9410991 3.4994785 15 P 0 ;0,1=81,2=0.000000
L 6.9518522 3.3915606 6.9718457 3.3615703 15 P 0 ;0,1=40,2=0.000000
L 6.9610926 3.4694882 6.9810861 3.4894817 15 P 0 ;0,1=81,2=0.000000
L 6.966091 3.4994785 6.9610926 3.4944801 15 P 0 ;0,1=81,2=0.000000
L 6.9718457 3.3915606 6.9518522 3.3615703 15 P 0 ;0,1=40,2=0.000000
L 6.9760878 3.4994785 6.966091 3.4994785 15 P 0 ;0,1=81,2=0.000000
L 6.9810861 3.4694882 6.9610926 3.4694882 15 P 0 ;0,1=81,2=0.000000
L 6.9810861 3.4894817 6.9810861 3.4944801 15 P 0 ;0,1=81,2=0.000000
L 6.9810861 3.4944801 6.9760878 3.4994785 15 P 0 ;0,1=81,2=0.000000
L 6.9818425 3.3615703 6.9918393 3.3615703 15 P 0 ;0,1=40,2=0.000000
L 6.9868409 3.3615703 6.9868409 3.3915606 15 P 0 ;0,1=40,2=0.000000
L 6.9868409 3.3915606 6.9818425 3.3865622 15 P 0 ;0,1=40,2=0.000000
L 6.9901575 1.911063 7.0295275 1.911063 10 P 0
L 6.9918393 3.3615703 6.9868409 3.3615703 15 P 0 ;0,1=40,2=0.000000
L 6.9948425 3.156063 7.0098425 3.156063 10 P 0
L 6.9948425 3.306063 7.0098425 3.306063 10 P 0
L 6.9975687 1.9655512 6.9975687 1.9805464 15 P 0 ;0,1=72,2=90.000000
L 6.9975687 1.9805464 7.0025671 1.9855447 15 P 0 ;0,1=72,2=90.000000
L 6.9975687 2.0005399 6.9975687 2.0105367 15 P 0 ;0,1=72,2=90.000000
L 6.9975687 2.0105367 7.0025671 2.015535 15 P 0 ;0,1=72,2=90.000000
L 7.0025671 1.9855447 7.0125638 1.9855447 15 P 0 ;0,1=72,2=90.000000
L 7.0025671 1.9955415 6.9975687 2.0005399 15 P 0 ;0,1=72,2=90.000000
L 7.0025671 2.015535 7.0075655 2.015535 15 P 0 ;0,1=72,2=90.000000
L 7.0035442 3.5299036 7.0035442 3.5721068 14 P 0
L 7.0035442 3.5721068 7.0035442 4.3569484 12 P 0
L 7.0075655 1.9955415 7.0025671 1.9955415 15 P 0 ;0,1=72,2=90.000000
L 7.0075655 2.015535 7.0125638 2.0105367 15 P 0 ;0,1=72,2=90.000000
L 7.0098425 3.156063 7.0098425 3.166063 10 P 0
L 7.0098425 3.166063 7.0098425 3.296063 10 P 0
L 7.0098425 3.296063 7.0098425 3.306063 10 P 0
L 7.0125638 1.9855447 7.0175622 1.9805464 15 P 0 ;0,1=72,2=90.000000
L 7.0125638 2.0005399 7.0075655 1.9955415 15 P 0 ;0,1=72,2=90.000000
L 7.0125638 2.0005399 7.0125638 2.0105367 15 P 0 ;0,1=72,2=90.000000
L 7.0125638 2.0105367 7.0175622 2.015535 15 P 0 ;0,1=72,2=90.000000
L 7.0175622 1.975548 7.027559 1.9855447 15 P 0 ;0,1=72,2=90.000000
L 7.0175622 1.9805464 7.0175622 1.9655512 15 P 0 ;0,1=72,2=90.000000
L 7.0175622 1.9955415 7.0125638 2.0005399 15 P 0 ;0,1=72,2=90.000000
L 7.0175622 2.015535 7.0225606 2.015535 15 P 0 ;0,1=72,2=90.000000
L 7.0225606 1.9955415 7.0175622 1.9955415 15 P 0 ;0,1=72,2=90.000000
L 7.0225606 2.015535 7.027559 2.0105367 15 P 0 ;0,1=72,2=90.000000
L 7.027559 1.9655512 6.9975687 1.9655512 15 P 0 ;0,1=72,2=90.000000
L 7.027559 2.0005399 7.0225606 1.9955415 15 P 0 ;0,1=72,2=90.000000
L 7.027559 2.0105367 7.027559 2.0005399 15 P 0 ;0,1=72,2=90.000000
P 6.5573425 3.151063 16 P 0 0
S P 0
OB 1.3066695 4.1391688 I
OS 1.3066695 4.1368228
OS 1.2917379 4.1368228
OS 1.2917517 4.136809
OS 1.2917793 4.1367814
OS 1.2918207 4.13674
OS 1.2918759 4.136671
OS 1.2919449 4.1365882
OS 1.2920415 4.1364778
OS 1.2921381 4.1363536
OS 1.2922485 4.1362294
OS 1.2923589 4.1360638
OS 1.2924969 4.1358982
OS 1.2926211 4.1357188
OS 1.2927729 4.1355256
OS 1.2929109 4.1353048
OS 1.2930627 4.135084
OS 1.2933663 4.1345872
OS 1.2933801 4.1345734
OS 1.2934077 4.134532
OS 1.2934491 4.1344492
OS 1.2934905 4.1343526
OS 1.2935595 4.1342422
OS 1.2936423 4.1341042
OS 1.2937251 4.1339386
OS 1.2938217 4.133773
OS 1.2940149 4.1333866
OS 1.2942081 4.1329726
OS 1.2944013 4.1325448
OS 1.2945669 4.1321308
OS 1.2923037 4.1321308
OS 1.2922899 4.1321584
OS 1.2922623 4.1322136
OS 1.2922071 4.132324
OS 1.2921381 4.132462
OS 1.2920553 4.1326276
OS 1.2919449 4.1328346
OS 1.2918207 4.1330554
OS 1.2916827 4.13329
OS 1.2915171 4.1335522
OS 1.2913515 4.1338282
OS 1.2909651 4.1344078
OS 1.2905373 4.1350012
OS 1.2900681 4.135567
OS 1.2900543 4.1355808
OS 1.2900129 4.135636
OS 1.2899439 4.135705
OS 1.2898473 4.1358016
OS 1.2897231 4.1359258
OS 1.2895851 4.1360638
OS 1.2894195 4.1362156
OS 1.2892539 4.1363812
OS 1.2890607 4.1365468
OS 1.2888537 4.1367262
OS 1.2884259 4.1370712
OS 1.2879705 4.1373886
OS 1.2877359 4.1375266
OS 1.2875013 4.1376508
OS 1.2875013 4.1391688
OS 1.3066695 4.1391688
OE
OB 1.2875151 4.1516578 I
OS 1.2875151 4.151782
OS 1.2875289 4.1519476
OS 1.2875565 4.1521132
OS 1.2875841 4.1523064
OS 1.2876531 4.1527204
OS 1.2877635 4.1531758
OS 1.2879153 4.153645
OS 1.2880119 4.1538658
OS 1.2881223 4.1540866
OS 1.2881223 4.1541004
OS 1.2881499 4.1541418
OS 1.2881913 4.154197
OS 1.2882327 4.1542798
OS 1.2883017 4.1543764
OS 1.2883845 4.1544868
OS 1.2884673 4.1546248
OS 1.2885777 4.1547628
OS 1.2888261 4.1550664
OS 1.2891435 4.1553838
OS 1.2895023 4.1557012
OS 1.2899163 4.155991
OS 1.2899301 4.1560048
OS 1.2899715 4.1560186
OS 1.2900405 4.15606
OS 1.2901233 4.1561152
OS 1.2902337 4.1561842
OS 1.2903717 4.1562532
OS 1.2905235 4.156336
OS 1.2907029 4.1564188
OS 1.2908961 4.1565154
OS 1.2911169 4.156612
OS 1.2913515 4.1567086
OS 1.2915999 4.156819
OS 1.2918621 4.1569156
OS 1.2921381 4.1569984
OS 1.2924417 4.157095
OS 1.2927453 4.1571778
OS 1.2927591 4.1571778
OS 1.2928281 4.1571916
OS 1.2929109 4.1572192
OS 1.2930489 4.1572468
OS 1.2932145 4.1572744
OS 1.2934215 4.1573158
OS 1.2936561 4.1573572
OS 1.2939321 4.1573986
OS 1.2942357 4.15744
OS 1.2945807 4.1574814
OS 1.2949533 4.1575228
OS 1.2953535 4.1575504
OS 1.2957813 4.157578
OS 1.2962505 4.1576056
OS 1.2967335 4.1576194
OS 1.2972579 4.1576194
OS 1.2972717 4.1576194
OS 1.2972993 4.1576194
OS 1.2973407 4.1576194
OS 1.2974097 4.1576194
OS 1.2974787 4.1576194
OS 1.2975753 4.1576194
OS 1.2976857 4.1576056
OS 1.2978099 4.1576056
OS 1.2980997 4.1575918
OS 1.2984309 4.157578
OS 1.2987897 4.1575642
OS 1.2991899 4.1575366
OS 1.2996177 4.1574952
OS 1.3000593 4.1574538
OS 1.3009563 4.1573296
OS 1.3014117 4.1572468
OS 1.3018533 4.1571502
OS 1.3022811 4.1570398
OS 1.3026813 4.1569156
OS 1.3027089 4.1569018
OS 1.3027779 4.156888
OS 1.3028745 4.1568466
OS 1.3030263 4.1567914
OS 1.3031919 4.1567086
OS 1.3033989 4.1566258
OS 1.3036197 4.1565154
OS 1.3038543 4.156405
OS 1.3041027 4.156267
OS 1.3043649 4.1561014
OS 1.3046271 4.1559358
OS 1.3049031 4.1557564
OS 1.3051653 4.1555494
OS 1.3054137 4.1553286
OS 1.3056483 4.155094
OS 1.3058691 4.1548456
OS 1.3058829 4.1548318
OS 1.3059105 4.1547766
OS 1.3059657 4.1547076
OS 1.3060485 4.1545972
OS 1.3061313 4.1544592
OS 1.3062279 4.1543074
OS 1.3063245 4.1541142
OS 1.3064211 4.1539072
OS 1.3065315 4.1536588
OS 1.3066281 4.1533966
OS 1.3067247 4.1531206
OS 1.3068075 4.152817
OS 1.3068765 4.1524858
OS 1.3069317 4.1521408
OS 1.3069731 4.151782
OS 1.3069869 4.1513956
OS 1.3069869 4.1512714
OS 1.3069731 4.1511334
OS 1.3069593 4.1509402
OS 1.3069317 4.1507056
OS 1.3068765 4.1504296
OS 1.3068213 4.1501398
OS 1.3067385 4.1498086
OS 1.3066419 4.1494636
OS 1.3065039 4.1491186
OS 1.3063521 4.1487598
OS 1.3061589 4.1483872
OS 1.3059381 4.1480284
OS 1.3056759 4.1476834
OS 1.3053723 4.1473522
OS 1.3050273 4.1470486
OS 1.3050135 4.1470486
OS 1.3049997 4.1470348
OS 1.3049583 4.1470072
OS 1.3049169 4.1469658
OS 1.3048479 4.1469244
OS 1.3047651 4.1468692
OS 1.3046823 4.146814
OS 1.3045719 4.1467588
OS 1.3044477 4.1466898
OS 1.3043097 4.146607
OS 1.3041579 4.146538
OS 1.3039923 4.1464552
OS 1.3037991 4.1463724
OS 1.3036059 4.1462896
OS 1.3033851 4.146193
OS 1.3031643 4.1461102
OS 1.3029159 4.1460274
OS 1.3026537 4.1459308
OS 1.3023777 4.145848
OS 1.3020741 4.1457652
OS 1.3017705 4.1456824
OS 1.3014393 4.1456134
OS 1.3011081 4.1455306
OS 1.3007355 4.1454616
OS 1.3003629 4.1454064
OS 1.2999765 4.1453512
OS 1.2995625 4.145296
OS 1.2991347 4.1452546
OS 1.2986931 4.1452132
OS 1.2982377 4.1451994
OS 1.2977547 4.1451718
OS 1.2972579 4.1451718
OS 1.2972441 4.1451718
OS 1.2972165 4.1451718
OS 1.2971751 4.1451718
OS 1.2971061 4.1451718
OS 1.2970233 4.1451718
OS 1.2969267 4.1451718
OS 1.2968163 4.1451856
OS 1.2966921 4.1451856
OS 1.2964161 4.1451994
OS 1.2960849 4.1452132
OS 1.2957123 4.145227
OS 1.2953121 4.1452546
OS 1.2948843 4.145296
OS 1.2944427 4.1453374
OS 1.2935319 4.1454616
OS 1.2930765 4.1455444
OS 1.2926349 4.145641
OS 1.2922071 4.1457376
OS 1.2918069 4.1458618
OS 1.2917793 4.1458756
OS 1.2917103 4.1458894
OS 1.2916137 4.1459308
OS 1.2914619 4.145986
OS 1.2912963 4.1460688
OS 1.2910893 4.1461516
OS 1.2908685 4.146262
OS 1.2906339 4.1463862
OS 1.2903855 4.1465104
OS 1.2901233 4.146676
OS 1.2898473 4.1468416
OS 1.2895851 4.147021
OS 1.2893229 4.147228
OS 1.2890745 4.1474488
OS 1.2888399 4.1476834
OS 1.2886191 4.1479318
OS 1.2886053 4.1479456
OS 1.2885639 4.1480008
OS 1.2885087 4.1480698
OS 1.2884397 4.1481802
OS 1.2883569 4.1483182
OS 1.2882603 4.1484838
OS 1.2881637 4.1486632
OS 1.2880533 4.148884
OS 1.2879567 4.1491186
OS 1.2878601 4.1493808
OS 1.2877635 4.1496706
OS 1.2876807 4.1499742
OS 1.2875979 4.1503054
OS 1.2875427 4.1506504
OS 1.2875151 4.1510092
OS 1.2875013 4.1513956
OS 1.2875013 4.1515474
OS 1.2875151 4.1516578
OE
OB 1.2875841 4.120939 I
OS 1.2875841 4.1211598
OS 1.2875979 4.1214082
OS 1.2876117 4.1216704
OS 1.2876393 4.121974
OS 1.2876669 4.1222776
OS 1.2876945 4.122595
OS 1.2877911 4.1232436
OS 1.2878463 4.1235472
OS 1.2879153 4.1238508
OS 1.2879981 4.1241406
OS 1.2880947 4.1244028
OS 1.2880947 4.1244166
OS 1.2881223 4.124458
OS 1.2881499 4.124527
OS 1.2881913 4.1246236
OS 1.2882465 4.124734
OS 1.2883293 4.1248582
OS 1.2884121 4.12501
OS 1.2885087 4.1251618
OS 1.2886329 4.1253274
OS 1.2887571 4.1255068
OS 1.2889089 4.1256862
OS 1.2890745 4.1258656
OS 1.2892677 4.1260312
OS 1.2894609 4.1262106
OS 1.2896817 4.1263762
OS 1.2899163 4.126528
OS 1.2899301 4.1265418
OS 1.2899715 4.1265694
OS 1.2900405 4.126597
OS 1.2901371 4.1266522
OS 1.2902613 4.1267074
OS 1.2904131 4.1267764
OS 1.2905787 4.1268592
OS 1.2907581 4.1269282
OS 1.2909651 4.1269972
OS 1.2911859 4.12708
OS 1.2914205 4.127149
OS 1.2916689 4.1272042
OS 1.2919311 4.1272594
OS 1.2922071 4.1273008
OS 1.2924969 4.1273146
OS 1.2927867 4.1273284
OS 1.2928143 4.1273284
OS 1.2928695 4.1273284
OS 1.2929799 4.1273146
OS 1.2931317 4.1273146
OS 1.2932973 4.127287
OS 1.2935043 4.1272594
OS 1.2937251 4.127218
OS 1.2939735 4.1271628
OS 1.2942357 4.1270938
OS 1.2945117 4.127011
OS 1.2948015 4.1269006
OS 1.2950913 4.1267764
OS 1.2953811 4.1266246
OS 1.2956571 4.1264452
OS 1.2959469 4.1262382
OS 1.2962091 4.1260036
OS 1.2962229 4.1259898
OS 1.2962643 4.1259484
OS 1.2963333 4.1258656
OS 1.2964299 4.1257552
OS 1.2965403 4.1256172
OS 1.2966645 4.1254378
OS 1.2968025 4.1252446
OS 1.2969543 4.12501
OS 1.2971061 4.124734
OS 1.2972579 4.1244442
OS 1.2973959 4.1240992
OS 1.2975477 4.1237404
OS 1.2976719 4.1233402
OS 1.2977961 4.1229124
OS 1.2978927 4.1224432
OS 1.2979755 4.1219464
OS 1.2979755 4.1219602
OS 1.2980031 4.1219878
OS 1.2980169 4.122043
OS 1.2980583 4.122112
OS 1.2980997 4.1221948
OS 1.2981549 4.1222914
OS 1.2982791 4.1225122
OS 1.2984171 4.1227606
OS 1.2985827 4.123009
OS 1.2987483 4.1232436
OS 1.2989277 4.1234644
OS 1.2989415 4.1234782
OS 1.2989691 4.1235196
OS 1.2990381 4.1235748
OS 1.2991071 4.1236576
OS 1.2992175 4.1237542
OS 1.2993279 4.1238646
OS 1.2994659 4.1240026
OS 1.2996315 4.1241406
OS 1.2998109 4.1242924
OS 1.3000041 4.124458
OS 1.3002111 4.1246374
OS 1.3004319 4.1248168
OS 1.3006803 4.1249962
OS 1.3009287 4.1251894
OS 1.3014807 4.125562
OS 1.3066695 4.1288602
OS 1.3066695 4.1257
OS 1.3026951 4.1231746
OS 1.3026813 4.1231608
OS 1.3026261 4.1231194
OS 1.3025295 4.1230642
OS 1.3024191 4.1229952
OS 1.3022673 4.1228986
OS 1.3021017 4.1227882
OS 1.3019223 4.122664
OS 1.3017291 4.1225398
OS 1.3013013 4.12225
OS 1.3008597 4.1219464
OS 1.3004457 4.1216428
OS 1.3002525 4.121491
OS 1.3000731 4.121353
OS 1.3000593 4.1213392
OS 1.3000317 4.1213254
OS 1.2999903 4.121284
OS 1.2999213 4.1212288
OS 1.2997557 4.1210908
OS 1.2995625 4.1209252
OS 1.2993555 4.1207182
OS 1.2991347 4.1205112
OS 1.2989415 4.1202904
OS 1.2987897 4.1200696
OS 1.2987759 4.120042
OS 1.2987345 4.119973
OS 1.2986655 4.1198626
OS 1.2985965 4.1197108
OS 1.2985137 4.1195452
OS 1.2984171 4.119352
OS 1.2983481 4.119145
OS 1.2982791 4.1189242
OS 1.2982791 4.1189104
OS 1.2982653 4.1188414
OS 1.2982515 4.118731
OS 1.2982239 4.118593
OS 1.2982101 4.1183998
OS 1.2981963 4.1181514
OS 1.2981825 4.1178616
OS 1.2981825 4.114591
OS 1.3066695 4.114591
OS 1.3066695 4.1120656
OS 1.2875703 4.1120656
OS 1.2875703 4.1207734
OS 1.2875841 4.120939
OE
OB 1.2896817 4.1206216 H
OS 1.2896817 4.114591
OS 1.2959883 4.114591
OS 1.2959883 4.1203042
OS 1.2959745 4.1204422
OS 1.2959745 4.1206216
OS 1.2959607 4.120801
OS 1.2959469 4.121008
OS 1.2959055 4.1214358
OS 1.2958365 4.1218912
OS 1.2957537 4.1223328
OS 1.2956985 4.122526
OS 1.2956433 4.1227192
OS 1.2956433 4.122733
OS 1.2956295 4.1227606
OS 1.2956019 4.1228158
OS 1.2955743 4.1228848
OS 1.2955329 4.1229676
OS 1.2954915 4.1230504
OS 1.2953673 4.1232712
OS 1.2952017 4.1235196
OS 1.2950085 4.123768
OS 1.2947739 4.1240026
OS 1.2944979 4.1242096
OS 1.2944841 4.1242096
OS 1.2944565 4.1242372
OS 1.2944151 4.124251
OS 1.2943599 4.1242924
OS 1.2942909 4.1243338
OS 1.2941943 4.1243752
OS 1.2939873 4.1244718
OS 1.2937389 4.1245546
OS 1.2934491 4.1246374
OS 1.2931317 4.1246926
OS 1.2927867 4.1247202
OS 1.2927729 4.1247202
OS 1.2927315 4.1247202
OS 1.2926625 4.1247202
OS 1.2925659 4.1247064
OS 1.2924417 4.1246926
OS 1.2923175 4.124665
OS 1.2921657 4.1246374
OS 1.2920001 4.124596
OS 1.2918345 4.1245408
OS 1.2916551 4.1244718
OS 1.2914619 4.1244028
OS 1.2912825 4.1243062
OS 1.2910893 4.124182
OS 1.2909099 4.1240578
OS 1.2907305 4.123906
OS 1.2905649 4.1237266
OS 1.2905511 4.1237128
OS 1.2905235 4.1236852
OS 1.2904821 4.1236162
OS 1.2904269 4.1235472
OS 1.2903579 4.1234368
OS 1.2902889 4.1232988
OS 1.2902061 4.123147
OS 1.2901233 4.1229676
OS 1.2900405 4.1227744
OS 1.2899577 4.1225398
OS 1.2898887 4.1222776
OS 1.2898197 4.1220016
OS 1.2897645 4.121698
OS 1.2897231 4.1213668
OS 1.2896955 4.121008
OS 1.2896817 4.1206216
OE
OB 1.2894471 4.151368 H
OS 1.2894471 4.151299
OS 1.2894609 4.1512162
OS 1.2894747 4.1511058
OS 1.2894885 4.1509678
OS 1.2895161 4.1508022
OS 1.2895575 4.1506366
OS 1.2896127 4.1504434
OS 1.2896955 4.1502364
OS 1.2897783 4.1500294
OS 1.2898887 4.1498086
OS 1.2900267 4.1496016
OS 1.2901785 4.1493808
OS 1.2903579 4.1491738
OS 1.2905787 4.1489806
OS 1.2908133 4.1487874
OS 1.2908271 4.1487736
OS 1.2908961 4.1487322
OS 1.2910065 4.148677
OS 1.2911583 4.1485942
OS 1.2913653 4.1485114
OS 1.2916137 4.1484148
OS 1.2919173 4.1483044
OS 1.2922761 4.148194
OS 1.2924693 4.148125
OS 1.2926901 4.1480698
OS 1.2929109 4.1480146
OS 1.2931593 4.1479732
OS 1.2934077 4.147918
OS 1.2936837 4.1478628
OS 1.2939735 4.1478214
OS 1.2942771 4.14778
OS 1.2945945 4.1477386
OS 1.2949257 4.1476972
OS 1.2952707 4.1476696
OS 1.2956295 4.147642
OS 1.2960159 4.1476144
OS 1.2964161 4.1476006
OS 1.2968301 4.1475868
OS 1.2972579 4.1475868
OS 1.2972717 4.1475868
OS 1.2973131 4.1475868
OS 1.2973683 4.1475868
OS 1.2974649 4.1475868
OS 1.2975753 4.1475868
OS 1.2976995 4.1476006
OS 1.2978513 4.1476006
OS 1.2980169 4.1476006
OS 1.2981963 4.1476144
OS 1.2983895 4.1476144
OS 1.2988311 4.147642
OS 1.2993003 4.1476834
OS 1.2997971 4.1477248
OS 1.3003215 4.14778
OS 1.3008459 4.147849
OS 1.3013703 4.1479456
OS 1.3018809 4.1480422
OS 1.3023639 4.1481664
OS 1.3027917 4.1483182
OS 1.3029987 4.148401
OS 1.3031781 4.1484838
OS 1.3033575 4.1485804
OS 1.3035093 4.148677
OS 1.3035231 4.1486908
OS 1.3035783 4.1487322
OS 1.3036473 4.1487874
OS 1.3037439 4.1488702
OS 1.3038681 4.1489806
OS 1.3039923 4.1491186
OS 1.3041441 4.1492566
OS 1.3042821 4.149436
OS 1.3044201 4.1496154
OS 1.3045719 4.1498224
OS 1.3046961 4.1500432
OS 1.3048065 4.1502916
OS 1.3049169 4.15054
OS 1.3049859 4.150816
OS 1.3050411 4.1511058
OS 1.3050549 4.1513956
OS 1.3050549 4.1514646
OS 1.3050411 4.1515474
OS 1.3050273 4.1516578
OS 1.3050135 4.1517958
OS 1.3049721 4.1519614
OS 1.3049307 4.1521408
OS 1.3048617 4.152334
OS 1.3047789 4.152541
OS 1.3046823 4.1527618
OS 1.3045581 4.1529826
OS 1.3044063 4.1532172
OS 1.3042269 4.153438
OS 1.3040199 4.1536726
OS 1.3037853 4.1538934
OS 1.3035093 4.1541004
OS 1.3034955 4.1541142
OS 1.3034265 4.1541418
OS 1.3033299 4.154197
OS 1.3031919 4.1542798
OS 1.3029987 4.1543626
OS 1.3027641 4.1544454
OS 1.3024881 4.1545558
OS 1.3021431 4.1546524
OS 1.3019499 4.1547076
OS 1.3017429 4.154749
OS 1.3015359 4.1548042
OS 1.3013013 4.1548594
OS 1.3010529 4.1549008
OS 1.3007907 4.1549422
OS 1.3005147 4.1549974
OS 1.3002111 4.1550388
OS 1.2999075 4.1550664
OS 1.2995763 4.1551078
OS 1.2992313 4.1551354
OS 1.2988725 4.155163
OS 1.2984999 4.1551768
OS 1.2980997 4.1551906
OS 1.2976857 4.1552044
OS 1.2972579 4.1552044
OS 1.2972441 4.1552044
OS 1.2972027 4.1552044
OS 1.2971337 4.1552044
OS 1.2970509 4.1552044
OS 1.2969405 4.1552044
OS 1.2968163 4.1552044
OS 1.2966645 4.1551906
OS 1.2964989 4.1551906
OS 1.2963195 4.1551768
OS 1.2961125 4.1551768
OS 1.2956847 4.1551492
OS 1.2952155 4.1551078
OS 1.2947049 4.1550664
OS 1.2941943 4.1550112
OS 1.2936699 4.1549422
OS 1.2931455 4.1548456
OS 1.2926349 4.1547352
OS 1.2921519 4.154611
OS 1.2917241 4.1544592
OS 1.2915171 4.1543764
OS 1.2913377 4.1542936
OS 1.2911583 4.154197
OS 1.2910065 4.1541004
OS 1.2909927 4.1540866
OS 1.2909375 4.1540452
OS 1.2908685 4.15399
OS 1.2907581 4.1539072
OS 1.2906477 4.1537968
OS 1.2905097 4.1536726
OS 1.2903717 4.1535208
OS 1.2902199 4.1533552
OS 1.2900819 4.153162
OS 1.2899439 4.152955
OS 1.2898059 4.1527342
OS 1.2896955 4.1524858
OS 1.2895851 4.1522236
OS 1.2895161 4.1519614
OS 1.2894609 4.1516716
OS 1.2894471 4.151368
OE
SE
S P 0
OB 1.3097808 4.028772 I
OS 1.3097808 4.026426
OS 1.2948492 4.026426
OS 1.294863 4.0264122
OS 1.2948906 4.0263846
OS 1.294932 4.0263432
OS 1.2949872 4.0262742
OS 1.2950562 4.0261914
OS 1.2951528 4.026081
OS 1.2952494 4.0259568
OS 1.2953598 4.0258326
OS 1.2954702 4.025667
OS 1.2956082 4.0255014
OS 1.2957324 4.025322
OS 1.2958842 4.0251288
OS 1.2960222 4.024908
OS 1.296174 4.0246872
OS 1.2964776 4.0241904
OS 1.2964914 4.0241766
OS 1.296519 4.0241352
OS 1.2965604 4.0240524
OS 1.2966018 4.0239558
OS 1.2966708 4.0238454
OS 1.2967536 4.0237074
OS 1.2968364 4.0235418
OS 1.296933 4.0233762
OS 1.2971262 4.0229898
OS 1.2973194 4.0225758
OS 1.2975126 4.022148
OS 1.2976782 4.021734
OS 1.295415 4.021734
OS 1.2954012 4.0217616
OS 1.2953736 4.0218168
OS 1.2953184 4.0219272
OS 1.2952494 4.0220652
OS 1.2951666 4.0222308
OS 1.2950562 4.0224378
OS 1.294932 4.0226586
OS 1.294794 4.0228932
OS 1.2946284 4.0231554
OS 1.2944628 4.0234314
OS 1.2940764 4.024011
OS 1.2936486 4.0246044
OS 1.2931794 4.0251702
OS 1.2931656 4.025184
OS 1.2931242 4.0252392
OS 1.2930552 4.0253082
OS 1.2929586 4.0254048
OS 1.2928344 4.025529
OS 1.2926964 4.025667
OS 1.2925308 4.0258188
OS 1.2923652 4.0259844
OS 1.292172 4.02615
OS 1.291965 4.0263294
OS 1.2915372 4.0266744
OS 1.2910818 4.0269918
OS 1.2908472 4.0271298
OS 1.2906126 4.027254
OS 1.2906126 4.028772
OS 1.3097808 4.028772
OE
OB 1.3097808 4.043607 I
OS 1.3097808 4.041261
OS 1.2948492 4.041261
OS 1.294863 4.0412472
OS 1.2948906 4.0412196
OS 1.294932 4.0411782
OS 1.2949872 4.0411092
OS 1.2950562 4.0410264
OS 1.2951528 4.040916
OS 1.2952494 4.0407918
OS 1.2953598 4.0406676
OS 1.2954702 4.040502
OS 1.2956082 4.0403364
OS 1.2957324 4.040157
OS 1.2958842 4.0399638
OS 1.2960222 4.039743
OS 1.296174 4.0395222
OS 1.2964776 4.0390254
OS 1.2964914 4.0390116
OS 1.296519 4.0389702
OS 1.2965604 4.0388874
OS 1.2966018 4.0387908
OS 1.2966708 4.0386804
OS 1.2967536 4.0385424
OS 1.2968364 4.0383768
OS 1.296933 4.0382112
OS 1.2971262 4.0378248
OS 1.2973194 4.0374108
OS 1.2975126 4.036983
OS 1.2976782 4.036569
OS 1.295415 4.036569
OS 1.2954012 4.0365966
OS 1.2953736 4.0366518
OS 1.2953184 4.0367622
OS 1.2952494 4.0369002
OS 1.2951666 4.0370658
OS 1.2950562 4.0372728
OS 1.294932 4.0374936
OS 1.294794 4.0377282
OS 1.2946284 4.0379904
OS 1.2944628 4.0382664
OS 1.2940764 4.038846
OS 1.2936486 4.0394394
OS 1.2931794 4.0400052
OS 1.2931656 4.040019
OS 1.2931242 4.0400742
OS 1.2930552 4.0401432
OS 1.2929586 4.0402398
OS 1.2928344 4.040364
OS 1.2926964 4.040502
OS 1.2925308 4.0406538
OS 1.2923652 4.0408194
OS 1.292172 4.040985
OS 1.291965 4.0411644
OS 1.2915372 4.0415094
OS 1.2910818 4.0418268
OS 1.2908472 4.0419648
OS 1.2906126 4.042089
OS 1.2906126 4.043607
OS 1.3097808 4.043607
OE
OB 1.2906954 4.0105422 I
OS 1.2906954 4.010763
OS 1.2907092 4.0110114
OS 1.290723 4.0112736
OS 1.2907506 4.0115772
OS 1.2907782 4.0118808
OS 1.2908058 4.0121982
OS 1.2909024 4.0128468
OS 1.2909576 4.0131504
OS 1.2910266 4.013454
OS 1.2911094 4.0137438
OS 1.291206 4.014006
OS 1.291206 4.0140198
OS 1.2912336 4.0140612
OS 1.2912612 4.0141302
OS 1.2913026 4.0142268
OS 1.2913578 4.0143372
OS 1.2914406 4.0144614
OS 1.2915234 4.0146132
OS 1.29162 4.014765
OS 1.2917442 4.0149306
OS 1.2918684 4.01511
OS 1.2920202 4.0152894
OS 1.2921858 4.0154688
OS 1.292379 4.0156344
OS 1.2925722 4.0158138
OS 1.292793 4.0159794
OS 1.2930276 4.0161312
OS 1.2930414 4.016145
OS 1.2930828 4.0161726
OS 1.2931518 4.0162002
OS 1.2932484 4.0162554
OS 1.2933726 4.0163106
OS 1.2935244 4.0163796
OS 1.29369 4.0164624
OS 1.2938694 4.0165314
OS 1.2940764 4.0166004
OS 1.2942972 4.0166832
OS 1.2945318 4.0167522
OS 1.2947802 4.0168074
OS 1.2950424 4.0168626
OS 1.2953184 4.016904
OS 1.2956082 4.0169178
OS 1.295898 4.0169316
OS 1.2959256 4.0169316
OS 1.2959808 4.0169316
OS 1.2960912 4.0169178
OS 1.296243 4.0169178
OS 1.2964086 4.0168902
OS 1.2966156 4.0168626
OS 1.2968364 4.0168212
OS 1.2970848 4.016766
OS 1.297347 4.016697
OS 1.297623 4.0166142
OS 1.2979128 4.0165038
OS 1.2982026 4.0163796
OS 1.2984924 4.0162278
OS 1.2987684 4.0160484
OS 1.2990582 4.0158414
OS 1.2993204 4.0156068
OS 1.2993342 4.015593
OS 1.2993756 4.0155516
OS 1.2994446 4.0154688
OS 1.2995412 4.0153584
OS 1.2996516 4.0152204
OS 1.2997758 4.015041
OS 1.2999138 4.0148478
OS 1.3000656 4.0146132
OS 1.3002174 4.0143372
OS 1.3003692 4.0140474
OS 1.3005072 4.0137024
OS 1.300659 4.0133436
OS 1.3007832 4.0129434
OS 1.3009074 4.0125156
OS 1.301004 4.0120464
OS 1.3010868 4.0115496
OS 1.3010868 4.0115634
OS 1.3011144 4.011591
OS 1.3011282 4.0116462
OS 1.3011696 4.0117152
OS 1.301211 4.011798
OS 1.3012662 4.0118946
OS 1.3013904 4.0121154
OS 1.3015284 4.0123638
OS 1.301694 4.0126122
OS 1.3018596 4.0128468
OS 1.302039 4.0130676
OS 1.3020528 4.0130814
OS 1.3020804 4.0131228
OS 1.3021494 4.013178
OS 1.3022184 4.0132608
OS 1.3023288 4.0133574
OS 1.3024392 4.0134678
OS 1.3025772 4.0136058
OS 1.3027428 4.0137438
OS 1.3029222 4.0138956
OS 1.3031154 4.0140612
OS 1.3033224 4.0142406
OS 1.3035432 4.01442
OS 1.3037916 4.0145994
OS 1.30404 4.0147926
OS 1.304592 4.0151652
OS 1.3097808 4.0184634
OS 1.3097808 4.0153032
OS 1.3058064 4.0127778
OS 1.3057926 4.012764
OS 1.3057374 4.0127226
OS 1.3056408 4.0126674
OS 1.3055304 4.0125984
OS 1.3053786 4.0125018
OS 1.305213 4.0123914
OS 1.3050336 4.0122672
OS 1.3048404 4.012143
OS 1.3044126 4.0118532
OS 1.303971 4.0115496
OS 1.303557 4.011246
OS 1.3033638 4.0110942
OS 1.3031844 4.0109562
OS 1.3031706 4.0109424
OS 1.303143 4.0109286
OS 1.3031016 4.0108872
OS 1.3030326 4.010832
OS 1.302867 4.010694
OS 1.3026738 4.0105284
OS 1.3024668 4.0103214
OS 1.302246 4.0101144
OS 1.3020528 4.0098936
OS 1.301901 4.0096728
OS 1.3018872 4.0096452
OS 1.3018458 4.0095762
OS 1.3017768 4.0094658
OS 1.3017078 4.009314
OS 1.301625 4.0091484
OS 1.3015284 4.0089552
OS 1.3014594 4.0087482
OS 1.3013904 4.0085274
OS 1.3013904 4.0085136
OS 1.3013766 4.0084446
OS 1.3013628 4.0083342
OS 1.3013352 4.0081962
OS 1.3013214 4.008003
OS 1.3013076 4.0077546
OS 1.3012938 4.0074648
OS 1.3012938 4.0041942
OS 1.3097808 4.0041942
OS 1.3097808 4.0016688
OS 1.2906816 4.0016688
OS 1.2906816 4.0103766
OS 1.2906954 4.0105422
OE
OB 1.292793 4.0102248 H
OS 1.292793 4.0041942
OS 1.2990996 4.0041942
OS 1.2990996 4.0099074
OS 1.2990858 4.0100454
OS 1.2990858 4.0102248
OS 1.299072 4.0104042
OS 1.2990582 4.0106112
OS 1.2990168 4.011039
OS 1.2989478 4.0114944
OS 1.298865 4.011936
OS 1.2988098 4.0121292
OS 1.2987546 4.0123224
OS 1.2987546 4.0123362
OS 1.2987408 4.0123638
OS 1.2987132 4.012419
OS 1.2986856 4.012488
OS 1.2986442 4.0125708
OS 1.2986028 4.0126536
OS 1.2984786 4.0128744
OS 1.298313 4.0131228
OS 1.2981198 4.0133712
OS 1.2978852 4.0136058
OS 1.2976092 4.0138128
OS 1.2975954 4.0138128
OS 1.2975678 4.0138404
OS 1.2975264 4.0138542
OS 1.2974712 4.0138956
OS 1.2974022 4.013937
OS 1.2973056 4.0139784
OS 1.2970986 4.014075
OS 1.2968502 4.0141578
OS 1.2965604 4.0142406
OS 1.296243 4.0142958
OS 1.295898 4.0143234
OS 1.2958842 4.0143234
OS 1.2958428 4.0143234
OS 1.2957738 4.0143234
OS 1.2956772 4.0143096
OS 1.295553 4.0142958
OS 1.2954288 4.0142682
OS 1.295277 4.0142406
OS 1.2951114 4.0141992
OS 1.2949458 4.014144
OS 1.2947664 4.014075
OS 1.2945732 4.014006
OS 1.2943938 4.0139094
OS 1.2942006 4.0137852
OS 1.2940212 4.013661
OS 1.2938418 4.0135092
OS 1.2936762 4.0133298
OS 1.2936624 4.013316
OS 1.2936348 4.0132884
OS 1.2935934 4.0132194
OS 1.2935382 4.0131504
OS 1.2934692 4.01304
OS 1.2934002 4.012902
OS 1.2933174 4.0127502
OS 1.2932346 4.0125708
OS 1.2931518 4.0123776
OS 1.293069 4.012143
OS 1.293 4.0118808
OS 1.292931 4.0116048
OS 1.2928758 4.0113012
OS 1.2928344 4.01097
OS 1.2928068 4.0106112
OS 1.292793 4.0102248
OE
SE
S P 0
OB 2.1591076 3.9429751 I
OS 2.1591076 3.9427543
OS 2.1590938 3.9425059
OS 2.15908 3.9422437
OS 2.1590524 3.9419401
OS 2.1590248 3.9416365
OS 2.1589972 3.9413191
OS 2.1589006 3.9406705
OS 2.1588454 3.9403669
OS 2.1587764 3.9400633
OS 2.1586936 3.9397735
OS 2.158597 3.9395113
OS 2.158597 3.9394975
OS 2.1585694 3.9394561
OS 2.1585418 3.9393871
OS 2.1585004 3.9392905
OS 2.1584452 3.9391801
OS 2.1583624 3.9390559
OS 2.1582796 3.9389041
OS 2.158183 3.9387523
OS 2.1580588 3.9385867
OS 2.1579346 3.9384073
OS 2.1577828 3.9382279
OS 2.1576172 3.9380485
OS 2.157424 3.9378829
OS 2.1572308 3.9377035
OS 2.15701 3.9375379
OS 2.1567754 3.9373861
OS 2.1567616 3.9373723
OS 2.1567202 3.9373447
OS 2.1566512 3.9373171
OS 2.1565546 3.9372619
OS 2.1564304 3.9372067
OS 2.1562786 3.9371377
OS 2.156113 3.9370549
OS 2.1559336 3.9369859
OS 2.1557266 3.9369169
OS 2.1555058 3.9368341
OS 2.1552712 3.9367651
OS 2.1550228 3.9367099
OS 2.1547606 3.9366547
OS 2.1544846 3.9366133
OS 2.1541948 3.9365995
OS 2.153905 3.9365857
OS 2.1538774 3.9365857
OS 2.1538222 3.9365857
OS 2.1537118 3.9365995
OS 2.15356 3.9365995
OS 2.1533944 3.9366271
OS 2.1531874 3.9366547
OS 2.1529666 3.9366961
OS 2.1527182 3.9367513
OS 2.152456 3.9368203
OS 2.15218 3.9369031
OS 2.1518902 3.9370135
OS 2.1516004 3.9371377
OS 2.1513106 3.9372895
OS 2.1510346 3.9374689
OS 2.1507448 3.9376759
OS 2.1504826 3.9379105
OS 2.1504688 3.9379243
OS 2.1504274 3.9379657
OS 2.1503584 3.9380485
OS 2.1502618 3.9381589
OS 2.1501514 3.9382969
OS 2.1500272 3.9384763
OS 2.1498892 3.9386695
OS 2.1497374 3.9389041
OS 2.1495856 3.9391801
OS 2.1494338 3.9394699
OS 2.1492958 3.9398149
OS 2.149144 3.9401737
OS 2.1490198 3.9405739
OS 2.1488956 3.9410017
OS 2.148799 3.9414709
OS 2.1487162 3.9419677
OS 2.1487162 3.9419539
OS 2.1486886 3.9419263
OS 2.1486748 3.9418711
OS 2.1486334 3.9418021
OS 2.148592 3.9417193
OS 2.1485368 3.9416227
OS 2.1484126 3.9414019
OS 2.1482746 3.9411535
OS 2.148109 3.9409051
OS 2.1479434 3.9406705
OS 2.147764 3.9404497
OS 2.1477502 3.9404359
OS 2.1477226 3.9403945
OS 2.1476536 3.9403393
OS 2.1475846 3.9402565
OS 2.1474742 3.9401599
OS 2.1473638 3.9400495
OS 2.1472258 3.9399115
OS 2.1470602 3.9397735
OS 2.1468808 3.9396217
OS 2.1466876 3.9394561
OS 2.1464806 3.9392767
OS 2.1462598 3.9390973
OS 2.1460114 3.9389179
OS 2.145763 3.9387247
OS 2.145211 3.9383521
OS 2.1400222 3.9350539
OS 2.1400222 3.9382141
OS 2.1439966 3.9407395
OS 2.1440104 3.9407533
OS 2.1440656 3.9407947
OS 2.1441622 3.9408499
OS 2.1442726 3.9409189
OS 2.1444244 3.9410155
OS 2.14459 3.9411259
OS 2.1447694 3.9412501
OS 2.1449626 3.9413743
OS 2.1453904 3.9416641
OS 2.145832 3.9419677
OS 2.146246 3.9422713
OS 2.1464392 3.9424231
OS 2.1466186 3.9425611
OS 2.1466324 3.9425749
OS 2.14666 3.9425887
OS 2.1467014 3.9426301
OS 2.1467704 3.9426853
OS 2.146936 3.9428233
OS 2.1471292 3.9429889
OS 2.1473362 3.9431959
OS 2.147557 3.9434029
OS 2.1477502 3.9436237
OS 2.147902 3.9438445
OS 2.1479158 3.9438721
OS 2.1479572 3.9439411
OS 2.1480262 3.9440515
OS 2.1480952 3.9442033
OS 2.148178 3.9443689
OS 2.1482746 3.9445621
OS 2.1483436 3.9447691
OS 2.1484126 3.9449899
OS 2.1484126 3.9450037
OS 2.1484264 3.9450727
OS 2.1484402 3.9451831
OS 2.1484678 3.9453211
OS 2.1484816 3.9455143
OS 2.1484954 3.9457627
OS 2.1485092 3.9460525
OS 2.1485092 3.9493231
OS 2.1400222 3.9493231
OS 2.1400222 3.9518485
OS 2.1591214 3.9518485
OS 2.1591214 3.9431407
OS 2.1591076 3.9429751
OE
OB 2.1400222 3.9247453 I
OS 2.1400222 3.9270913
OS 2.1549538 3.9270913
OS 2.15494 3.9271051
OS 2.1549124 3.9271327
OS 2.154871 3.9271741
OS 2.1548158 3.9272431
OS 2.1547468 3.9273259
OS 2.1546502 3.9274363
OS 2.1545536 3.9275605
OS 2.1544432 3.9276847
OS 2.1543328 3.9278503
OS 2.1541948 3.9280159
OS 2.1540706 3.9281953
OS 2.1539188 3.9283885
OS 2.1537808 3.9286093
OS 2.153629 3.9288301
OS 2.1533254 3.9293269
OS 2.1533116 3.9293407
OS 2.153284 3.9293821
OS 2.1532426 3.9294649
OS 2.1532012 3.9295615
OS 2.1531322 3.9296719
OS 2.1530494 3.9298099
OS 2.1529666 3.9299755
OS 2.15287 3.9301411
OS 2.1526768 3.9305275
OS 2.1524836 3.9309415
OS 2.1522904 3.9313693
OS 2.1521248 3.9317833
OS 2.154388 3.9317833
OS 2.1544018 3.9317557
OS 2.1544294 3.9317005
OS 2.1544846 3.9315901
OS 2.1545536 3.9314521
OS 2.1546364 3.9312865
OS 2.1547468 3.9310795
OS 2.154871 3.9308587
OS 2.155009 3.9306241
OS 2.1551746 3.9303619
OS 2.1553402 3.9300859
OS 2.1557266 3.9295063
OS 2.1561544 3.9289129
OS 2.1566236 3.9283471
OS 2.1566374 3.9283333
OS 2.1566788 3.9282781
OS 2.1567478 3.9282091
OS 2.1568444 3.9281125
OS 2.1569686 3.9279883
OS 2.1571066 3.9278503
OS 2.1572722 3.9276985
OS 2.1574378 3.9275329
OS 2.157631 3.9273673
OS 2.157838 3.9271879
OS 2.1582658 3.9268429
OS 2.1587212 3.9265255
OS 2.1589558 3.9263875
OS 2.1591904 3.9262633
OS 2.1591904 3.9247453
OS 2.1400222 3.9247453
OE
OB 2.1591766 3.9121459 I
OS 2.1591628 3.9119527
OS 2.159149 3.9117181
OS 2.1591076 3.9114559
OS 2.1590662 3.9111523
OS 2.1589972 3.9108349
OS 2.1589144 3.9104899
OS 2.1588178 3.9101449
OS 2.1586936 3.9097723
OS 2.1585418 3.9094135
OS 2.1583624 3.9090547
OS 2.1581692 3.9087097
OS 2.1579346 3.9083785
OS 2.1576586 3.9080611
OS 2.1576448 3.9080473
OS 2.1575896 3.9079921
OS 2.1575068 3.9079093
OS 2.1573826 3.9078127
OS 2.1572446 3.9076885
OS 2.1570652 3.9075505
OS 2.1568582 3.9073987
OS 2.1566236 3.9072469
OS 2.1563614 3.9071089
OS 2.1560716 3.9069571
OS 2.1557542 3.9068191
OS 2.155423 3.9066949
OS 2.1550642 3.9065983
OS 2.1546916 3.9065155
OS 2.1542914 3.9064603
OS 2.1538774 3.9064465
OS 2.1538636 3.9064465
OS 2.1538222 3.9064465
OS 2.153767 3.9064465
OS 2.1536842 3.9064465
OS 2.1535738 3.9064603
OS 2.1534634 3.9064741
OS 2.1533254 3.9064879
OS 2.1531736 3.9065017
OS 2.1528286 3.9065569
OS 2.1524422 3.9066397
OS 2.152042 3.9067639
OS 2.151628 3.9069157
OS 2.1516142 3.9069157
OS 2.1515728 3.9069433
OS 2.1515176 3.9069709
OS 2.1514348 3.9070123
OS 2.1513382 3.9070537
OS 2.151214 3.9071227
OS 2.151076 3.9071917
OS 2.1509242 3.9072883
OS 2.1507586 3.9073849
OS 2.1505792 3.9074953
OS 2.150179 3.9077713
OS 2.149972 3.9079231
OS 2.1497512 3.9080887
OS 2.1495304 3.9082819
OS 2.1492958 3.9084751
OS 2.149282 3.9084889
OS 2.1492406 3.9085303
OS 2.1491716 3.9085855
OS 2.149075 3.9086821
OS 2.1489508 3.9088063
OS 2.148799 3.9089581
OS 2.1486196 3.9091237
OS 2.1484126 3.9093307
OS 2.1481918 3.9095653
OS 2.1479434 3.9098413
OS 2.1476674 3.9101311
OS 2.1473638 3.9104623
OS 2.1470464 3.9108211
OS 2.1467014 3.9112075
OS 2.1463288 3.9116353
OS 2.1459424 3.9120907
OS 2.1459286 3.9121183
OS 2.1458596 3.9121873
OS 2.1457768 3.9122839
OS 2.1456526 3.9124219
OS 2.1455146 3.9126013
OS 2.145349 3.9127807
OS 2.1451696 3.9129877
OS 2.1449764 3.9132085
OS 2.1445762 3.9136777
OS 2.1443692 3.9138985
OS 2.144176 3.9141193
OS 2.1439828 3.9143263
OS 2.1438172 3.9145057
OS 2.1436654 3.9146713
OS 2.1435274 3.9147955
OS 2.1434998 3.9148231
OS 2.143417 3.9148921
OS 2.1432928 3.9150025
OS 2.143141 3.9151405
OS 2.1429478 3.9152923
OS 2.1427408 3.9154579
OS 2.1425062 3.9156235
OS 2.1422716 3.9157753
OS 2.1422716 3.9064189
OS 2.1400222 3.9064189
OS 2.1400222 3.9190321
OS 2.140036 3.9190321
OS 2.1400636 3.9190321
OS 2.140105 3.9190321
OS 2.1401602 3.9190321
OS 2.140243 3.9190321
OS 2.1403258 3.9190183
OS 2.1405466 3.9190045
OS 2.1407812 3.9189769
OS 2.1410572 3.9189355
OS 2.141347 3.9188665
OS 2.1416368 3.9187699
OS 2.1416506 3.9187699
OS 2.141692 3.9187423
OS 2.141761 3.9187147
OS 2.1418576 3.9186733
OS 2.1419818 3.9186319
OS 2.1421198 3.9185629
OS 2.1422716 3.9184801
OS 2.1424372 3.9183973
OS 2.1426304 3.9183007
OS 2.1428236 3.9181765
OS 2.1432514 3.9179143
OS 2.1437068 3.9175969
OS 2.144176 3.9172243
OS 2.1441898 3.9172105
OS 2.1442312 3.9171691
OS 2.1443002 3.9171139
OS 2.1443968 3.9170311
OS 2.144521 3.9169207
OS 2.144659 3.9167827
OS 2.1448246 3.9166309
OS 2.145004 3.9164377
OS 2.145211 3.9162307
OS 2.1454318 3.9160099
OS 2.1456664 3.9157615
OS 2.1459286 3.9154855
OS 2.1461908 3.9151819
OS 2.1464668 3.9148645
OS 2.1467566 3.9145195
OS 2.1470602 3.9141607
OS 2.147074 3.9141469
OS 2.1470878 3.9141193
OS 2.1471292 3.9140779
OS 2.1471706 3.9140227
OS 2.1472396 3.9139537
OS 2.1473086 3.9138709
OS 2.147488 3.9136639
OS 2.147695 3.9134017
OS 2.1479572 3.9131257
OS 2.1482332 3.9128083
OS 2.1485368 3.9124771
OS 2.1488542 3.9121183
OS 2.1491854 3.9117733
OS 2.1495166 3.9114145
OS 2.1498616 3.9110833
OS 2.1501928 3.9107521
OS 2.1505102 3.9104623
OS 2.1508276 3.9101863
OS 2.1511174 3.9099655
OS 2.1511312 3.9099517
OS 2.1511864 3.9099241
OS 2.1512692 3.9098689
OS 2.1513658 3.9097861
OS 2.1515038 3.9097033
OS 2.1516556 3.9096205
OS 2.151835 3.9095101
OS 2.1520282 3.9094135
OS 2.1522352 3.9093169
OS 2.152456 3.9092065
OS 2.152939 3.9090271
OS 2.1531874 3.9089581
OS 2.1534358 3.9089029
OS 2.1536842 3.9088753
OS 2.1539326 3.9088615
OS 2.1539464 3.9088615
OS 2.1540016 3.9088615
OS 2.1540706 3.9088615
OS 2.1541672 3.9088753
OS 2.1542914 3.9088891
OS 2.1544294 3.9089167
OS 2.1545812 3.9089443
OS 2.1547468 3.9089857
OS 2.1549262 3.9090409
OS 2.1551194 3.9091099
OS 2.1553126 3.9091927
OS 2.1555058 3.9092893
OS 2.1557128 3.9093997
OS 2.155906 3.9095377
OS 2.1560992 3.9096895
OS 2.1562786 3.9098689
OS 2.1562924 3.9098827
OS 2.15632 3.9099103
OS 2.1563614 3.9099655
OS 2.1564304 3.9100483
OS 2.1564994 3.9101449
OS 2.1565822 3.9102691
OS 2.1566788 3.9104071
OS 2.1567616 3.9105589
OS 2.1568582 3.9107383
OS 2.156941 3.9109315
OS 2.1570238 3.9111523
OS 2.1570928 3.9113731
OS 2.1571618 3.9116215
OS 2.1572032 3.9118837
OS 2.1572308 3.9121597
OS 2.1572446 3.9124495
OS 2.1572446 3.9126151
OS 2.1572308 3.9127255
OS 2.157217 3.9128773
OS 2.1571894 3.9130429
OS 2.1571618 3.9132223
OS 2.1571204 3.9134293
OS 2.1570652 3.9136363
OS 2.1569962 3.9138571
OS 2.1569134 3.9140779
OS 2.1568168 3.9143125
OS 2.1566926 3.9145333
OS 2.1565546 3.9147541
OS 2.1564028 3.9149749
OS 2.1562234 3.9151681
OS 2.1562096 3.9151819
OS 2.156182 3.9152095
OS 2.156113 3.9152647
OS 2.156044 3.9153199
OS 2.1559336 3.9154027
OS 2.1558094 3.9154855
OS 2.1556576 3.9155821
OS 2.155492 3.9156649
OS 2.1553126 3.9157615
OS 2.1550918 3.9158581
OS 2.154871 3.9159409
OS 2.1546226 3.9160237
OS 2.1543466 3.9160789
OS 2.1540568 3.9161341
OS 2.1537532 3.9161617
OS 2.153422 3.9161755
OS 2.1536704 3.9185905
OS 2.1536842 3.9185905
OS 2.153698 3.9185905
OS 2.1537394 3.9185767
OS 2.1537946 3.9185767
OS 2.1539326 3.9185629
OS 2.154112 3.9185215
OS 2.1543328 3.9184801
OS 2.154595 3.9184249
OS 2.1548848 3.9183559
OS 2.1551884 3.9182731
OS 2.1555196 3.9181627
OS 2.1558508 3.9180385
OS 2.1561958 3.9178867
OS 2.1565408 3.9177073
OS 2.156872 3.9175141
OS 2.1571894 3.9172795
OS 2.157493 3.9170311
OS 2.157769 3.9167413
OS 2.1577828 3.9167275
OS 2.1578242 3.9166723
OS 2.157907 3.9165757
OS 2.1579898 3.9164515
OS 2.1581002 3.9162859
OS 2.1582244 3.9160927
OS 2.1583486 3.9158581
OS 2.1584866 3.9155959
OS 2.1586108 3.9152923
OS 2.158735 3.9149749
OS 2.1588592 3.9146161
OS 2.1589696 3.9142297
OS 2.1590662 3.9138157
OS 2.1591352 3.9133741
OS 2.1591766 3.9129049
OS 2.1591904 3.9124081
OS 2.1591904 3.9122839
OS 2.1591766 3.9121459
OE
OB 2.15701 3.9432925 H
OS 2.15701 3.9493231
OS 2.1507034 3.9493231
OS 2.1507034 3.9436099
OS 2.1507172 3.9434719
OS 2.1507172 3.9432925
OS 2.150731 3.9431131
OS 2.1507448 3.9429061
OS 2.1507862 3.9424783
OS 2.1508552 3.9420229
OS 2.150938 3.9415813
OS 2.1509932 3.9413881
OS 2.1510484 3.9411949
OS 2.1510484 3.9411811
OS 2.1510622 3.9411535
OS 2.1510898 3.9410983
OS 2.1511174 3.9410293
OS 2.1511588 3.9409465
OS 2.1512002 3.9408637
OS 2.1513244 3.9406429
OS 2.15149 3.9403945
OS 2.1516832 3.9401461
OS 2.1519178 3.9399115
OS 2.1521938 3.9397045
OS 2.1522076 3.9397045
OS 2.1522352 3.9396769
OS 2.1522766 3.9396631
OS 2.1523318 3.9396217
OS 2.1524008 3.9395803
OS 2.1524974 3.9395389
OS 2.1527044 3.9394423
OS 2.1529528 3.9393595
OS 2.1532426 3.9392767
OS 2.15356 3.9392215
OS 2.153905 3.9391939
OS 2.1539188 3.9391939
OS 2.1539602 3.9391939
OS 2.1540292 3.9391939
OS 2.1541258 3.9392077
OS 2.15425 3.9392215
OS 2.1543742 3.9392491
OS 2.154526 3.9392767
OS 2.1546916 3.9393181
OS 2.1548572 3.9393733
OS 2.1550366 3.9394423
OS 2.1552298 3.9395113
OS 2.1554092 3.9396079
OS 2.1556024 3.9397321
OS 2.1557818 3.9398563
OS 2.1559612 3.9400081
OS 2.1561268 3.9401875
OS 2.1561406 3.9402013
OS 2.1561682 3.9402289
OS 2.1562096 3.9402979
OS 2.1562648 3.9403669
OS 2.1563338 3.9404773
OS 2.1564028 3.9406153
OS 2.1564856 3.9407671
OS 2.1565684 3.9409465
OS 2.1566512 3.9411397
OS 2.156734 3.9413743
OS 2.156803 3.9416365
OS 2.156872 3.9419125
OS 2.1569272 3.9422161
OS 2.1569686 3.9425473
OS 2.1569962 3.9429061
OS 2.15701 3.9432925
OE
SE
S P 0
OB 2.221288 3.9440559 I
OS 2.221288 3.9438351
OS 2.2212742 3.9435867
OS 2.2212604 3.9433245
OS 2.2212328 3.9430209
OS 2.2212052 3.9427173
OS 2.2211776 3.9423999
OS 2.221081 3.9417513
OS 2.2210258 3.9414477
OS 2.2209568 3.9411441
OS 2.220874 3.9408543
OS 2.2207774 3.9405921
OS 2.2207774 3.9405783
OS 2.2207498 3.9405369
OS 2.2207222 3.9404679
OS 2.2206808 3.9403713
OS 2.2206256 3.9402609
OS 2.2205428 3.9401367
OS 2.22046 3.9399849
OS 2.2203634 3.9398331
OS 2.2202392 3.9396675
OS 2.220115 3.9394881
OS 2.2199632 3.9393087
OS 2.2197976 3.9391293
OS 2.2196044 3.9389637
OS 2.2194112 3.9387843
OS 2.2191904 3.9386187
OS 2.2189558 3.9384669
OS 2.218942 3.9384531
OS 2.2189006 3.9384255
OS 2.2188316 3.9383979
OS 2.218735 3.9383427
OS 2.2186108 3.9382875
OS 2.218459 3.9382185
OS 2.2182934 3.9381357
OS 2.218114 3.9380667
OS 2.217907 3.9379977
OS 2.2176862 3.9379149
OS 2.2174516 3.9378459
OS 2.2172032 3.9377907
OS 2.216941 3.9377355
OS 2.216665 3.9376941
OS 2.2163752 3.9376803
OS 2.2160854 3.9376665
OS 2.2160578 3.9376665
OS 2.2160026 3.9376665
OS 2.2158922 3.9376803
OS 2.2157404 3.9376803
OS 2.2155748 3.9377079
OS 2.2153678 3.9377355
OS 2.215147 3.9377769
OS 2.2148986 3.9378321
OS 2.2146364 3.9379011
OS 2.2143604 3.9379839
OS 2.2140706 3.9380943
OS 2.2137808 3.9382185
OS 2.213491 3.9383703
OS 2.213215 3.9385497
OS 2.2129252 3.9387567
OS 2.212663 3.9389913
OS 2.2126492 3.9390051
OS 2.2126078 3.9390465
OS 2.2125388 3.9391293
OS 2.2124422 3.9392397
OS 2.2123318 3.9393777
OS 2.2122076 3.9395571
OS 2.2120696 3.9397503
OS 2.2119178 3.9399849
OS 2.211766 3.9402609
OS 2.2116142 3.9405507
OS 2.2114762 3.9408957
OS 2.2113244 3.9412545
OS 2.2112002 3.9416547
OS 2.211076 3.9420825
OS 2.2109794 3.9425517
OS 2.2108966 3.9430485
OS 2.2108966 3.9430347
OS 2.210869 3.9430071
OS 2.2108552 3.9429519
OS 2.2108138 3.9428829
OS 2.2107724 3.9428001
OS 2.2107172 3.9427035
OS 2.210593 3.9424827
OS 2.210455 3.9422343
OS 2.2102894 3.9419859
OS 2.2101238 3.9417513
OS 2.2099444 3.9415305
OS 2.2099306 3.9415167
OS 2.209903 3.9414753
OS 2.209834 3.9414201
OS 2.209765 3.9413373
OS 2.2096546 3.9412407
OS 2.2095442 3.9411303
OS 2.2094062 3.9409923
OS 2.2092406 3.9408543
OS 2.2090612 3.9407025
OS 2.208868 3.9405369
OS 2.208661 3.9403575
OS 2.2084402 3.9401781
OS 2.2081918 3.9399987
OS 2.2079434 3.9398055
OS 2.2073914 3.9394329
OS 2.2022026 3.9361347
OS 2.2022026 3.9392949
OS 2.206177 3.9418203
OS 2.2061908 3.9418341
OS 2.206246 3.9418755
OS 2.2063426 3.9419307
OS 2.206453 3.9419997
OS 2.2066048 3.9420963
OS 2.2067704 3.9422067
OS 2.2069498 3.9423309
OS 2.207143 3.9424551
OS 2.2075708 3.9427449
OS 2.2080124 3.9430485
OS 2.2084264 3.9433521
OS 2.2086196 3.9435039
OS 2.208799 3.9436419
OS 2.2088128 3.9436557
OS 2.2088404 3.9436695
OS 2.2088818 3.9437109
OS 2.2089508 3.9437661
OS 2.2091164 3.9439041
OS 2.2093096 3.9440697
OS 2.2095166 3.9442767
OS 2.2097374 3.9444837
OS 2.2099306 3.9447045
OS 2.2100824 3.9449253
OS 2.2100962 3.9449529
OS 2.2101376 3.9450219
OS 2.2102066 3.9451323
OS 2.2102756 3.9452841
OS 2.2103584 3.9454497
OS 2.210455 3.9456429
OS 2.210524 3.9458499
OS 2.210593 3.9460707
OS 2.210593 3.9460845
OS 2.2106068 3.9461535
OS 2.2106206 3.9462639
OS 2.2106482 3.9464019
OS 2.210662 3.9465951
OS 2.2106758 3.9468435
OS 2.2106896 3.9471333
OS 2.2106896 3.9504039
OS 2.2022026 3.9504039
OS 2.2022026 3.9529293
OS 2.2213018 3.9529293
OS 2.2213018 3.9442215
OS 2.221288 3.9440559
OE
OB 2.2022026 3.9258261 I
OS 2.2022026 3.9281721
OS 2.2171342 3.9281721
OS 2.2171204 3.9281859
OS 2.2170928 3.9282135
OS 2.2170514 3.9282549
OS 2.2169962 3.9283239
OS 2.2169272 3.9284067
OS 2.2168306 3.9285171
OS 2.216734 3.9286413
OS 2.2166236 3.9287655
OS 2.2165132 3.9289311
OS 2.2163752 3.9290967
OS 2.216251 3.9292761
OS 2.2160992 3.9294693
OS 2.2159612 3.9296901
OS 2.2158094 3.9299109
OS 2.2155058 3.9304077
OS 2.215492 3.9304215
OS 2.2154644 3.9304629
OS 2.215423 3.9305457
OS 2.2153816 3.9306423
OS 2.2153126 3.9307527
OS 2.2152298 3.9308907
OS 2.215147 3.9310563
OS 2.2150504 3.9312219
OS 2.2148572 3.9316083
OS 2.214664 3.9320223
OS 2.2144708 3.9324501
OS 2.2143052 3.9328641
OS 2.2165684 3.9328641
OS 2.2165822 3.9328365
OS 2.2166098 3.9327813
OS 2.216665 3.9326709
OS 2.216734 3.9325329
OS 2.2168168 3.9323673
OS 2.2169272 3.9321603
OS 2.2170514 3.9319395
OS 2.2171894 3.9317049
OS 2.217355 3.9314427
OS 2.2175206 3.9311667
OS 2.217907 3.9305871
OS 2.2183348 3.9299937
OS 2.218804 3.9294279
OS 2.2188178 3.9294141
OS 2.2188592 3.9293589
OS 2.2189282 3.9292899
OS 2.2190248 3.9291933
OS 2.219149 3.9290691
OS 2.219287 3.9289311
OS 2.2194526 3.9287793
OS 2.2196182 3.9286137
OS 2.2198114 3.9284481
OS 2.2200184 3.9282687
OS 2.2204462 3.9279237
OS 2.2209016 3.9276063
OS 2.2211362 3.9274683
OS 2.2213708 3.9273441
OS 2.2213708 3.9258261
OS 2.2022026 3.9258261
OE
OB 2.221357 3.9135717 I
OS 2.221357 3.9134337
OS 2.2213294 3.9132681
OS 2.2213156 3.9130887
OS 2.221288 3.9128955
OS 2.2212466 3.9126747
OS 2.2212052 3.9124539
OS 2.221081 3.9119709
OS 2.221012 3.9117087
OS 2.2209154 3.9114603
OS 2.2208188 3.9112119
OS 2.2206946 3.9109635
OS 2.2206808 3.9109497
OS 2.220667 3.9109083
OS 2.2206256 3.9108393
OS 2.2205704 3.9107427
OS 2.2205014 3.9106323
OS 2.2204186 3.9105081
OS 2.220322 3.9103701
OS 2.2202116 3.9102183
OS 2.2199494 3.9098871
OS 2.219632 3.9095559
OS 2.2192732 3.9092385
OS 2.2190662 3.9090867
OS 2.2188592 3.9089487
OS 2.2188454 3.9089349
OS 2.218804 3.9089211
OS 2.2187488 3.9088797
OS 2.2186522 3.9088383
OS 2.2185556 3.9087831
OS 2.2184176 3.9087279
OS 2.2182796 3.9086589
OS 2.218114 3.9085899
OS 2.2179346 3.9085347
OS 2.2177552 3.9084657
OS 2.2173412 3.9083553
OS 2.2168858 3.9082725
OS 2.2166512 3.9082587
OS 2.2164028 3.9082449
OS 2.216389 3.9082449
OS 2.2163476 3.9082449
OS 2.2162786 3.9082449
OS 2.2161958 3.9082587
OS 2.2160854 3.9082587
OS 2.2159612 3.9082863
OS 2.2158094 3.9083001
OS 2.2156576 3.9083277
OS 2.2152988 3.9084105
OS 2.2149262 3.9085347
OS 2.214733 3.9086037
OS 2.214526 3.9087003
OS 2.2143328 3.9087969
OS 2.2141396 3.9089211
OS 2.2141258 3.9089349
OS 2.2140982 3.9089487
OS 2.214043 3.9089901
OS 2.213974 3.9090453
OS 2.2138912 3.9091143
OS 2.2137946 3.9091971
OS 2.2136842 3.9092937
OS 2.21356 3.9094179
OS 2.2134358 3.9095421
OS 2.2133116 3.9096939
OS 2.2131736 3.9098457
OS 2.2130356 3.9100251
OS 2.2129114 3.9102183
OS 2.2127734 3.9104253
OS 2.2126492 3.9106461
OS 2.2125388 3.9108807
OS 2.2125388 3.9108669
OS 2.212525 3.9108117
OS 2.2124974 3.9107151
OS 2.212456 3.9106047
OS 2.2124146 3.9104529
OS 2.2123456 3.9102873
OS 2.2122766 3.9101079
OS 2.21218 3.9099147
OS 2.2120834 3.9097077
OS 2.2119592 3.9094869
OS 2.211835 3.9092661
OS 2.2116832 3.9090453
OS 2.2115176 3.9088383
OS 2.2113382 3.9086313
OS 2.2111312 3.9084243
OS 2.2109104 3.9082449
OS 2.2108966 3.9082311
OS 2.2108552 3.9082035
OS 2.2107862 3.9081621
OS 2.2106896 3.9080931
OS 2.2105654 3.9080241
OS 2.2104274 3.9079413
OS 2.2102618 3.9078585
OS 2.2100686 3.9077757
OS 2.2098478 3.9076929
OS 2.2096132 3.9075963
OS 2.2093648 3.9075273
OS 2.2090888 3.9074583
OS 2.208799 3.9073893
OS 2.2084954 3.9073479
OS 2.208178 3.9073203
OS 2.207833 3.9073065
OS 2.2078054 3.9073065
OS 2.2077226 3.9073065
OS 2.2075846 3.9073203
OS 2.207419 3.9073341
OS 2.2071982 3.9073617
OS 2.2069498 3.9074031
OS 2.2066738 3.9074583
OS 2.2063702 3.9075411
OS 2.206039 3.9076377
OS 2.2057078 3.9077481
OS 2.205349 3.9078999
OS 2.2049902 3.9080793
OS 2.2046314 3.9082863
OS 2.2042726 3.9085347
OS 2.2039276 3.9088245
OS 2.2035964 3.9091419
OS 2.2035826 3.9091695
OS 2.2035274 3.9092247
OS 2.2034308 3.9093213
OS 2.2033204 3.9094731
OS 2.2031962 3.9096525
OS 2.2030444 3.9098595
OS 2.2028926 3.9101217
OS 2.202727 3.9103977
OS 2.2025614 3.9107151
OS 2.2024096 3.9110739
OS 2.2022578 3.9114465
OS 2.2021336 3.9118605
OS 2.2020232 3.9122883
OS 2.2019266 3.9127575
OS 2.2018714 3.9132405
OS 2.2018576 3.9137511
OS 2.2018576 3.9138615
OS 2.2018714 3.9139995
OS 2.2018852 3.9141651
OS 2.201899 3.9143859
OS 2.2019404 3.9146343
OS 2.2019818 3.9149103
OS 2.2020508 3.9152139
OS 2.2021198 3.9155313
OS 2.2022164 3.9158763
OS 2.2023406 3.9162213
OS 2.2024924 3.9165801
OS 2.202658 3.9169251
OS 2.2028512 3.9172701
OS 2.2030858 3.9176151
OS 2.203348 3.9179325
OS 2.2033618 3.9179463
OS 2.203417 3.9180015
OS 2.2034998 3.9180843
OS 2.203624 3.9181947
OS 2.2037758 3.9183189
OS 2.2039552 3.9184707
OS 2.2041622 3.9186225
OS 2.2043968 3.9187881
OS 2.204659 3.9189537
OS 2.2049626 3.9191193
OS 2.20528 3.9192711
OS 2.205625 3.9194229
OS 2.2059976 3.9195471
OS 2.206384 3.9196713
OS 2.206798 3.9197541
OS 2.2072396 3.9198093
OS 2.207557 3.9174633
OS 2.2075294 3.9174633
OS 2.2074742 3.9174495
OS 2.2073638 3.9174219
OS 2.2072258 3.9173805
OS 2.2070602 3.9173391
OS 2.2068808 3.9172839
OS 2.2066738 3.9172149
OS 2.206453 3.9171459
OS 2.20597 3.9169527
OS 2.2055008 3.9167181
OS 2.2052662 3.9165801
OS 2.2050454 3.9164283
OS 2.2048522 3.9162765
OS 2.2046728 3.9160971
OS 2.204659 3.9160833
OS 2.2046314 3.9160557
OS 2.20459 3.9160005
OS 2.2045348 3.9159177
OS 2.2044658 3.9158349
OS 2.2043968 3.9157107
OS 2.204314 3.9155865
OS 2.204245 3.9154347
OS 2.2041622 3.9152691
OS 2.2040794 3.9150897
OS 2.2040104 3.9148965
OS 2.2039414 3.9146895
OS 2.2038862 3.9144687
OS 2.2038448 3.9142341
OS 2.2038172 3.9139995
OS 2.2038034 3.9137373
OS 2.2038034 3.9136683
OS 2.2038172 3.9135717
OS 2.2038172 3.9134613
OS 2.2038448 3.9133095
OS 2.2038586 3.9131439
OS 2.2039 3.9129645
OS 2.2039414 3.9127575
OS 2.2040104 3.9125505
OS 2.2040794 3.9123159
OS 2.204176 3.9120813
OS 2.2042864 3.9118467
OS 2.2044244 3.9116121
OS 2.2045762 3.9113775
OS 2.2047418 3.9111567
OS 2.2049488 3.9109359
OS 2.2049626 3.9109221
OS 2.205004 3.9108807
OS 2.2050592 3.9108255
OS 2.2051558 3.9107565
OS 2.2052662 3.9106737
OS 2.2054042 3.9105771
OS 2.205556 3.9104667
OS 2.2057354 3.9103563
OS 2.2059286 3.9102597
OS 2.2061494 3.9101493
OS 2.2063702 3.9100527
OS 2.2066324 3.9099699
OS 2.2068946 3.9099009
OS 2.2071706 3.9098457
OS 2.2074742 3.9098043
OS 2.2077778 3.9097905
OS 2.2077916 3.9097905
OS 2.2078468 3.9097905
OS 2.2079296 3.9097905
OS 2.2080538 3.9098043
OS 2.208178 3.9098181
OS 2.2083436 3.9098457
OS 2.208523 3.9098733
OS 2.2087162 3.9099285
OS 2.2089232 3.9099837
OS 2.209144 3.9100527
OS 2.2093648 3.9101355
OS 2.2095856 3.9102321
OS 2.2098064 3.9103563
OS 2.2100272 3.9105081
OS 2.2102342 3.9106599
OS 2.2104412 3.9108531
OS 2.210455 3.9108669
OS 2.2104826 3.9108945
OS 2.2105378 3.9109635
OS 2.2106068 3.9110463
OS 2.2106896 3.9111429
OS 2.2107724 3.9112671
OS 2.210869 3.9114189
OS 2.2109656 3.9115845
OS 2.2110622 3.9117639
OS 2.2111588 3.9119709
OS 2.2112416 3.9121917
OS 2.2113244 3.9124263
OS 2.2113934 3.9126747
OS 2.2114486 3.9129507
OS 2.2114762 3.9132267
OS 2.21149 3.9135303
OS 2.21149 3.9136545
OS 2.2114762 3.9137925
OS 2.2114624 3.9139857
OS 2.2114348 3.9142341
OS 2.2113796 3.9145101
OS 2.2113244 3.9148275
OS 2.2112416 3.9151863
OS 2.2132978 3.9149241
OS 2.2132978 3.9148827
OS 2.213284 3.9148413
OS 2.213284 3.9147861
OS 2.2132702 3.9146619
OS 2.2132702 3.9143997
OS 2.213284 3.9143031
OS 2.2132978 3.9141651
OS 2.2133116 3.9140133
OS 2.2133392 3.9138477
OS 2.2133668 3.9136545
OS 2.2134082 3.9134475
OS 2.2134634 3.9132405
OS 2.2136014 3.9127851
OS 2.2136842 3.9125505
OS 2.2137946 3.9123159
OS 2.213905 3.9120813
OS 2.214043 3.9118605
OS 2.2140568 3.9118467
OS 2.2140844 3.9118053
OS 2.2141258 3.9117501
OS 2.2141948 3.9116673
OS 2.2142776 3.9115845
OS 2.2143742 3.9114741
OS 2.2144984 3.9113775
OS 2.2146364 3.9112533
OS 2.214802 3.9111429
OS 2.2149814 3.9110325
OS 2.2151746 3.9109359
OS 2.2153954 3.9108531
OS 2.21563 3.9107703
OS 2.2158922 3.9107151
OS 2.2161682 3.9106737
OS 2.216458 3.9106599
OS 2.2164718 3.9106599
OS 2.2165132 3.9106599
OS 2.2165822 3.9106599
OS 2.2166788 3.9106737
OS 2.2167754 3.9106875
OS 2.2169134 3.9107013
OS 2.2170514 3.9107289
OS 2.2172032 3.9107703
OS 2.2175344 3.9108807
OS 2.2177138 3.9109497
OS 2.2178932 3.9110325
OS 2.2180726 3.9111291
OS 2.218252 3.9112533
OS 2.2184176 3.9113913
OS 2.2185832 3.9115431
OS 2.218597 3.9115569
OS 2.2186246 3.9115845
OS 2.218666 3.9116259
OS 2.2187212 3.9116949
OS 2.2187764 3.9117915
OS 2.2188592 3.9118881
OS 2.2189282 3.9120123
OS 2.219011 3.9121503
OS 2.2190938 3.9123021
OS 2.2191628 3.9124677
OS 2.2192456 3.9126609
OS 2.2193008 3.9128541
OS 2.219356 3.9130749
OS 2.2193974 3.9132957
OS 2.219425 3.9135441
OS 2.2194388 3.9137925
OS 2.2194388 3.9139305
OS 2.219425 3.9140133
OS 2.2194112 3.9141375
OS 2.2193974 3.9142755
OS 2.2193698 3.9144273
OS 2.2193284 3.9145929
OS 2.2192318 3.9149517
OS 2.2191628 3.9151311
OS 2.2190662 3.9153243
OS 2.2189696 3.9155175
OS 2.2188592 3.9157107
OS 2.2187212 3.9158901
OS 2.2185694 3.9160695
OS 2.2185556 3.9160833
OS 2.218528 3.9161109
OS 2.2184728 3.9161523
OS 2.2184038 3.9162213
OS 2.218321 3.9162903
OS 2.2182106 3.9163731
OS 2.2180726 3.9164559
OS 2.2179346 3.9165525
OS 2.2177552 3.9166491
OS 2.217562 3.9167457
OS 2.217355 3.9168561
OS 2.2171204 3.9169389
OS 2.216872 3.9170355
OS 2.2166098 3.9171045
OS 2.21632 3.9171735
OS 2.2160026 3.9172287
OS 2.2164166 3.9195747
OS 2.2164304 3.9195747
OS 2.2164442 3.9195747
OS 2.216527 3.9195471
OS 2.2166374 3.9195195
OS 2.216803 3.9194781
OS 2.21701 3.9194229
OS 2.2172308 3.9193539
OS 2.2174792 3.9192711
OS 2.2177552 3.9191745
OS 2.218045 3.9190503
OS 2.2183486 3.9189123
OS 2.2186522 3.9187467
OS 2.2189558 3.9185673
OS 2.2192594 3.9183741
OS 2.2195492 3.9181533
OS 2.2198252 3.9179049
OS 2.2200736 3.9176289
OS 2.2200874 3.9176151
OS 2.2201288 3.9175599
OS 2.2201978 3.9174771
OS 2.2202806 3.9173529
OS 2.2203772 3.9172011
OS 2.2204876 3.9170217
OS 2.220598 3.9168147
OS 2.2207222 3.9165801
OS 2.2208464 3.9163179
OS 2.2209568 3.9160281
OS 2.2210672 3.9157245
OS 2.2211638 3.9153933
OS 2.2212466 3.9150345
OS 2.2213156 3.9146481
OS 2.221357 3.9142479
OS 2.2213708 3.9138339
OS 2.2213708 3.9136821
OS 2.221357 3.9135717
OE
OB 2.2191904 3.9443733 H
OS 2.2191904 3.9504039
OS 2.2128838 3.9504039
OS 2.2128838 3.9446907
OS 2.2128976 3.9445527
OS 2.2128976 3.9443733
OS 2.2129114 3.9441939
OS 2.2129252 3.9439869
OS 2.2129666 3.9435591
OS 2.2130356 3.9431037
OS 2.2131184 3.9426621
OS 2.2131736 3.9424689
OS 2.2132288 3.9422757
OS 2.2132288 3.9422619
OS 2.2132426 3.9422343
OS 2.2132702 3.9421791
OS 2.2132978 3.9421101
OS 2.2133392 3.9420273
OS 2.2133806 3.9419445
OS 2.2135048 3.9417237
OS 2.2136704 3.9414753
OS 2.2138636 3.9412269
OS 2.2140982 3.9409923
OS 2.2143742 3.9407853
OS 2.214388 3.9407853
OS 2.2144156 3.9407577
OS 2.214457 3.9407439
OS 2.2145122 3.9407025
OS 2.2145812 3.9406611
OS 2.2146778 3.9406197
OS 2.2148848 3.9405231
OS 2.2151332 3.9404403
OS 2.215423 3.9403575
OS 2.2157404 3.9403023
OS 2.2160854 3.9402747
OS 2.2160992 3.9402747
OS 2.2161406 3.9402747
OS 2.2162096 3.9402747
OS 2.2163062 3.9402885
OS 2.2164304 3.9403023
OS 2.2165546 3.9403299
OS 2.2167064 3.9403575
OS 2.216872 3.9403989
OS 2.2170376 3.9404541
OS 2.217217 3.9405231
OS 2.2174102 3.9405921
OS 2.2175896 3.9406887
OS 2.2177828 3.9408129
OS 2.2179622 3.9409371
OS 2.2181416 3.9410889
OS 2.2183072 3.9412683
OS 2.218321 3.9412821
OS 2.2183486 3.9413097
OS 2.21839 3.9413787
OS 2.2184452 3.9414477
OS 2.2185142 3.9415581
OS 2.2185832 3.9416961
OS 2.218666 3.9418479
OS 2.2187488 3.9420273
OS 2.2188316 3.9422205
OS 2.2189144 3.9424551
OS 2.2189834 3.9427173
OS 2.2190524 3.9429933
OS 2.2191076 3.9432969
OS 2.219149 3.9436281
OS 2.2191766 3.9439869
OS 2.2191904 3.9443733
OE
SE

### steps/pcb/layers/top_paste/features
#Layer_Color=8421504
#
#Feature symbol names
#
$0 r3.937
$1 r1
$2 rect61.02x9.84
$3 rect66.93x53.15
$4 rect9.84x61.02
$5 rect53.15x66.93
$6 rect28x165
$7 rect28x126
$8 rect9.8425x10.8268
$9 rect10.8268x9.8425
$10 rect28.3465x39.3701
$11 rect39.3701x33.4646
$12 rect27.5591x35.4331
$13 rect82.874x44.0945
$14 rect35.4331x27.5591
$15 rect70.8661x9.8425
$16 rect165.3543x125.9843
$17 oval78.7402x23.622
$18 rect25.5906x41.3386
$19 rect39.3701x37.4016
$20 rect64.9606x51.1811
$21 rect17.7165x54.3307
$22 rect55.9055x61.0236
$23 rect70.8661x74.8031
$24 rect39.3701x74.8031
$25 rect19.685x90.5512
$26 rect78.7402x98.4252
$27 rect86.6142x41.3386
$28 rect41.3386x39.3701
$29 rect19.685x35.4331
$30 oval57.0866x17.7165
$31 rect77.5591x22.4409
$32 rect51.1811x74.8031
$33 rect39.3701x90.5512
$34 rect39.3701x70.8661
$35 rect53.1496x27.5591
$36 rect27.5591x45.2756
$37 rect41.3386x45.2756
$38 rect50x200
$39 rect57.0866x37.4016
$40 rect31.4961x66.9291
$41 rect9.8425x22.6378
$42 rect26.5748x9.8425
$43 rect38.5827x34.252
$44 rect212.5984x114.1732
$45 rect96.4567x124.0157
$46 rect33.4646x39.3701
$47 rect57.0866x45.2756
$48 rect37.4016x39.3701
$49 rect25.1969x26.7717
$50 rect45.2756x57.0866
$51 rect26.7717x25.1969
$52 rect39.3701x28.3465
$53 rect23.622x25.5906
$54 rect25.5906x23.622

#
#Feature attribute names
#
@0 .geometry
@1 .pad_usage

#
#Feature attribute text strings
#
&0 SMD_RectX61.0200Y9.8400
&1 SMD_RectX66.9300Y53.1500
&2 SMD_RectX9.8400Y61.0200
&3 SMD_RectX53.1500Y66.9300
&4 SMD_RectX28.0000Y165.0000
&5 SMD_RectX28.0000Y126.0000
&6 SMD_RectX9.8425Y10.8268
&7 SMD_RectX10.8268Y9.8425
&8 SMD_RectX28.3465Y39.3701
&9 SMD_RectX39.3701Y33.4646
&10 SMD_RectX27.5591Y35.4331
&11 SMD_RectX82.8740Y44.0945
&12 SMD_RectX35.4331Y27.5591
&13 SMD_RectX70.8661Y9.8425
&14 SMD_RectX165.3543Y125.9843
&15 SMD_OvalX78.7402Y23.6220
&16 SMD_RectX25.5906Y41.3386
&17 SMD_RectX39.3701Y37.4016
&18 SMD_RectX64.9606Y51.1811
&19 SMD_RectX17.7165Y54.3307
&20 SMD_RectX55.9055Y61.0236
&21 SMD_RectX70.8661Y74.8031
&22 SMD_RectX39.3701Y74.8031
&23 SMD_RectX19.6850Y90.5512
&24 SMD_RectX78.7402Y98.4252
&25 SMD_RectX86.6142Y41.3386
&26 SMD_RectX41.3386Y39.3701
&27 SMD_RectX19.6850Y35.4331
&28 SMD_OvalX57.0866Y17.7165
&29 SMD_RectX77.5591Y22.4409
&30 SMD_RectX51.1811Y74.8031
&31 SMD_RectX39.3701Y90.5512
&32 SMD_RectX39.3701Y70.8661
&33 SMD_RectX53.1496Y27.5591
&34 SMD_RectX27.5591Y45.2756
&35 SMD_RectX41.3386Y45.2756
&36 SMD_RectX50.0000Y200.0000
&37 SMD_RectX57.0866Y37.4016
&38 SMD_RectX31.4961Y66.9291
&39 SMD_RectX9.8425Y22.6378
&40 SMD_RectX26.5748Y9.8425
&41 SMD_RectX38.5827Y34.2520
&42 SMD_RectX212.5984Y114.1732
&43 SMD_RectX96.4567Y124.0157
&44 SMD_RectX33.4646Y39.3701
&45 SMD_RectX57.0866Y45.2756
&46 SMD_RectX37.4016Y39.3701
&47 SMD_RectX25.1969Y26.7717
&48 SMD_RectX45.2756Y57.0866
&49 SMD_RectX26.7717Y25.1969
&50 SMD_RectX39.3701Y28.3465
&51 SMD_RectX23.6220Y25.5906
&52 SMD_RectX25.5906Y23.6220

#
#Layer features
#
A 1.7712204 0.4310709 1.6275196 0.4310709 1.69937 0.4310709 0 P 0 N
L -0.0001175 0.177913 0.5908825 0.177913 1 P 0
L -0.0004331 0.1781182 0.5901181 0.1781182 0 P 0
L 0.5901181 0.1781182 0.5901181 0.5029213 0 P 0
L 0.5901181 0.5029213 1.312559 0.5029213 0 P 0
L 0.5908825 0.177913 0.5908825 0.502913 1 P 0
L 1.312559 0.313945 1.312559 0.5029213 0 P 0
L 1.312559 0.313945 1.6275197 0.313945 0 P 0
L 1.6275197 0.313945 1.6275197 0.4310709 0 P 0
P 0.5948031 0.906063 28 P 0 0 ;0=26,1=0
P 0.5948031 1.431063 28 P 0 0 ;0=26,1=0
P 0.5948031 1.956063 28 P 0 0 ;0=26,1=0
P 0.5948031 2.481063 28 P 0 0 ;0=26,1=0
P 0.6389685 4.0388976 52 P 0 0 ;0=50,1=0
P 0.6389685 4.0932283 52 P 0 0 ;0=50,1=0
P 0.6448425 4.1975197 46 P 0 0 ;0=44,1=0
P 0.6448425 4.2546063 46 P 0 0 ;0=44,1=0
P 0.6548425 0.8479921 27 P 0 0 ;0=25,1=0
P 0.6548425 0.9641339 27 P 0 0 ;0=25,1=0
P 0.6548425 1.3729921 27 P 0 0 ;0=25,1=0
P 0.6548425 1.4891339 27 P 0 0 ;0=25,1=0
P 0.6548425 1.8979921 27 P 0 0 ;0=25,1=0
P 0.6548425 2.0141339 27 P 0 0 ;0=25,1=0
P 0.6548425 2.4229921 27 P 0 0 ;0=25,1=0
P 0.6548425 2.5391339 27 P 0 0 ;0=25,1=0
P 0.8406351 4.0388976 52 P 0 0 ;0=50,1=0
P 0.8406351 4.0932283 52 P 0 0 ;0=50,1=0
P 0.8465091 4.1975197 46 P 0 0 ;0=44,1=0
P 0.8465091 4.2546063 46 P 0 0 ;0=44,1=0
P 0.9005905 1.7470472 12 P 0 0 ;0=10,1=0
P 0.9015747 0.7185038 12 P 0 0 ;0=10,1=0
P 0.9045275 1.2244094 12 P 0 0 ;0=10,1=0
P 0.9084645 2.2844487 12 P 0 0 ;0=10,1=0
P 0.9326378 0.906063 45 P 0 0 ;0=43,1=0
P 0.9326378 1.431063 45 P 0 0 ;0=43,1=0
P 0.9326378 1.956063 45 P 0 0 ;0=43,1=0
P 0.9326378 2.481063 45 P 0 0 ;0=43,1=0
P 0.9596456 1.7470472 12 P 0 0 ;0=10,1=0
P 0.9606298 0.7185038 12 P 0 0 ;0=10,1=0
P 0.9635826 1.2244094 12 P 0 0 ;0=10,1=0
P 0.9675196 2.2844487 12 P 0 0 ;0=10,1=0
P 1.0423017 4.0388976 52 P 0 0 ;0=50,1=0
P 1.0423017 4.0932283 52 P 0 0 ;0=50,1=0
P 1.0481757 4.1975197 46 P 0 0 ;0=44,1=0
P 1.0481757 4.2546063 46 P 0 0 ;0=44,1=0
P 1.1570472 0.906063 45 P 0 0 ;0=43,1=0
P 1.1570472 1.431063 45 P 0 0 ;0=43,1=0
P 1.1570472 1.956063 45 P 0 0 ;0=43,1=0
P 1.1570472 2.481063 45 P 0 0 ;0=43,1=0
P 1.2439683 4.0388976 52 P 0 0 ;0=50,1=0
P 1.2439683 4.0932283 52 P 0 0 ;0=50,1=0
P 1.2498423 4.1975197 46 P 0 0 ;0=44,1=0
P 1.2498423 4.2546063 46 P 0 0 ;0=44,1=0
P 1.3464567 3.9783465 14 P 0 0 ;0=12,1=0
P 1.3464567 4.0374016 14 P 0 0 ;0=12,1=0
P 1.3464567 4.0826772 14 P 0 0 ;0=12,1=0
P 1.3464567 4.1417323 14 P 0 0 ;0=12,1=0
P 1.6171125 1.319673 2 P 0 0 ;0=0,1=0
P 1.6171125 1.339363 2 P 0 0 ;0=0,1=0
P 1.6171125 1.359043 2 P 0 0 ;0=0,1=0
P 1.6171125 1.378733 2 P 0 0 ;0=0,1=0
P 1.6171125 1.398413 2 P 0 0 ;0=0,1=0
P 1.6171125 1.418103 2 P 0 0 ;0=0,1=0
P 1.6171125 1.437783 2 P 0 0 ;0=0,1=0
P 1.6171125 1.457473 2 P 0 0 ;0=0,1=0
P 1.6171125 1.477153 2 P 0 0 ;0=0,1=0
P 1.6171125 1.496843 2 P 0 0 ;0=0,1=0
P 1.6171125 1.516523 2 P 0 0 ;0=0,1=0
P 1.6171125 1.536213 2 P 0 0 ;0=0,1=0
P 1.6171125 1.555893 2 P 0 0 ;0=0,1=0
P 1.6171125 1.575583 2 P 0 0 ;0=0,1=0
P 1.6171125 1.595263 2 P 0 0 ;0=0,1=0
P 1.6171125 1.614953 2 P 0 0 ;0=0,1=0
P 1.6171125 1.634633 2 P 0 0 ;0=0,1=0
P 1.6171125 1.654323 2 P 0 0 ;0=0,1=0
P 1.6171125 1.674003 2 P 0 0 ;0=0,1=0
P 1.6171125 1.693693 2 P 0 0 ;0=0,1=0
P 1.6171125 1.713373 2 P 0 0 ;0=0,1=0
P 1.6171125 1.733063 2 P 0 0 ;0=0,1=0
P 1.6171125 1.752743 2 P 0 0 ;0=0,1=0
P 1.6171125 1.772433 2 P 0 0 ;0=0,1=0
P 1.6171125 1.792113 2 P 0 0 ;0=0,1=0
P 1.6171125 1.811803 2 P 0 0 ;0=0,1=0
P 1.6171125 1.831483 2 P 0 0 ;0=0,1=0
P 1.6171125 1.851173 2 P 0 0 ;0=0,1=0
P 1.6171125 1.870853 2 P 0 0 ;0=0,1=0
P 1.6171125 1.890543 2 P 0 0 ;0=0,1=0
P 1.6171125 1.910223 2 P 0 0 ;0=0,1=0
P 1.6171125 1.929913 2 P 0 0 ;0=0,1=0
P 1.6171125 1.949593 2 P 0 0 ;0=0,1=0
P 1.6171125 1.969283 2 P 0 0 ;0=0,1=0
P 1.6171125 1.988963 2 P 0 0 ;0=0,1=0
P 1.6171125 2.008653 2 P 0 0 ;0=0,1=0
P 1.6171125 2.028333 2 P 0 0 ;0=0,1=0
P 1.6171125 2.048023 2 P 0 0 ;0=0,1=0
P 1.6171125 2.067703 2 P 0 0 ;0=0,1=0
P 1.6171125 2.087393 2 P 0 0 ;0=0,1=0
P 1.631559 4.024563 30 P 0 0 ;0=28,1=0
P 1.631559 4.049563 30 P 0 0 ;0=28,1=0
P 1.631559 4.074563 30 P 0 0 ;0=28,1=0
P 1.631559 4.099563 30 P 0 0 ;0=28,1=0
P 1.631559 4.124563 30 P 0 0 ;0=28,1=0
P 1.631559 4.149563 30 P 0 0 ;0=28,1=0
P 1.631559 4.174563 30 P 0 0 ;0=28,1=0
P 1.631559 4.199563 30 P 0 0 ;0=28,1=0
P 1.6643465 4.273063 19 P 0 0 ;0=17,1=0
P 1.6968325 1.275383 3 P 0 0 ;0=1,1=0
P 1.6968325 2.131683 3 P 0 0 ;0=1,1=0
P 1.7273386 4.273063 19 P 0 0 ;0=17,1=0
P 1.7765525 1.319673 2 P 0 0 ;0=0,1=0
P 1.7765525 1.339363 2 P 0 0 ;0=0,1=0
P 1.7765525 1.359043 2 P 0 0 ;0=0,1=0
P 1.7765525 1.378733 2 P 0 0 ;0=0,1=0
P 1.7765525 1.398413 2 P 0 0 ;0=0,1=0
P 1.7765525 1.418103 2 P 0 0 ;0=0,1=0
P 1.7765525 1.437783 2 P 0 0 ;0=0,1=0
P 1.7765525 1.457473 2 P 0 0 ;0=0,1=0
P 1.7765525 1.477153 2 P 0 0 ;0=0,1=0
P 1.7765525 1.496843 2 P 0 0 ;0=0,1=0
P 1.7765525 1.516523 2 P 0 0 ;0=0,1=0
P 1.7765525 1.536213 2 P 0 0 ;0=0,1=0
P 1.7765525 1.555893 2 P 0 0 ;0=0,1=0
P 1.7765525 1.575583 2 P 0 0 ;0=0,1=0
P 1.7765525 1.595263 2 P 0 0 ;0=0,1=0
P 1.7765525 1.614953 2 P 0 0 ;0=0,1=0
P 1.7765525 1.634633 2 P 0 0 ;0=0,1=0
P 1.7765525 1.654323 2 P 0 0 ;0=0,1=0
P 1.7765525 1.674003 2 P 0 0 ;0=0,1=0
P 1.7765525 1.693693 2 P 0 0 ;0=0,1=0
P 1.7765525 1.713373 2 P 0 0 ;0=0,1=0
P 1.7765525 1.733063 2 P 0 0 ;0=0,1=0
P 1.7765525 1.752743 2 P 0 0 ;0=0,1=0
P 1.7765525 1.772433 2 P 0 0 ;0=0,1=0
P 1.7765525 1.792113 2 P 0 0 ;0=0,1=0
P 1.7765525 1.811803 2 P 0 0 ;0=0,1=0
P 1.7765525 1.831483 2 P 0 0 ;0=0,1=0
P 1.7765525 1.851173 2 P 0 0 ;0=0,1=0
P 1.7765525 1.870853 2 P 0 0 ;0=0,1=0
P 1.7765525 1.890543 2 P 0 0 ;0=0,1=0
P 1.7765525 1.910223 2 P 0 0 ;0=0,1=0
P 1.7765525 1.929913 2 P 0 0 ;0=0,1=0
P 1.7765525 1.949593 2 P 0 0 ;0=0,1=0
P 1.7765525 1.969283 2 P 0 0 ;0=0,1=0
P 1.7765525 1.988963 2 P 0 0 ;0=0,1=0
P 1.7765525 2.008653 2 P 0 0 ;0=0,1=0
P 1.7765525 2.028333 2 P 0 0 ;0=0,1=0
P 1.7765525 2.048023 2 P 0 0 ;0=0,1=0
P 1.7765525 2.067703 2 P 0 0 ;0=0,1=0
P 1.7765525 2.087393 2 P 0 0 ;0=0,1=0
P 1.7972451 0.1377953 6 P 0 0 ;0=4,1=0
P 1.8024094 4.276063 50 P 0 0 ;0=48,1=0
P 1.8366151 0.1377953 6 P 0 0 ;0=4,1=0
P 1.8461259 4.024563 30 P 0 0 ;0=28,1=0
P 1.8461259 4.049563 30 P 0 0 ;0=28,1=0
P 1.8461259 4.074563 30 P 0 0 ;0=28,1=0
P 1.8461259 4.099563 30 P 0 0 ;0=28,1=0
P 1.8461259 4.124563 30 P 0 0 ;0=28,1=0
P 1.8461259 4.149563 30 P 0 0 ;0=28,1=0
P 1.8461259 4.174563 30 P 0 0 ;0=28,1=0
P 1.8461259 4.199563 30 P 0 0 ;0=28,1=0
P 1.8732756 4.276063 50 P 0 0 ;0=48,1=0
P 1.8759851 0.1377953 6 P 0 0 ;0=4,1=0
P 1.9153551 0.1377953 6 P 0 0 ;0=4,1=0
P 1.9338425 4.0748977 52 P 0 0 ;0=50,1=0
P 1.9338425 4.1292284 52 P 0 0 ;0=50,1=0
P 1.9547251 0.1377953 6 P 0 0 ;0=4,1=0
P 1.9940951 0.1377953 6 P 0 0 ;0=4,1=0
P 2.0334651 0.1377953 6 P 0 0 ;0=4,1=0
P 2.0728351 0.1377953 6 P 0 0 ;0=4,1=0
P 2.1122051 0.1377953 6 P 0 0 ;0=4,1=0
P 2.1398425 3.6641339 49 P 0 0 ;0=47,1=0
P 2.1398425 3.6979922 49 P 0 0 ;0=47,1=0
P 2.1468425 2.6248976 52 P 0 0 ;0=50,1=0
P 2.1468425 2.6792283 52 P 0 0 ;0=50,1=0
P 2.1515748 4.0157481 14 P 0 0 ;0=12,1=0
P 2.1515748 4.0748032 14 P 0 0 ;0=12,1=0
P 2.1515751 0.1377953 6 P 0 0 ;0=4,1=0
P 2.1686825 2.438533 5 P 0 0 ;0=3,1=0
P 2.1686925 0.958593 5 P 0 0 ;0=3,1=0
P 2.1909451 0.1377953 6 P 0 0 ;0=4,1=0
P 2.1996929 4.275063 20 P 0 0 ;0=18,1=0
P 2.2098425 3.6456299 47 P 0 0 ;0=45,1=0
P 2.2098425 3.7164961 47 P 0 0 ;0=45,1=0
P 2.2125984 4.0157481 14 P 0 0 ;0=12,1=0
P 2.2125984 4.0748032 14 P 0 0 ;0=12,1=0
P 2.2129725 2.358813 4 P 0 0 ;0=2,1=0
P 2.2129725 2.518253 4 P 0 0 ;0=2,1=0
P 2.2129825 0.878873 4 P 0 0 ;0=2,1=0
P 2.2129825 1.038313 4 P 0 0 ;0=2,1=0
P 2.2326625 2.358813 4 P 0 0 ;0=2,1=0
P 2.2326625 2.518253 4 P 0 0 ;0=2,1=0
P 2.2326725 0.878873 4 P 0 0 ;0=2,1=0
P 2.2326725 1.038313 4 P 0 0 ;0=2,1=0
P 2.2341417 4.1736851 22 P 0 0 ;0=20,1=0
P 2.2523425 2.358813 4 P 0 0 ;0=2,1=0
P 2.2523425 2.518253 4 P 0 0 ;0=2,1=0
P 2.2523525 0.878873 4 P 0 0 ;0=2,1=0
P 2.2523525 1.038313 4 P 0 0 ;0=2,1=0
P 2.2715433 4.275063 24 P 0 0 ;0=22,1=0
P 2.2720325 2.358813 4 P 0 0 ;0=2,1=0
P 2.2720325 2.518253 4 P 0 0 ;0=2,1=0
P 2.2720425 0.878873 4 P 0 0 ;0=2,1=0
P 2.2720425 1.038313 4 P 0 0 ;0=2,1=0
P 2.2813858 4.1703386 21 P 0 0 ;0=19,1=0
P 2.2917125 2.358813 4 P 0 0 ;0=2,1=0
P 2.2917125 2.518253 4 P 0 0 ;0=2,1=0
P 2.2917225 0.878873 4 P 0 0 ;0=2,1=0
P 2.2917225 1.038313 4 P 0 0 ;0=2,1=0
P 2.3069763 4.1703386 21 P 0 0 ;0=19,1=0
P 2.3090551 0.1377953 6 P 0 0 ;0=4,1=0
P 2.3114025 2.358813 4 P 0 0 ;0=2,1=0
P 2.3114025 2.518253 4 P 0 0 ;0=2,1=0
P 2.3114125 0.878873 4 P 0 0 ;0=2,1=0
P 2.3114125 1.038313 4 P 0 0 ;0=2,1=0
P 2.3310825 2.358813 4 P 0 0 ;0=2,1=0
P 2.3310825 2.518253 4 P 0 0 ;0=2,1=0
P 2.3310925 0.878873 4 P 0 0 ;0=2,1=0
P 2.3310925 1.038313 4 P 0 0 ;0=2,1=0
P 2.3325669 4.1703386 21 P 0 0 ;0=19,1=0
P 2.3348425 3.4045276 13 P 0 0 ;0=11,1=0
P 2.3348425 3.4832677 13 P 0 0 ;0=11,1=0
P 2.3348425 3.5620079 13 P 0 0 ;0=11,1=0
P 2.3348425 3.640748 13 P 0 0 ;0=11,1=0
P 2.3484251 0.1377953 6 P 0 0 ;0=4,1=0
P 2.3507725 2.358813 4 P 0 0 ;0=2,1=0
P 2.3507725 2.518253 4 P 0 0 ;0=2,1=0
P 2.3507825 0.878873 4 P 0 0 ;0=2,1=0
P 2.3507825 1.038313 4 P 0 0 ;0=2,1=0
P 2.3581575 4.1703386 21 P 0 0 ;0=19,1=0
P 2.3704525 2.358813 4 P 0 0 ;0=2,1=0
P 2.3704525 2.518253 4 P 0 0 ;0=2,1=0
P 2.3704625 0.878873 4 P 0 0 ;0=2,1=0
P 2.3704625 1.038313 4 P 0 0 ;0=2,1=0
P 2.3778425 4.275063 23 P 0 0 ;0=21,1=0
P 2.383748 4.1703386 21 P 0 0 ;0=19,1=0
P 2.3877951 0.1377953 6 P 0 0 ;0=4,1=0
P 2.3877954 2.8996063 14 P 0 0 ;0=12,1=0
P 2.3877954 2.9586614 14 P 0 0 ;0=12,1=0
P 2.3901425 2.358813 4 P 0 0 ;0=2,1=0
P 2.3901425 2.518253 4 P 0 0 ;0=2,1=0
P 2.3901525 0.878873 4 P 0 0 ;0=2,1=0
P 2.3901525 1.038313 4 P 0 0 ;0=2,1=0
P 2.4098225 2.358813 4 P 0 0 ;0=2,1=0
P 2.4098225 2.518253 4 P 0 0 ;0=2,1=0
P 2.4098325 0.878873 4 P 0 0 ;0=2,1=0
P 2.4098325 1.038313 4 P 0 0 ;0=2,1=0
P 2.4271651 0.1377953 6 P 0 0 ;0=4,1=0
P 2.4295125 2.358813 4 P 0 0 ;0=2,1=0
P 2.4295125 2.518253 4 P 0 0 ;0=2,1=0
P 2.4295225 0.878873 4 P 0 0 ;0=2,1=0
P 2.4295225 1.038313 4 P 0 0 ;0=2,1=0
P 2.4309921 4.1736851 22 P 0 0 ;0=20,1=0
P 2.4491925 2.358813 4 P 0 0 ;0=2,1=0
P 2.4491925 2.518253 4 P 0 0 ;0=2,1=0
P 2.4492025 0.878873 4 P 0 0 ;0=2,1=0
P 2.4492025 1.038313 4 P 0 0 ;0=2,1=0
P 2.4654409 4.275063 20 P 0 0 ;0=18,1=0
P 2.4665351 0.1377953 6 P 0 0 ;0=4,1=0
P 2.4688825 2.358813 4 P 0 0 ;0=2,1=0
P 2.4688825 2.518253 4 P 0 0 ;0=2,1=0
P 2.4688925 0.878873 4 P 0 0 ;0=2,1=0
P 2.4688925 1.038313 4 P 0 0 ;0=2,1=0
P 2.4885625 2.358813 4 P 0 0 ;0=2,1=0
P 2.4885625 2.518253 4 P 0 0 ;0=2,1=0
P 2.4885725 0.878873 4 P 0 0 ;0=2,1=0
P 2.4885725 1.038313 4 P 0 0 ;0=2,1=0
P 2.503937 0.5738189 53 P 0 0 ;0=51,1=0
P 2.503937 0.6072835 53 P 0 0 ;0=51,1=0
P 2.5059051 0.1377953 6 P 0 0 ;0=4,1=0
P 2.5082525 2.358813 4 P 0 0 ;0=2,1=0
P 2.5082525 2.518253 4 P 0 0 ;0=2,1=0
P 2.5082625 0.878873 4 P 0 0 ;0=2,1=0
P 2.5082625 1.038313 4 P 0 0 ;0=2,1=0
P 2.5098425 3.4045276 13 P 0 0 ;0=11,1=0
P 2.5098425 3.4832677 13 P 0 0 ;0=11,1=0
P 2.5098425 3.5620079 13 P 0 0 ;0=11,1=0
P 2.5098425 3.640748 13 P 0 0 ;0=11,1=0
P 2.5279325 2.358813 4 P 0 0 ;0=2,1=0
P 2.5279325 2.518253 4 P 0 0 ;0=2,1=0
P 2.5279425 0.878873 4 P 0 0 ;0=2,1=0
P 2.5279425 1.038313 4 P 0 0 ;0=2,1=0
P 2.5452751 0.1377953 6 P 0 0 ;0=4,1=0
P 2.5476225 2.358813 4 P 0 0 ;0=2,1=0
P 2.5476225 2.518253 4 P 0 0 ;0=2,1=0
P 2.5476325 0.878873 4 P 0 0 ;0=2,1=0
P 2.5476325 1.038313 4 P 0 0 ;0=2,1=0
P 2.5673025 2.358813 4 P 0 0 ;0=2,1=0
P 2.5673025 2.518253 4 P 0 0 ;0=2,1=0
P 2.5673125 0.878873 4 P 0 0 ;0=2,1=0
P 2.5673125 1.038313 4 P 0 0 ;0=2,1=0
P 2.5846451 0.1377953 6 P 0 0 ;0=4,1=0
P 2.5869925 2.358813 4 P 0 0 ;0=2,1=0
P 2.5869925 2.518253 4 P 0 0 ;0=2,1=0
P 2.5870025 0.878873 4 P 0 0 ;0=2,1=0
P 2.5870025 1.038313 4 P 0 0 ;0=2,1=0
P 2.6066725 2.358813 4 P 0 0 ;0=2,1=0
P 2.6066725 2.518253 4 P 0 0 ;0=2,1=0
P 2.6066825 0.878873 4 P 0 0 ;0=2,1=0
P 2.6066825 1.038313 4 P 0 0 ;0=2,1=0
P 2.6240151 0.1377953 6 P 0 0 ;0=4,1=0
P 2.6263625 2.358813 4 P 0 0 ;0=2,1=0
P 2.6263625 2.518253 4 P 0 0 ;0=2,1=0
P 2.6263725 0.878873 4 P 0 0 ;0=2,1=0
P 2.6263725 1.038313 4 P 0 0 ;0=2,1=0
P 2.6398425 3.5356299 47 P 0 0 ;0=45,1=0
P 2.6398425 3.6064961 47 P 0 0 ;0=45,1=0
P 2.6460425 2.358813 4 P 0 0 ;0=2,1=0
P 2.6460425 2.518253 4 P 0 0 ;0=2,1=0
P 2.6460525 0.878873 4 P 0 0 ;0=2,1=0
P 2.6460525 1.038313 4 P 0 0 ;0=2,1=0
P 2.6633851 0.1377953 6 P 0 0 ;0=4,1=0
P 2.6657325 2.358813 4 P 0 0 ;0=2,1=0
P 2.6657325 2.518253 4 P 0 0 ;0=2,1=0
P 2.6657425 0.878873 4 P 0 0 ;0=2,1=0
P 2.6657425 1.038313 4 P 0 0 ;0=2,1=0
P 2.6854125 2.358813 4 P 0 0 ;0=2,1=0
P 2.6854125 2.518253 4 P 0 0 ;0=2,1=0
P 2.6854225 0.878873 4 P 0 0 ;0=2,1=0
P 2.6854225 1.038313 4 P 0 0 ;0=2,1=0
P 2.694252 3.7503543 29 P 0 0 ;0=27,1=0
P 2.7027551 0.1377953 6 P 0 0 ;0=4,1=0
P 2.7051025 2.358813 4 P 0 0 ;0=2,1=0
P 2.7051025 2.518253 4 P 0 0 ;0=2,1=0
P 2.7051125 0.878873 4 P 0 0 ;0=2,1=0
P 2.7051125 1.038313 4 P 0 0 ;0=2,1=0
P 2.7198425 3.6617716 29 P 0 0 ;0=27,1=0
P 2.7247825 2.358813 4 P 0 0 ;0=2,1=0
P 2.7247825 2.518253 4 P 0 0 ;0=2,1=0
P 2.7247925 0.878873 4 P 0 0 ;0=2,1=0
P 2.7247925 1.038313 4 P 0 0 ;0=2,1=0
P 2.7248425 3.5591338 49 P 0 0 ;0=47,1=0
P 2.7248425 3.5929921 49 P 0 0 ;0=47,1=0
P 2.7421251 0.1377953 6 P 0 0 ;0=4,1=0
P 2.7444725 2.358813 4 P 0 0 ;0=2,1=0
P 2.7444725 2.518253 4 P 0 0 ;0=2,1=0
P 2.7444825 0.878873 4 P 0 0 ;0=2,1=0
P 2.7444825 1.038313 4 P 0 0 ;0=2,1=0
P 2.7454331 3.7503543 29 P 0 0 ;0=27,1=0
P 2.7568898 2.9372047 17 P 0 0 ;0=15,1=0
P 2.7568898 2.9872047 17 P 0 0 ;0=15,1=0
P 2.7568898 3.0372047 17 P 0 0 ;0=15,1=0
P 2.7568898 3.0872047 17 P 0 0 ;0=15,1=0
P 2.7568898 3.1372047 17 P 0 0 ;0=15,1=0
P 2.7568898 3.1872047 17 P 0 0 ;0=15,1=0
P 2.7568898 3.2372047 17 P 0 0 ;0=15,1=0
P 2.7568898 3.2872047 17 P 0 0 ;0=15,1=0
P 2.7641525 2.358813 4 P 0 0 ;0=2,1=0
P 2.7641525 2.518253 4 P 0 0 ;0=2,1=0
P 2.7641625 0.878873 4 P 0 0 ;0=2,1=0
P 2.7641625 1.038313 4 P 0 0 ;0=2,1=0
P 2.7814951 0.1377953 6 P 0 0 ;0=4,1=0
P 2.7838425 2.358813 4 P 0 0 ;0=2,1=0
P 2.7838425 2.518253 4 P 0 0 ;0=2,1=0
P 2.7838525 0.878873 4 P 0 0 ;0=2,1=0
P 2.7838525 1.038313 4 P 0 0 ;0=2,1=0
P 2.8035225 2.358813 4 P 0 0 ;0=2,1=0
P 2.8035225 2.518253 4 P 0 0 ;0=2,1=0
P 2.8035325 0.878873 4 P 0 0 ;0=2,1=0
P 2.8035325 1.038313 4 P 0 0 ;0=2,1=0
P 2.809252 3.7503543 29 P 0 0 ;0=27,1=0
P 2.8208651 0.1377953 6 P 0 0 ;0=4,1=0
P 2.8232125 2.358813 4 P 0 0 ;0=2,1=0
P 2.8232125 2.518253 4 P 0 0 ;0=2,1=0
P 2.8232225 0.878873 4 P 0 0 ;0=2,1=0
P 2.8232225 1.038313 4 P 0 0 ;0=2,1=0
P 2.8348425 3.6617716 29 P 0 0 ;0=27,1=0
P 2.8428925 2.358813 4 P 0 0 ;0=2,1=0
P 2.8428925 2.518253 4 P 0 0 ;0=2,1=0
P 2.8429025 0.878873 4 P 0 0 ;0=2,1=0
P 2.8429025 1.038313 4 P 0 0 ;0=2,1=0
P 2.8602351 0.1377953 6 P 0 0 ;0=4,1=0
P 2.8604331 3.7503543 29 P 0 0 ;0=27,1=0
P 2.8625825 2.358813 4 P 0 0 ;0=2,1=0
P 2.8625825 2.518253 4 P 0 0 ;0=2,1=0
P 2.8625925 0.878873 4 P 0 0 ;0=2,1=0
P 2.8625925 1.038313 4 P 0 0 ;0=2,1=0
P 2.8822625 2.358813 4 P 0 0 ;0=2,1=0
P 2.8822625 2.518253 4 P 0 0 ;0=2,1=0
P 2.8822725 0.878873 4 P 0 0 ;0=2,1=0
P 2.8822725 1.038313 4 P 0 0 ;0=2,1=0
P 2.8996051 0.1377953 6 P 0 0 ;0=4,1=0
P 2.9019525 2.358813 4 P 0 0 ;0=2,1=0
P 2.9019525 2.518253 4 P 0 0 ;0=2,1=0
P 2.9019625 0.878873 4 P 0 0 ;0=2,1=0
P 2.9019625 1.038313 4 P 0 0 ;0=2,1=0
P 2.9216325 2.358813 4 P 0 0 ;0=2,1=0
P 2.9216325 2.518253 4 P 0 0 ;0=2,1=0
P 2.9216425 0.878873 4 P 0 0 ;0=2,1=0
P 2.9216425 1.038313 4 P 0 0 ;0=2,1=0
P 2.9389751 0.1377953 6 P 0 0 ;0=4,1=0
P 2.9413225 2.358813 4 P 0 0 ;0=2,1=0
P 2.9413225 2.518253 4 P 0 0 ;0=2,1=0
P 2.9413325 0.878873 4 P 0 0 ;0=2,1=0
P 2.9413325 1.038313 4 P 0 0 ;0=2,1=0
P 2.9448425 3.6666929 39 P 0 0 ;0=37,1=0
P 2.9448425 3.7454331 39 P 0 0 ;0=37,1=0
P 2.9448425 3.951063 38 P 0 0 ;0=36,1=0
P 2.9448425 4.2211417 38 P 0 0 ;0=36,1=0
P 2.9610025 2.358813 4 P 0 0 ;0=2,1=0
P 2.9610025 2.518253 4 P 0 0 ;0=2,1=0
P 2.9610125 0.878873 4 P 0 0 ;0=2,1=0
P 2.9610125 1.038313 4 P 0 0 ;0=2,1=0
P 2.9783451 0.1377953 6 P 0 0 ;0=4,1=0
P 2.9806925 2.358813 4 P 0 0 ;0=2,1=0
P 2.9806925 2.518253 4 P 0 0 ;0=2,1=0
P 2.9807025 0.878873 4 P 0 0 ;0=2,1=0
P 2.9807025 1.038313 4 P 0 0 ;0=2,1=0
P 3.0177151 0.1377953 6 P 0 0 ;0=4,1=0
P 3.0249825 2.438533 5 P 0 0 ;0=3,1=0
P 3.0249925 0.958593 5 P 0 0 ;0=3,1=0
P 3.0448425 3.6666929 39 P 0 0 ;0=37,1=0
P 3.0448425 3.7454331 39 P 0 0 ;0=37,1=0
P 3.0448425 3.951063 38 P 0 0 ;0=36,1=0
P 3.0448425 4.2211417 38 P 0 0 ;0=36,1=0
P 3.0551181 0.5738189 53 P 0 0 ;0=51,1=0
P 3.0551181 0.6072835 53 P 0 0 ;0=51,1=0
P 3.0570851 0.1572953 7 P 0 0 ;0=5,1=0
P 3.0964551 0.1377953 6 P 0 0 ;0=4,1=0
P 3.1112205 2.9372047 17 P 0 0 ;0=15,1=0
P 3.1112205 2.9872047 17 P 0 0 ;0=15,1=0
P 3.1112205 3.0372047 17 P 0 0 ;0=15,1=0
P 3.1112205 3.0872047 17 P 0 0 ;0=15,1=0
P 3.1112205 3.1372047 17 P 0 0 ;0=15,1=0
P 3.1112205 3.1872047 17 P 0 0 ;0=15,1=0
P 3.1112205 3.2372047 17 P 0 0 ;0=15,1=0
P 3.1112205 3.2872047 17 P 0 0 ;0=15,1=0
P 3.1448425 3.6666929 39 P 0 0 ;0=37,1=0
P 3.1448425 3.7454331 39 P 0 0 ;0=37,1=0
P 3.1448425 3.951063 38 P 0 0 ;0=36,1=0
P 3.1448425 4.2211417 38 P 0 0 ;0=36,1=0
P 3.2091732 2.7952756 9 P 0 0 ;0=7,1=0
P 3.2091732 2.8149606 9 P 0 0 ;0=7,1=0
P 3.2091732 2.8346456 9 P 0 0 ;0=7,1=0
P 3.219252 3.7503543 29 P 0 0 ;0=27,1=0
P 3.2293307 2.7849212 8 P 0 0 ;0=6,1=0
P 3.2293307 2.845 8 P 0 0 ;0=6,1=0
P 3.2448425 3.6617716 29 P 0 0 ;0=27,1=0
P 3.2448425 3.951063 38 P 0 0 ;0=36,1=0
P 3.2448425 4.2211417 38 P 0 0 ;0=36,1=0
P 3.2490157 2.7849212 8 P 0 0 ;0=6,1=0
P 3.2490157 2.845 8 P 0 0 ;0=6,1=0
P 3.2691732 2.7952756 9 P 0 0 ;0=7,1=0
P 3.2691732 2.8149606 9 P 0 0 ;0=7,1=0
P 3.2691732 2.8346456 9 P 0 0 ;0=7,1=0
P 3.2704331 3.7503543 29 P 0 0 ;0=27,1=0
P 3.3331103 3.2062205 34 P 0 0 ;0=32,1=0
P 3.3331103 3.3951969 34 P 0 0 ;0=32,1=0
P 3.3448425 3.951063 38 P 0 0 ;0=36,1=0
P 3.3448425 4.2211417 38 P 0 0 ;0=36,1=0
P 3.3498425 3.6666929 39 P 0 0 ;0=37,1=0
P 3.3498425 3.7454331 39 P 0 0 ;0=37,1=0
P 3.3921654 3.2062205 34 P 0 0 ;0=32,1=0
P 3.3921654 3.3951969 34 P 0 0 ;0=32,1=0
P 3.4385827 2.8923386 37 P 0 0 ;0=35,1=0
P 3.4385827 3.0517874 37 P 0 0 ;0=35,1=0
P 3.444252 3.7503543 29 P 0 0 ;0=27,1=0
P 3.4444882 2.948441 35 P 0 0 ;0=33,1=0
P 3.4444882 2.995685 35 P 0 0 ;0=33,1=0
P 3.4512205 3.2062205 34 P 0 0 ;0=32,1=0
P 3.4512205 3.3951969 34 P 0 0 ;0=32,1=0
P 3.4698425 3.6617716 29 P 0 0 ;0=27,1=0
P 3.4776771 2.797063 10 P 0 0 ;0=8,1=0
P 3.4848425 2.8923386 36 P 0 0 ;0=34,1=0
P 3.4848425 3.0517874 36 P 0 0 ;0=34,1=0
P 3.4920225 1.319633 2 P 0 0 ;0=0,1=0
P 3.4920225 1.339323 2 P 0 0 ;0=0,1=0
P 3.4920225 1.359003 2 P 0 0 ;0=0,1=0
P 3.4920225 1.378693 2 P 0 0 ;0=0,1=0
P 3.4920225 1.398373 2 P 0 0 ;0=0,1=0
P 3.4920225 1.418063 2 P 0 0 ;0=0,1=0
P 3.4920225 1.437743 2 P 0 0 ;0=0,1=0
P 3.4920225 1.457433 2 P 0 0 ;0=0,1=0
P 3.4920225 1.477113 2 P 0 0 ;0=0,1=0
P 3.4920225 1.496803 2 P 0 0 ;0=0,1=0
P 3.4920225 1.516483 2 P 0 0 ;0=0,1=0
P 3.4920225 1.536173 2 P 0 0 ;0=0,1=0
P 3.4920225 1.555853 2 P 0 0 ;0=0,1=0
P 3.4920225 1.575543 2 P 0 0 ;0=0,1=0
P 3.4920225 1.595223 2 P 0 0 ;0=0,1=0
P 3.4920225 1.614913 2 P 0 0 ;0=0,1=0
P 3.4920225 1.634593 2 P 0 0 ;0=0,1=0
P 3.4920225 1.654283 2 P 0 0 ;0=0,1=0
P 3.4920225 1.673963 2 P 0 0 ;0=0,1=0
P 3.4920225 1.693653 2 P 0 0 ;0=0,1=0
P 3.4920225 1.713333 2 P 0 0 ;0=0,1=0
P 3.4920225 1.733023 2 P 0 0 ;0=0,1=0
P 3.4920225 1.752703 2 P 0 0 ;0=0,1=0
P 3.4920225 1.772393 2 P 0 0 ;0=0,1=0
P 3.4920225 1.792073 2 P 0 0 ;0=0,1=0
P 3.4920225 1.811763 2 P 0 0 ;0=0,1=0
P 3.4920225 1.831443 2 P 0 0 ;0=0,1=0
P 3.4920225 1.851133 2 P 0 0 ;0=0,1=0
P 3.4920225 1.870813 2 P 0 0 ;0=0,1=0
P 3.4920225 1.890503 2 P 0 0 ;0=0,1=0
P 3.4920225 1.910183 2 P 0 0 ;0=0,1=0
P 3.4920225 1.929873 2 P 0 0 ;0=0,1=0
P 3.4920225 1.949553 2 P 0 0 ;0=0,1=0
P 3.4920225 1.969243 2 P 0 0 ;0=0,1=0
P 3.4920225 1.988923 2 P 0 0 ;0=0,1=0
P 3.4920225 2.008613 2 P 0 0 ;0=0,1=0
P 3.4920225 2.028293 2 P 0 0 ;0=0,1=0
P 3.4920225 2.047983 2 P 0 0 ;0=0,1=0
P 3.4920225 2.067663 2 P 0 0 ;0=0,1=0
P 3.4920225 2.087353 2 P 0 0 ;0=0,1=0
P 3.4954331 3.7503543 29 P 0 0 ;0=27,1=0
P 3.5102756 3.2062205 34 P 0 0 ;0=32,1=0
P 3.5102756 3.3951969 34 P 0 0 ;0=32,1=0
P 3.5251968 2.948441 35 P 0 0 ;0=33,1=0
P 3.5251968 2.995685 35 P 0 0 ;0=33,1=0
P 3.5311023 2.8923386 37 P 0 0 ;0=35,1=0
P 3.5311023 3.0517874 37 P 0 0 ;0=35,1=0
P 3.5320078 2.797063 10 P 0 0 ;0=8,1=0
P 3.5693307 3.2062205 34 P 0 0 ;0=32,1=0
P 3.5693307 3.3853543 33 P 0 0 ;0=31,1=0
P 3.5717425 1.275343 3 P 0 0 ;0=1,1=0
P 3.5717425 2.131643 3 P 0 0 ;0=1,1=0
P 3.5898425 3.7275197 46 P 0 0 ;0=44,1=0
P 3.5898425 3.7846063 46 P 0 0 ;0=44,1=0
P 3.5898425 3.8525197 46 P 0 0 ;0=44,1=0
P 3.5898425 3.9096063 46 P 0 0 ;0=44,1=0
P 3.6514625 1.319633 2 P 0 0 ;0=0,1=0
P 3.6514625 1.339323 2 P 0 0 ;0=0,1=0
P 3.6514625 1.359003 2 P 0 0 ;0=0,1=0
P 3.6514625 1.378693 2 P 0 0 ;0=0,1=0
P 3.6514625 1.398373 2 P 0 0 ;0=0,1=0
P 3.6514625 1.418063 2 P 0 0 ;0=0,1=0
P 3.6514625 1.437743 2 P 0 0 ;0=0,1=0
P 3.6514625 1.457433 2 P 0 0 ;0=0,1=0
P 3.6514625 1.477113 2 P 0 0 ;0=0,1=0
P 3.6514625 1.496803 2 P 0 0 ;0=0,1=0
P 3.6514625 1.516483 2 P 0 0 ;0=0,1=0
P 3.6514625 1.536173 2 P 0 0 ;0=0,1=0
P 3.6514625 1.555853 2 P 0 0 ;0=0,1=0
P 3.6514625 1.575543 2 P 0 0 ;0=0,1=0
P 3.6514625 1.595223 2 P 0 0 ;0=0,1=0
P 3.6514625 1.614913 2 P 0 0 ;0=0,1=0
P 3.6514625 1.634593 2 P 0 0 ;0=0,1=0
P 3.6514625 1.654283 2 P 0 0 ;0=0,1=0
P 3.6514625 1.673963 2 P 0 0 ;0=0,1=0
P 3.6514625 1.693653 2 P 0 0 ;0=0,1=0
P 3.6514625 1.713333 2 P 0 0 ;0=0,1=0
P 3.6514625 1.733023 2 P 0 0 ;0=0,1=0
P 3.6514625 1.752703 2 P 0 0 ;0=0,1=0
P 3.6514625 1.772393 2 P 0 0 ;0=0,1=0
P 3.6514625 1.792073 2 P 0 0 ;0=0,1=0
P 3.6514625 1.811763 2 P 0 0 ;0=0,1=0
P 3.6514625 1.831443 2 P 0 0 ;0=0,1=0
P 3.6514625 1.851133 2 P 0 0 ;0=0,1=0
P 3.6514625 1.870813 2 P 0 0 ;0=0,1=0
P 3.6514625 1.890503 2 P 0 0 ;0=0,1=0
P 3.6514625 1.910183 2 P 0 0 ;0=0,1=0
P 3.6514625 1.929873 2 P 0 0 ;0=0,1=0
P 3.6514625 1.949553 2 P 0 0 ;0=0,1=0
P 3.6514625 1.969243 2 P 0 0 ;0=0,1=0
P 3.6514625 1.988923 2 P 0 0 ;0=0,1=0
P 3.6514625 2.008613 2 P 0 0 ;0=0,1=0
P 3.6514625 2.028293 2 P 0 0 ;0=0,1=0
P 3.6514625 2.047983 2 P 0 0 ;0=0,1=0
P 3.6514625 2.067663 2 P 0 0 ;0=0,1=0
P 3.6514625 2.087353 2 P 0 0 ;0=0,1=0
P 3.6594094 0.726063 50 P 0 0 ;0=48,1=0
P 3.6681102 3.786063 54 P 0 0 ;0=52,1=0
P 3.6681102 3.861063 54 P 0 0 ;0=52,1=0
P 3.6829133 0.636063 51 P 0 0 ;0=49,1=0
P 3.6888425 3.266567 48 P 0 0 ;0=46,1=0
P 3.6888425 3.3295591 48 P 0 0 ;0=46,1=0
P 3.6938425 3.1176299 47 P 0 0 ;0=45,1=0
P 3.6938425 3.1884961 47 P 0 0 ;0=45,1=0
P 3.6962598 4.0276378 26 P 0 0 ;0=24,1=0
P 3.6962598 4.2441732 26 P 0 0 ;0=24,1=0
P 3.7015748 3.786063 54 P 0 0 ;0=52,1=0
P 3.7015748 3.861063 54 P 0 0 ;0=52,1=0
P 3.7167716 0.636063 51 P 0 0 ;0=49,1=0
P 3.7302756 0.726063 50 P 0 0 ;0=48,1=0
P 3.7698425 3.2011339 49 P 0 0 ;0=47,1=0
P 3.7698425 3.2349922 49 P 0 0 ;0=47,1=0
P 3.772559 3.683563 30 P 0 0 ;0=28,1=0
P 3.772559 3.708563 30 P 0 0 ;0=28,1=0
P 3.772559 3.733563 30 P 0 0 ;0=28,1=0
P 3.772559 3.758563 30 P 0 0 ;0=28,1=0
P 3.772559 3.783563 30 P 0 0 ;0=28,1=0
P 3.772559 3.808563 30 P 0 0 ;0=28,1=0
P 3.772559 3.833563 30 P 0 0 ;0=28,1=0
P 3.772559 3.858563 30 P 0 0 ;0=28,1=0
P 3.8084646 4.0237008 25 P 0 0 ;0=23,1=0
P 3.8399606 4.0237008 25 P 0 0 ;0=23,1=0
P 3.8714567 4.0237008 25 P 0 0 ;0=23,1=0
P 3.9029528 4.0237008 25 P 0 0 ;0=23,1=0
P 3.9114214 1.5996232 15 P 0 0 ;0=13,1=0
P 3.9114214 1.6196232 15 P 0 0 ;0=13,1=0
P 3.9114214 1.6396232 15 P 0 0 ;0=13,1=0
P 3.9114214 1.6596232 15 P 0 0 ;0=13,1=0
P 3.9114214 1.6796232 15 P 0 0 ;0=13,1=0
P 3.9114214 1.6996232 15 P 0 0 ;0=13,1=0
P 3.9114214 1.7196232 15 P 0 0 ;0=13,1=0
P 3.9114214 1.7396232 15 P 0 0 ;0=13,1=0
P 3.9114214 1.7596232 15 P 0 0 ;0=13,1=0
P 3.9114214 1.7796232 15 P 0 0 ;0=13,1=0
P 3.9344488 4.0237008 25 P 0 0 ;0=23,1=0
P 3.9598425 2.7806299 47 P 0 0 ;0=45,1=0
P 3.9598425 2.8514961 47 P 0 0 ;0=45,1=0
P 3.9871259 3.683563 30 P 0 0 ;0=28,1=0
P 3.9871259 3.708563 30 P 0 0 ;0=28,1=0
P 3.9871259 3.733563 30 P 0 0 ;0=28,1=0
P 3.9871259 3.758563 30 P 0 0 ;0=28,1=0
P 3.9871259 3.783563 30 P 0 0 ;0=28,1=0
P 3.9871259 3.808563 30 P 0 0 ;0=28,1=0
P 3.9871259 3.833563 30 P 0 0 ;0=28,1=0
P 3.9871259 3.858563 30 P 0 0 ;0=28,1=0
P 4.0398425 3.029567 48 P 0 0 ;0=46,1=0
P 4.0398425 3.0925591 48 P 0 0 ;0=46,1=0
P 4.0466536 4.0276378 26 P 0 0 ;0=24,1=0
P 4.0466536 4.2441732 26 P 0 0 ;0=24,1=0
P 4.0648425 2.7806299 47 P 0 0 ;0=45,1=0
P 4.0648425 2.8514961 47 P 0 0 ;0=45,1=0
P 4.0689017 1.5996232 15 P 0 0 ;0=13,1=0
P 4.0689017 1.6196232 15 P 0 0 ;0=13,1=0
P 4.0689017 1.6396232 15 P 0 0 ;0=13,1=0
P 4.0689017 1.6596232 15 P 0 0 ;0=13,1=0
P 4.0689017 1.6796232 15 P 0 0 ;0=13,1=0
P 4.0689017 1.6996232 15 P 0 0 ;0=13,1=0
P 4.0689017 1.7196232 15 P 0 0 ;0=13,1=0
P 4.0689017 1.7396232 15 P 0 0 ;0=13,1=0
P 4.0689017 1.7596232 15 P 0 0 ;0=13,1=0
P 4.0689017 1.7796232 15 P 0 0 ;0=13,1=0
P 4.1048425 3.7706299 47 P 0 0 ;0=45,1=0
P 4.1048425 3.8414961 47 P 0 0 ;0=45,1=0
P 4.1098425 3.0441338 49 P 0 0 ;0=47,1=0
P 4.1098425 3.0779921 49 P 0 0 ;0=47,1=0
P 4.1126772 3.701063 10 P 0 0 ;0=8,1=0
P 4.1498425 2.7898819 43 P 0 0 ;0=41,1=0
P 4.1498425 2.8422441 43 P 0 0 ;0=41,1=0
P 4.1505905 3.6033465 10 P 0 0 ;0=8,1=0
P 4.1648425 3.0441338 49 P 0 0 ;0=47,1=0
P 4.1648425 3.0779921 49 P 0 0 ;0=47,1=0
P 4.1670079 3.701063 10 P 0 0 ;0=8,1=0
P 4.1948425 3.774567 48 P 0 0 ;0=46,1=0
P 4.1948425 3.8375591 48 P 0 0 ;0=46,1=0
P 4.2049212 3.6033465 10 P 0 0 ;0=8,1=0
P 4.2094094 3.246063 50 P 0 0 ;0=48,1=0
P 4.2198425 3.0441338 49 P 0 0 ;0=47,1=0
P 4.2198425 3.0779921 49 P 0 0 ;0=47,1=0
P 4.2348425 2.7806299 47 P 0 0 ;0=45,1=0
P 4.2348425 2.8514961 47 P 0 0 ;0=45,1=0
P 4.2748425 3.0441338 49 P 0 0 ;0=47,1=0
P 4.2748425 3.0779921 49 P 0 0 ;0=47,1=0
P 4.2755905 3.6033465 11 P 0 0 ;0=9,1=0
P 4.2802756 3.246063 50 P 0 0 ;0=48,1=0
P 4.3326771 3.6033465 11 P 0 0 ;0=9,1=0
P 4.3348425 3.0441338 49 P 0 0 ;0=47,1=0
P 4.3348425 3.0779921 49 P 0 0 ;0=47,1=0
P 4.3398425 2.7806299 47 P 0 0 ;0=45,1=0
P 4.3398425 2.8514961 47 P 0 0 ;0=45,1=0
P 4.3948425 3.0441338 49 P 0 0 ;0=47,1=0
P 4.3948425 3.0779921 49 P 0 0 ;0=47,1=0
P 4.4329134 4.206063 40 P 0 0 ;0=38,1=0
P 4.4348425 2.7898819 43 P 0 0 ;0=41,1=0
P 4.4348425 2.8422441 43 P 0 0 ;0=41,1=0
P 4.4548425 3.0441338 49 P 0 0 ;0=47,1=0
P 4.4548425 3.0779921 49 P 0 0 ;0=47,1=0
P 4.5667716 4.206063 40 P 0 0 ;0=38,1=0
P 4.6526771 4.206063 10 P 0 0 ;0=8,1=0
P 4.6526772 4.121063 10 P 0 0 ;0=8,1=0
P 4.7070078 4.206063 10 P 0 0 ;0=8,1=0
P 4.7070079 4.121063 10 P 0 0 ;0=8,1=0
P 4.9094488 2.8080708 16 P 0 0 ;0=14,1=0
P 4.9094488 3.9616142 16 P 0 0 ;0=14,1=0
P 4.9579134 4.206063 40 P 0 0 ;0=38,1=0
P 5.0917716 4.206063 40 P 0 0 ;0=38,1=0
P 5.2126771 4.206063 10 P 0 0 ;0=8,1=0
P 5.2126772 4.126063 10 P 0 0 ;0=8,1=0
P 5.2670078 4.206063 10 P 0 0 ;0=8,1=0
P 5.2670079 4.126063 10 P 0 0 ;0=8,1=0
P 5.6344488 3.359252 51 P 0 0 ;0=49,1=0
P 5.6683071 3.359252 51 P 0 0 ;0=49,1=0
P 5.7411417 3.3612205 50 P 0 0 ;0=48,1=0
P 5.8120079 3.3612205 50 P 0 0 ;0=48,1=0
P 5.8879921 3.701063 18 P 0 0 ;0=16,1=0
P 6.0048425 2.3388977 52 P 0 0 ;0=50,1=0
P 6.0048425 2.3932284 52 P 0 0 ;0=50,1=0
P 6.0316929 3.701063 18 P 0 0 ;0=16,1=0
P 6.0356772 3.556063 10 P 0 0 ;0=8,1=0
P 6.0648425 2.3441339 49 P 0 0 ;0=47,1=0
P 6.0648425 2.3779922 49 P 0 0 ;0=47,1=0
P 6.0900079 3.556063 10 P 0 0 ;0=8,1=0
P 6.0933464 2.171063 19 P 0 0 ;0=17,1=0
P 6.1228425 2.4338976 52 P 0 0 ;0=50,1=0
P 6.1228425 2.4882283 52 P 0 0 ;0=50,1=0
P 6.1563385 2.171063 19 P 0 0 ;0=17,1=0
P 6.1574016 2.241063 31 P 0 0 ;0=29,1=0
P 6.1574016 2.291063 31 P 0 0 ;0=29,1=0
P 6.1574016 2.341063 31 P 0 0 ;0=29,1=0
P 6.1574016 2.391063 31 P 0 0 ;0=29,1=0
P 6.1979921 3.701063 18 P 0 0 ;0=16,1=0
P 6.2029921 3.566063 18 P 0 0 ;0=16,1=0
P 6.2348425 2.1288977 52 P 0 0 ;0=50,1=0
P 6.2348425 2.1832284 52 P 0 0 ;0=50,1=0
P 6.253937 2.7559055 47 P 0 0 ;0=45,1=0
P 6.253937 2.8267717 47 P 0 0 ;0=45,1=0
P 6.3126772 2.451063 10 P 0 0 ;0=8,1=0
P 6.3198425 1.4601181 44 P 0 0 ;0=42,1=0
P 6.3198425 1.8420079 44 P 0 0 ;0=42,1=0
P 6.3279134 2.501063 51 P 0 0 ;0=49,1=0
P 6.3279134 2.556063 51 P 0 0 ;0=49,1=0
P 6.3279134 2.611063 51 P 0 0 ;0=49,1=0
P 6.3279134 2.656063 51 P 0 0 ;0=49,1=0
P 6.3348425 2.1106299 47 P 0 0 ;0=45,1=0
P 6.3348425 2.1814961 47 P 0 0 ;0=45,1=0
P 6.3416929 3.701063 18 P 0 0 ;0=16,1=0
P 6.3466929 3.566063 18 P 0 0 ;0=16,1=0
P 6.3522834 2.241063 31 P 0 0 ;0=29,1=0
P 6.3522834 2.291063 31 P 0 0 ;0=29,1=0
P 6.3522834 2.341063 31 P 0 0 ;0=29,1=0
P 6.3522834 2.391063 31 P 0 0 ;0=29,1=0
P 6.3617717 2.501063 51 P 0 0 ;0=49,1=0
P 6.3617717 2.556063 51 P 0 0 ;0=49,1=0
P 6.3617717 2.611063 51 P 0 0 ;0=49,1=0
P 6.3617717 2.656063 51 P 0 0 ;0=49,1=0
P 6.3670079 2.451063 10 P 0 0 ;0=8,1=0
P 6.3720472 2.7559055 47 P 0 0 ;0=45,1=0
P 6.3720472 2.8267717 47 P 0 0 ;0=45,1=0
P 6.3883268 3.1524803 42 P 0 0 ;0=40,1=0
P 6.3883268 3.1721654 42 P 0 0 ;0=40,1=0
P 6.3883268 3.1918504 42 P 0 0 ;0=40,1=0
P 6.3883268 3.2115354 42 P 0 0 ;0=40,1=0
P 6.3883268 3.2312205 42 P 0 0 ;0=40,1=0
P 6.3883268 3.2509055 42 P 0 0 ;0=40,1=0
P 6.3883268 3.2705906 42 P 0 0 ;0=40,1=0
P 6.3883268 3.2902756 42 P 0 0 ;0=40,1=0
P 6.3883268 3.3099606 42 P 0 0 ;0=40,1=0
P 6.3883268 3.3296457 42 P 0 0 ;0=40,1=0
P 6.4203149 3.1500197 41 P 0 0 ;0=39,1=0
P 6.4203149 3.3321063 41 P 0 0 ;0=39,1=0
P 6.4394094 3.071063 50 P 0 0 ;0=48,1=0
P 6.44 3.1500197 41 P 0 0 ;0=39,1=0
P 6.44 3.3321063 41 P 0 0 ;0=39,1=0
P 6.459685 3.3321063 41 P 0 0 ;0=39,1=0
P 6.4598425 3.1500197 41 P 0 0 ;0=39,1=0
P 6.4698425 2.2395669 48 P 0 0 ;0=46,1=0
P 6.4698425 2.302559 48 P 0 0 ;0=46,1=0
P 6.4793701 3.1500197 41 P 0 0 ;0=39,1=0
P 6.4793701 3.3321063 41 P 0 0 ;0=39,1=0
P 6.5102756 3.071063 50 P 0 0 ;0=48,1=0
P 6.5113582 3.1524803 42 P 0 0 ;0=40,1=0
P 6.5113582 3.1721654 42 P 0 0 ;0=40,1=0
P 6.5113582 3.1918504 42 P 0 0 ;0=40,1=0
P 6.5113582 3.2115354 42 P 0 0 ;0=40,1=0
P 6.5113582 3.2312205 42 P 0 0 ;0=40,1=0
P 6.5113582 3.2509055 42 P 0 0 ;0=40,1=0
P 6.5113582 3.2705906 42 P 0 0 ;0=40,1=0
P 6.5113582 3.2902756 42 P 0 0 ;0=40,1=0
P 6.5113582 3.3099606 42 P 0 0 ;0=40,1=0
P 6.5113582 3.3296457 42 P 0 0 ;0=40,1=0
P 6.5198425 1.954567 48 P 0 0 ;0=46,1=0
P 6.5198425 2.0175591 48 P 0 0 ;0=46,1=0
P 6.5848425 3.0391338 49 P 0 0 ;0=47,1=0
P 6.5848425 3.0729921 49 P 0 0 ;0=47,1=0
P 6.6048425 3.1295669 48 P 0 0 ;0=46,1=0
P 6.6048425 3.192559 48 P 0 0 ;0=46,1=0
P 6.6048425 3.264567 48 P 0 0 ;0=46,1=0
P 6.6048425 3.3275591 48 P 0 0 ;0=46,1=0
P 6.6294094 1.421063 50 P 0 0 ;0=48,1=0
P 6.6294094 1.531063 50 P 0 0 ;0=48,1=0
P 6.6374016 1.881063 31 P 0 0 ;0=29,1=0
P 6.6374016 1.931063 31 P 0 0 ;0=29,1=0
P 6.6374016 1.981063 31 P 0 0 ;0=29,1=0
P 6.6374016 2.031063 31 P 0 0 ;0=29,1=0
P 6.6429133 1.611063 51 P 0 0 ;0=49,1=0
P 6.6429133 1.671063 51 P 0 0 ;0=49,1=0
P 6.6429133 1.721063 51 P 0 0 ;0=49,1=0
P 6.6429133 1.776063 51 P 0 0 ;0=49,1=0
P 6.6598425 2.0956299 47 P 0 0 ;0=45,1=0
P 6.6598425 2.1664961 47 P 0 0 ;0=45,1=0
P 6.6767716 1.611063 51 P 0 0 ;0=49,1=0
P 6.6767716 1.671063 51 P 0 0 ;0=49,1=0
P 6.6767716 1.721063 51 P 0 0 ;0=49,1=0
P 6.6767716 1.776063 51 P 0 0 ;0=49,1=0
P 6.6798425 2.4201181 44 P 0 0 ;0=42,1=0
P 6.6798425 2.8020079 44 P 0 0 ;0=42,1=0
P 6.7002756 1.421063 50 P 0 0 ;0=48,1=0
P 6.7002756 1.531063 50 P 0 0 ;0=48,1=0
P 6.7265748 3.1680709 32 P 0 0 ;0=30,1=0
P 6.7265748 3.2940551 32 P 0 0 ;0=30,1=0
P 6.7276771 1.816063 10 P 0 0 ;0=8,1=0
P 6.7498425 2.0888976 52 P 0 0 ;0=50,1=0
P 6.7498425 2.1432283 52 P 0 0 ;0=50,1=0
P 6.7820078 1.816063 10 P 0 0 ;0=8,1=0
P 6.8322834 1.881063 31 P 0 0 ;0=29,1=0
P 6.8322834 1.931063 31 P 0 0 ;0=29,1=0
P 6.8322834 1.981063 31 P 0 0 ;0=29,1=0
P 6.8322834 2.031063 31 P 0 0 ;0=29,1=0
P 6.8426771 1.816063 10 P 0 0 ;0=8,1=0
P 6.8433465 2.096063 19 P 0 0 ;0=17,1=0
P 6.8970078 1.816063 10 P 0 0 ;0=8,1=0
P 6.9063386 2.096063 19 P 0 0 ;0=17,1=0
P 6.9398425 1.8891338 49 P 0 0 ;0=47,1=0
P 6.9398425 1.9229921 49 P 0 0 ;0=47,1=0
P 6.9431102 3.1680709 32 P 0 0 ;0=30,1=0
P 6.9431102 3.2940551 32 P 0 0 ;0=30,1=0
P 7.0098425 1.8838977 52 P 0 0 ;0=50,1=0
P 7.0098425 1.9382284 52 P 0 0 ;0=50,1=0

### steps/pcb/layers/top_solder/features
#Layer_Color=8388736
#
#Feature symbol names
#
$0 r3.937
$1 r1
$2 rect314.9607x135.8267
$3 rect1354.3307x230.315
$4 rect69.02x17.84
$5 rect74.93x61.15
$6 rect17.84x69.02
$7 rect61.15x74.93
$8 rect36x173
$9 rect36x134
$10 rect17.8425x18.8268
$11 rect18.8268x17.8425
$12 rect36.3465x47.3701
$13 rect47.3701x41.4646
$14 rect35.5591x43.4331
$15 rect90.874x52.0945
$16 rect43.4331x35.5591
$17 rect78.8661x17.8425
$18 rect165.3543x125.9843
$19 oval86.7402x31.622
$20 rect33.5906x49.3386
$21 rect47.3701x45.4016
$22 rect72.9606x59.1811
$23 rect25.7165x62.3307
$24 rect63.9055x69.0236
$25 rect78.8661x82.8031
$26 rect47.3701x82.8031
$27 rect27.685x98.5512
$28 rect86.7402x106.4252
$29 rect94.6142x49.3386
$30 rect49.3386x47.3701
$31 rect27.685x43.4331
$32 oval65.0866x25.7165
$33 rect85.5591x30.4409
$34 rect59.1811x82.8031
$35 rect47.3701x98.5512
$36 rect47.3701x78.8661
$37 rect61.1496x35.5591
$38 rect35.5591x53.2756
$39 rect49.3386x53.2756
$40 rect58x208
$41 rect65.0866x45.4016
$42 rect39.4961x74.9291
$43 rect17.8425x30.6378
$44 rect34.5748x17.8425
$45 rect46.5827x42.252
$46 rect220.5984x122.1732
$47 rect104.4567x132.0157
$48 rect41.4646x47.3701
$49 rect65.0866x53.2756
$50 rect45.4016x47.3701
$51 rect33.1969x34.7717
$52 rect53.2756x65.0866
$53 rect34.7717x33.1969
$54 rect47.3701x36.3465
$55 rect31.622x33.5906
$56 rect33.5906x31.622
$57 r8
$58 s8
$59 r29.66
$60 r250
$61 r63
$62 s63
$63 r83
$64 r69.0236
$65 s69.0236
$66 r39.4961
$67 r73.9843
$68 r106.4252
$69 oval204.8504x106.4252
$70 oval185.1654x96.5827
$71 oval96.5827x185.1654
$72 r128
$73 r120
$74 r58
$75 r24
$76 r208

#
#Feature attribute names
#
@0 .geometry
@1 .pad_usage

#
#Feature attribute text strings
#
&0 SMD_RectX61.0200Y9.8400
&1 SMD_RectX66.9300Y53.1500
&2 SMD_RectX9.8400Y61.0200
&3 SMD_RectX53.1500Y66.9300
&4 SMD_RectX28.0000Y165.0000
&5 SMD_RectX28.0000Y126.0000
&6 SMD_RectX9.8425Y10.8268
&7 SMD_RectX10.8268Y9.8425
&8 SMD_RectX28.3465Y39.3701
&9 SMD_RectX39.3701Y33.4646
&10 SMD_RectX27.5591Y35.4331
&11 SMD_RectX82.8740Y44.0945
&12 SMD_RectX35.4331Y27.5591
&13 SMD_RectX70.8661Y9.8425
&14 SMD_RectX165.3543Y125.9843
&15 SMD_OvalX78.7402Y23.6220
&16 SMD_RectX25.5906Y41.3386
&17 SMD_RectX39.3701Y37.4016
&18 SMD_RectX64.9606Y51.1811
&19 SMD_RectX17.7165Y54.3307
&20 SMD_RectX55.9055Y61.0236
&21 SMD_RectX70.8661Y74.8031
&22 SMD_RectX39.3701Y74.8031
&23 SMD_RectX19.6850Y90.5512
&24 SMD_RectX78.7402Y98.4252
&25 SMD_RectX86.6142Y41.3386
&26 SMD_RectX41.3386Y39.3701
&27 SMD_RectX19.6850Y35.4331
&28 SMD_OvalX57.0866Y17.7165
&29 SMD_RectX77.5591Y22.4409
&30 SMD_RectX51.1811Y74.8031
&31 SMD_RectX39.3701Y90.5512
&32 SMD_RectX39.3701Y70.8661
&33 SMD_RectX53.1496Y27.5591
&34 SMD_RectX27.5591Y45.2756
&35 SMD_RectX41.3386Y45.2756
&36 SMD_RectX50.0000Y200.0000
&37 SMD_RectX57.0866Y37.4016
&38 SMD_RectX31.4961Y66.9291
&39 SMD_RectX9.8425Y22.6378
&40 SMD_RectX26.5748Y9.8425
&41 SMD_RectX38.5827Y34.2520
&42 SMD_RectX212.5984Y114.1732
&43 SMD_RectX96.4567Y124.0157
&44 SMD_RectX33.4646Y39.3701
&45 SMD_RectX57.0866Y45.2756
&46 SMD_RectX37.4016Y39.3701
&47 SMD_RectX25.1969Y26.7717
&48 SMD_RectX45.2756Y57.0866
&49 SMD_RectX26.7717Y25.1969
&50 SMD_RectX39.3701Y28.3465
&51 SMD_RectX23.6220Y25.5906
&52 SMD_RectX25.5906Y23.6220
&53 Pad_Simple_X0.0000Y0.0000H29.9213C69.9213
&54 Pad_Simple_X0.0000Y0.0000H118.1100C158.1100
&55 Pad_Simple_X21.6600Y21.6600H21.6600C61.6600
&56 Pad_Simple_X250.0000Y250.0000H125.1969C165.1969
&57 Pad_Simple_X55.0000Y55.0000H30.0000C70.0000
&58 Pad_Simple_X75.0000Y75.0000H50.0000C90.0000
&59 Pad_Simple_X61.0236Y61.0236H41.3386C81.3386
&60 Pad_Simple_X31.4961Y31.4961H35.4331C75.4331
&61 Pad_Simple_X65.9843Y65.9843H65.9843C105.9843
&62 Pad_Simple_X98.4252Y98.4252H64.9606C104.9606
&63 Pad_Simple_X196.8504Y98.4252H39.3701C79.3701
&64 Pad_Simple_X177.1654Y88.5827H39.3701C79.3701
&65 Pad_Simple_X88.5827Y177.1654H39.3701C79.3701
&66 Pad_Simple_X120.0000Y120.0000H68.0000C108.0000
&67 Pad_Simple_X112.0000Y112.0000H60.0000C100.0000
&68 Pad_Complex_X50.0000Y50.0000H118.1102C158.1102
&69 Pad_Simple_X98.4252Y98.4252H70.8661C110.8661
&70 Pad_Simple_X50.0000Y50.0000H118.1102C158.1102
&71 VIA_RoundD16.0000H8.0000C48.0000
&72 VIA_RoundD200.0000H125.9843C165.9843

#
#Layer features
#
A 1.7712204 0.4310709 1.6275196 0.4310709 1.69937 0.4310709 0 P 0 N
L -0.0001175 0.177913 0.5908825 0.177913 1 P 0
L -0.0004331 0.1781182 0.5901181 0.1781182 0 P 0
L 0.5901181 0.1781182 0.5901181 0.5029213 0 P 0
L 0.5901181 0.5029213 1.312559 0.5029213 0 P 0
L 0.5908825 0.177913 0.5908825 0.502913 1 P 0
L 1.312559 0.313945 1.312559 0.5029213 0 P 0
L 1.312559 0.313945 1.6275197 0.313945 0 P 0
L 1.6275197 0.313945 1.6275197 0.4310709 0 P 0
P 0.0998425 0.806063 72 P 0 0 ;0=66,1=0
P 0.0998425 1.006063 72 P 0 0 ;0=66,1=0
P 0.0998425 1.331063 72 P 0 0 ;0=66,1=0
P 0.0998425 1.531063 72 P 0 0 ;0=66,1=0
P 0.0998425 1.856063 72 P 0 0 ;0=66,1=0
P 0.0998425 2.056063 72 P 0 0 ;0=66,1=0
P 0.0998425 2.381063 72 P 0 0 ;0=66,1=0
P 0.0998425 2.581063 72 P 0 0 ;0=66,1=0
P 0.1998425 0.906063 73 P 0 0 ;0=67,1=0
P 0.1998425 1.431063 73 P 0 0 ;0=67,1=0
P 0.1998425 1.956063 73 P 0 0 ;0=67,1=0
P 0.1998425 2.481063 73 P 0 0 ;0=67,1=0
P 0.285433 4.152063 60 P 0 0 ;0=56,1=0
P 0.2854331 0.3681102 60 P 0 0 ;0=56,1=0
P 0.2998425 0.806063 72 P 0 0 ;0=66,1=0
P 0.2998425 1.006063 72 P 0 0 ;0=66,1=0
P 0.2998425 1.331063 72 P 0 0 ;0=66,1=0
P 0.2998425 1.531063 72 P 0 0 ;0=66,1=0
P 0.2998425 1.856063 72 P 0 0 ;0=66,1=0
P 0.2998425 2.056063 72 P 0 0 ;0=66,1=0
P 0.2998425 2.381063 72 P 0 0 ;0=66,1=0
P 0.2998425 2.581063 72 P 0 0 ;0=66,1=0
P 0.5948031 0.906063 30 P 0 0 ;0=26,1=0
P 0.5948031 1.431063 30 P 0 0 ;0=26,1=0
P 0.5948031 1.956063 30 P 0 0 ;0=26,1=0
P 0.5948031 2.481063 30 P 0 0 ;0=26,1=0
P 0.6389685 4.0388976 54 P 0 0 ;0=50,1=0
P 0.6389685 4.0932283 54 P 0 0 ;0=50,1=0
P 0.6448425 4.1975197 48 P 0 0 ;0=44,1=0
P 0.6448425 4.2546063 48 P 0 0 ;0=44,1=0
P 0.6548425 0.8479921 29 P 0 0 ;0=25,1=0
P 0.6548425 0.9641339 29 P 0 0 ;0=25,1=0
P 0.6548425 1.3729921 29 P 0 0 ;0=25,1=0
P 0.6548425 1.4891339 29 P 0 0 ;0=25,1=0
P 0.6548425 1.8979921 29 P 0 0 ;0=25,1=0
P 0.6548425 2.0141339 29 P 0 0 ;0=25,1=0
P 0.6548425 2.4229921 29 P 0 0 ;0=25,1=0
P 0.6548425 2.5391339 29 P 0 0 ;0=25,1=0
P 0.8406351 4.0388976 54 P 0 0 ;0=50,1=0
P 0.8406351 4.0932283 54 P 0 0 ;0=50,1=0
P 0.8465091 4.1975197 48 P 0 0 ;0=44,1=0
P 0.8465091 4.2546063 48 P 0 0 ;0=44,1=0
P 0.9005905 1.7470472 14 P 0 0 ;0=10,1=0
P 0.9015747 0.7185038 14 P 0 0 ;0=10,1=0
P 0.9045275 1.2244094 14 P 0 0 ;0=10,1=0
P 0.9084645 2.2844487 14 P 0 0 ;0=10,1=0
P 0.9326378 0.906063 47 P 0 0 ;0=43,1=0
P 0.9326378 1.431063 47 P 0 0 ;0=43,1=0
P 0.9326378 1.956063 47 P 0 0 ;0=43,1=0
P 0.9326378 2.481063 47 P 0 0 ;0=43,1=0
P 0.9596456 1.7470472 14 P 0 0 ;0=10,1=0
P 0.9606298 0.7185038 14 P 0 0 ;0=10,1=0
P 0.9635826 1.2244094 14 P 0 0 ;0=10,1=0
P 0.9675196 2.2844487 14 P 0 0 ;0=10,1=0
P 1.0423017 4.0388976 54 P 0 0 ;0=50,1=0
P 1.0423017 4.0932283 54 P 0 0 ;0=50,1=0
P 1.0481757 4.1975197 48 P 0 0 ;0=44,1=0
P 1.0481757 4.2546063 48 P 0 0 ;0=44,1=0
P 1.1570472 0.906063 47 P 0 0 ;0=43,1=0
P 1.1570472 1.431063 47 P 0 0 ;0=43,1=0
P 1.1570472 1.956063 47 P 0 0 ;0=43,1=0
P 1.1570472 2.481063 47 P 0 0 ;0=43,1=0
P 1.2439683 4.0388976 54 P 0 0 ;0=50,1=0
P 1.2439683 4.0932283 54 P 0 0 ;0=50,1=0
P 1.2498423 4.1975197 48 P 0 0 ;0=44,1=0
P 1.2498423 4.2546063 48 P 0 0 ;0=44,1=0
P 1.3464567 3.9783465 16 P 0 0 ;0=12,1=0
P 1.3464567 4.0374016 16 P 0 0 ;0=12,1=0
P 1.3464567 4.0826772 16 P 0 0 ;0=12,1=0
P 1.3464567 4.1417323 16 P 0 0 ;0=12,1=0
P 1.4576771 4.053937 61 P 0 0 ;0=57,1=0
P 1.4576771 4.153937 61 P 0 0 ;0=57,1=0
P 1.4576771 4.253937 62 P 0 0 ;0=57,1=0
P 1.4704724 0.2450787 2 P 0 0
P 1.6171125 1.319673 4 P 0 0 ;0=0,1=0
P 1.6171125 1.339363 4 P 0 0 ;0=0,1=0
P 1.6171125 1.359043 4 P 0 0 ;0=0,1=0
P 1.6171125 1.378733 4 P 0 0 ;0=0,1=0
P 1.6171125 1.398413 4 P 0 0 ;0=0,1=0
P 1.6171125 1.418103 4 P 0 0 ;0=0,1=0
P 1.6171125 1.437783 4 P 0 0 ;0=0,1=0
P 1.6171125 1.457473 4 P 0 0 ;0=0,1=0
P 1.6171125 1.477153 4 P 0 0 ;0=0,1=0
P 1.6171125 1.496843 4 P 0 0 ;0=0,1=0
P 1.6171125 1.516523 4 P 0 0 ;0=0,1=0
P 1.6171125 1.536213 4 P 0 0 ;0=0,1=0
P 1.6171125 1.555893 4 P 0 0 ;0=0,1=0
P 1.6171125 1.575583 4 P 0 0 ;0=0,1=0
P 1.6171125 1.595263 4 P 0 0 ;0=0,1=0
P 1.6171125 1.614953 4 P 0 0 ;0=0,1=0
P 1.6171125 1.634633 4 P 0 0 ;0=0,1=0
P 1.6171125 1.654323 4 P 0 0 ;0=0,1=0
P 1.6171125 1.674003 4 P 0 0 ;0=0,1=0
P 1.6171125 1.693693 4 P 0 0 ;0=0,1=0
P 1.6171125 1.713373 4 P 0 0 ;0=0,1=0
P 1.6171125 1.733063 4 P 0 0 ;0=0,1=0
P 1.6171125 1.752743 4 P 0 0 ;0=0,1=0
P 1.6171125 1.772433 4 P 0 0 ;0=0,1=0
P 1.6171125 1.792113 4 P 0 0 ;0=0,1=0
P 1.6171125 1.811803 4 P 0 0 ;0=0,1=0
P 1.6171125 1.831483 4 P 0 0 ;0=0,1=0
P 1.6171125 1.851173 4 P 0 0 ;0=0,1=0
P 1.6171125 1.870853 4 P 0 0 ;0=0,1=0
P 1.6171125 1.890543 4 P 0 0 ;0=0,1=0
P 1.6171125 1.910223 4 P 0 0 ;0=0,1=0
P 1.6171125 1.929913 4 P 0 0 ;0=0,1=0
P 1.6171125 1.949593 4 P 0 0 ;0=0,1=0
P 1.6171125 1.969283 4 P 0 0 ;0=0,1=0
P 1.6171125 1.988963 4 P 0 0 ;0=0,1=0
P 1.6171125 2.008653 4 P 0 0 ;0=0,1=0
P 1.6171125 2.028333 4 P 0 0 ;0=0,1=0
P 1.6171125 2.048023 4 P 0 0 ;0=0,1=0
P 1.6171125 2.067703 4 P 0 0 ;0=0,1=0
P 1.6171125 2.087393 4 P 0 0 ;0=0,1=0
P 1.631559 4.024563 32 P 0 0 ;0=28,1=0
P 1.631559 4.049563 32 P 0 0 ;0=28,1=0
P 1.631559 4.074563 32 P 0 0 ;0=28,1=0
P 1.631559 4.099563 32 P 0 0 ;0=28,1=0
P 1.631559 4.124563 32 P 0 0 ;0=28,1=0
P 1.631559 4.149563 32 P 0 0 ;0=28,1=0
P 1.631559 4.174563 32 P 0 0 ;0=28,1=0
P 1.631559 4.199563 32 P 0 0 ;0=28,1=0
P 1.6519425 2.486293 58 P 0 0 ;0=54,1=0
P 1.6529425 0.916293 58 P 0 0 ;0=54,1=0
P 1.6643465 4.273063 21 P 0 0 ;0=17,1=0
P 1.6968325 1.275383 5 P 0 0 ;0=1,1=0
P 1.6968325 1.309833 59 P 0 0 ;0=55,1=0
P 1.6968325 2.097233 59 P 0 0 ;0=55,1=0
P 1.6968325 2.131683 5 P 0 0 ;0=1,1=0
P 1.7273386 4.273063 21 P 0 0 ;0=17,1=0
P 1.7765525 1.319673 4 P 0 0 ;0=0,1=0
P 1.7765525 1.339363 4 P 0 0 ;0=0,1=0
P 1.7765525 1.359043 4 P 0 0 ;0=0,1=0
P 1.7765525 1.378733 4 P 0 0 ;0=0,1=0
P 1.7765525 1.398413 4 P 0 0 ;0=0,1=0
P 1.7765525 1.418103 4 P 0 0 ;0=0,1=0
P 1.7765525 1.437783 4 P 0 0 ;0=0,1=0
P 1.7765525 1.457473 4 P 0 0 ;0=0,1=0
P 1.7765525 1.477153 4 P 0 0 ;0=0,1=0
P 1.7765525 1.496843 4 P 0 0 ;0=0,1=0
P 1.7765525 1.516523 4 P 0 0 ;0=0,1=0
P 1.7765525 1.536213 4 P 0 0 ;0=0,1=0
P 1.7765525 1.555893 4 P 0 0 ;0=0,1=0
P 1.7765525 1.575583 4 P 0 0 ;0=0,1=0
P 1.7765525 1.595263 4 P 0 0 ;0=0,1=0
P 1.7765525 1.614953 4 P 0 0 ;0=0,1=0
P 1.7765525 1.634633 4 P 0 0 ;0=0,1=0
P 1.7765525 1.654323 4 P 0 0 ;0=0,1=0
P 1.7765525 1.674003 4 P 0 0 ;0=0,1=0
P 1.7765525 1.693693 4 P 0 0 ;0=0,1=0
P 1.7765525 1.713373 4 P 0 0 ;0=0,1=0
P 1.7765525 1.733063 4 P 0 0 ;0=0,1=0
P 1.7765525 1.752743 4 P 0 0 ;0=0,1=0
P 1.7765525 1.772433 4 P 0 0 ;0=0,1=0
P 1.7765525 1.792113 4 P 0 0 ;0=0,1=0
P 1.7765525 1.811803 4 P 0 0 ;0=0,1=0
P 1.7765525 1.831483 4 P 0 0 ;0=0,1=0
P 1.7765525 1.851173 4 P 0 0 ;0=0,1=0
P 1.7765525 1.870853 4 P 0 0 ;0=0,1=0
P 1.7765525 1.890543 4 P 0 0 ;0=0,1=0
P 1.7765525 1.910223 4 P 0 0 ;0=0,1=0
P 1.7765525 1.929913 4 P 0 0 ;0=0,1=0
P 1.7765525 1.949593 4 P 0 0 ;0=0,1=0
P 1.7765525 1.969283 4 P 0 0 ;0=0,1=0
P 1.7765525 1.988963 4 P 0 0 ;0=0,1=0
P 1.7765525 2.008653 4 P 0 0 ;0=0,1=0
P 1.7765525 2.028333 4 P 0 0 ;0=0,1=0
P 1.7765525 2.048023 4 P 0 0 ;0=0,1=0
P 1.7765525 2.067703 4 P 0 0 ;0=0,1=0
P 1.7765525 2.087393 4 P 0 0 ;0=0,1=0
P 1.7972451 0.1377953 8 P 0 0 ;0=4,1=0
P 1.8024094 4.276063 52 P 0 0 ;0=48,1=0
P 1.8366151 0.1377953 8 P 0 0 ;0=4,1=0
P 1.8461259 4.024563 32 P 0 0 ;0=28,1=0
P 1.8461259 4.049563 32 P 0 0 ;0=28,1=0
P 1.8461259 4.074563 32 P 0 0 ;0=28,1=0
P 1.8461259 4.099563 32 P 0 0 ;0=28,1=0
P 1.8461259 4.124563 32 P 0 0 ;0=28,1=0
P 1.8461259 4.149563 32 P 0 0 ;0=28,1=0
P 1.8461259 4.174563 32 P 0 0 ;0=28,1=0
P 1.8461259 4.199563 32 P 0 0 ;0=28,1=0
P 1.8732756 4.276063 52 P 0 0 ;0=48,1=0
P 1.8759851 0.1377953 8 P 0 0 ;0=4,1=0
P 1.9153551 0.1377953 8 P 0 0 ;0=4,1=0
P 1.9338425 4.0748977 54 P 0 0 ;0=50,1=0
P 1.9338425 4.1292284 54 P 0 0 ;0=50,1=0
P 1.9547251 0.1377953 8 P 0 0 ;0=4,1=0
P 1.9940951 0.1377953 8 P 0 0 ;0=4,1=0
P 2.0334651 0.1377953 8 P 0 0 ;0=4,1=0
P 2.0433071 4.057874 61 P 0 0 ;0=57,1=0
P 2.0433071 4.157874 61 P 0 0 ;0=57,1=0
P 2.0433071 4.257874 62 P 0 0 ;0=57,1=0
P 2.0728351 0.1377953 8 P 0 0 ;0=4,1=0
P 2.1122051 0.1377953 8 P 0 0 ;0=4,1=0
P 2.1398425 3.6641339 51 P 0 0 ;0=47,1=0
P 2.1398425 3.6979922 51 P 0 0 ;0=47,1=0
P 2.1468425 2.6248976 54 P 0 0 ;0=50,1=0
P 2.1468425 2.6792283 54 P 0 0 ;0=50,1=0
P 2.1515748 4.0157481 16 P 0 0 ;0=12,1=0
P 2.1515748 4.0748032 16 P 0 0 ;0=12,1=0
P 2.1515751 0.1377953 8 P 0 0 ;0=4,1=0
P 2.1686825 2.438533 7 P 0 0 ;0=3,1=0
P 2.1686925 0.958593 7 P 0 0 ;0=3,1=0
P 2.1909451 0.1377953 8 P 0 0 ;0=4,1=0
P 2.1996929 4.275063 22 P 0 0 ;0=18,1=0
P 2.2031325 2.438533 59 P 0 0 ;0=55,1=0
P 2.2031425 0.958593 59 P 0 0 ;0=55,1=0
P 2.2098425 3.6456299 49 P 0 0 ;0=45,1=0
P 2.2098425 3.7164961 49 P 0 0 ;0=45,1=0
P 2.2125984 4.0157481 16 P 0 0 ;0=12,1=0
P 2.2125984 4.0748032 16 P 0 0 ;0=12,1=0
P 2.2129725 2.358813 6 P 0 0 ;0=2,1=0
P 2.2129725 2.518253 6 P 0 0 ;0=2,1=0
P 2.2129825 0.878873 6 P 0 0 ;0=2,1=0
P 2.2129825 1.038313 6 P 0 0 ;0=2,1=0
P 2.2326625 2.358813 6 P 0 0 ;0=2,1=0
P 2.2326625 2.518253 6 P 0 0 ;0=2,1=0
P 2.2326725 0.878873 6 P 0 0 ;0=2,1=0
P 2.2326725 1.038313 6 P 0 0 ;0=2,1=0
P 2.2341417 4.1736851 24 P 0 0 ;0=20,1=0
P 2.2523425 2.358813 6 P 0 0 ;0=2,1=0
P 2.2523425 2.518253 6 P 0 0 ;0=2,1=0
P 2.2523525 0.878873 6 P 0 0 ;0=2,1=0
P 2.2523525 1.038313 6 P 0 0 ;0=2,1=0
P 2.2715433 4.275063 26 P 0 0 ;0=22,1=0
P 2.2720325 2.358813 6 P 0 0 ;0=2,1=0
P 2.2720325 2.518253 6 P 0 0 ;0=2,1=0
P 2.2720425 0.878873 6 P 0 0 ;0=2,1=0
P 2.2720425 1.038313 6 P 0 0 ;0=2,1=0
P 2.2813858 4.1703386 23 P 0 0 ;0=19,1=0
P 2.2917125 2.358813 6 P 0 0 ;0=2,1=0
P 2.2917125 2.518253 6 P 0 0 ;0=2,1=0
P 2.2917225 0.878873 6 P 0 0 ;0=2,1=0
P 2.2917225 1.038313 6 P 0 0 ;0=2,1=0
P 2.3069763 4.1703386 23 P 0 0 ;0=19,1=0
P 2.3090551 0.1377953 8 P 0 0 ;0=4,1=0
P 2.3114025 2.358813 6 P 0 0 ;0=2,1=0
P 2.3114025 2.518253 6 P 0 0 ;0=2,1=0
P 2.3114125 0.878873 6 P 0 0 ;0=2,1=0
P 2.3114125 1.038313 6 P 0 0 ;0=2,1=0
P 2.3310825 2.358813 6 P 0 0 ;0=2,1=0
P 2.3310825 2.518253 6 P 0 0 ;0=2,1=0
P 2.3310925 0.878873 6 P 0 0 ;0=2,1=0
P 2.3310925 1.038313 6 P 0 0 ;0=2,1=0
P 2.3325669 4.1703386 23 P 0 0 ;0=19,1=0
P 2.3348425 3.4045276 15 P 0 0 ;0=11,1=0
P 2.3348425 3.4832677 15 P 0 0 ;0=11,1=0
P 2.3348425 3.5620079 15 P 0 0 ;0=11,1=0
P 2.3348425 3.640748 15 P 0 0 ;0=11,1=0
P 2.3484251 0.1377953 8 P 0 0 ;0=4,1=0
P 2.3507725 2.358813 6 P 0 0 ;0=2,1=0
P 2.3507725 2.518253 6 P 0 0 ;0=2,1=0
P 2.3507825 0.878873 6 P 0 0 ;0=2,1=0
P 2.3507825 1.038313 6 P 0 0 ;0=2,1=0
P 2.3581575 4.1703386 23 P 0 0 ;0=19,1=0
P 2.3704525 2.358813 6 P 0 0 ;0=2,1=0
P 2.3704525 2.518253 6 P 0 0 ;0=2,1=0
P 2.3704625 0.878873 6 P 0 0 ;0=2,1=0
P 2.3704625 1.038313 6 P 0 0 ;0=2,1=0
P 2.3778425 4.275063 25 P 0 0 ;0=21,1=0
P 2.383748 4.1703386 23 P 0 0 ;0=19,1=0
P 2.3877951 0.1377953 8 P 0 0 ;0=4,1=0
P 2.3877954 2.8996063 16 P 0 0 ;0=12,1=0
P 2.3877954 2.9586614 16 P 0 0 ;0=12,1=0
P 2.3901425 2.358813 6 P 0 0 ;0=2,1=0
P 2.3901425 2.518253 6 P 0 0 ;0=2,1=0
P 2.3901525 0.878873 6 P 0 0 ;0=2,1=0
P 2.3901525 1.038313 6 P 0 0 ;0=2,1=0
P 2.4098225 2.358813 6 P 0 0 ;0=2,1=0
P 2.4098225 2.518253 6 P 0 0 ;0=2,1=0
P 2.4098325 0.878873 6 P 0 0 ;0=2,1=0
P 2.4098325 1.038313 6 P 0 0 ;0=2,1=0
P 2.4223425 3.0822126 57 P 0 0 ;0=53,1=0
P 2.4223425 3.2396929 57 P 0 0 ;0=53,1=0
P 2.4223425 3.4438977 57 P 0 0 ;0=53,1=0
P 2.4223425 3.601378 57 P 0 0 ;0=53,1=0
P 2.4271651 0.1377953 8 P 0 0 ;0=4,1=0
P 2.4295125 2.358813 6 P 0 0 ;0=2,1=0
P 2.4295125 2.518253 6 P 0 0 ;0=2,1=0
P 2.4295225 0.878873 6 P 0 0 ;0=2,1=0
P 2.4295225 1.038313 6 P 0 0 ;0=2,1=0
P 2.4309921 4.1736851 24 P 0 0 ;0=20,1=0
P 2.4468503 0.1112205 3 P 0 0
P 2.4491925 2.358813 6 P 0 0 ;0=2,1=0
P 2.4491925 2.518253 6 P 0 0 ;0=2,1=0
P 2.4492025 0.878873 6 P 0 0 ;0=2,1=0
P 2.4492025 1.038313 6 P 0 0 ;0=2,1=0
P 2.4654409 4.275063 22 P 0 0 ;0=18,1=0
P 2.4665351 0.1377953 8 P 0 0 ;0=4,1=0
P 2.4688825 2.358813 6 P 0 0 ;0=2,1=0
P 2.4688825 2.518253 6 P 0 0 ;0=2,1=0
P 2.4688925 0.878873 6 P 0 0 ;0=2,1=0
P 2.4688925 1.038313 6 P 0 0 ;0=2,1=0
P 2.4885625 2.358813 6 P 0 0 ;0=2,1=0
P 2.4885625 2.518253 6 P 0 0 ;0=2,1=0
P 2.4885725 0.878873 6 P 0 0 ;0=2,1=0
P 2.4885725 1.038313 6 P 0 0 ;0=2,1=0
P 2.503937 0.5738189 55 P 0 0 ;0=51,1=0
P 2.503937 0.6072835 55 P 0 0 ;0=51,1=0
P 2.5059051 0.1377953 8 P 0 0 ;0=4,1=0
P 2.5082525 2.358813 6 P 0 0 ;0=2,1=0
P 2.5082525 2.518253 6 P 0 0 ;0=2,1=0
P 2.5082625 0.878873 6 P 0 0 ;0=2,1=0
P 2.5082625 1.038313 6 P 0 0 ;0=2,1=0
P 2.5098425 3.4045276 15 P 0 0 ;0=11,1=0
P 2.5098425 3.4832677 15 P 0 0 ;0=11,1=0
P 2.5098425 3.5620079 15 P 0 0 ;0=11,1=0
P 2.5098425 3.640748 15 P 0 0 ;0=11,1=0
P 2.5279325 2.358813 6 P 0 0 ;0=2,1=0
P 2.5279325 2.518253 6 P 0 0 ;0=2,1=0
P 2.5279425 0.878873 6 P 0 0 ;0=2,1=0
P 2.5279425 1.038313 6 P 0 0 ;0=2,1=0
P 2.5452751 0.1377953 8 P 0 0 ;0=4,1=0
P 2.5476225 2.358813 6 P 0 0 ;0=2,1=0
P 2.5476225 2.518253 6 P 0 0 ;0=2,1=0
P 2.5476325 0.878873 6 P 0 0 ;0=2,1=0
P 2.5476325 1.038313 6 P 0 0 ;0=2,1=0
P 2.5673025 2.358813 6 P 0 0 ;0=2,1=0
P 2.5673025 2.518253 6 P 0 0 ;0=2,1=0
P 2.5673125 0.878873 6 P 0 0 ;0=2,1=0
P 2.5673125 1.038313 6 P 0 0 ;0=2,1=0
P 2.5846451 0.1377953 8 P 0 0 ;0=4,1=0
P 2.5869925 2.358813 6 P 0 0 ;0=2,1=0
P 2.5869925 2.518253 6 P 0 0 ;0=2,1=0
P 2.5870025 0.878873 6 P 0 0 ;0=2,1=0
P 2.5870025 1.038313 6 P 0 0 ;0=2,1=0
P 2.6066725 2.358813 6 P 0 0 ;0=2,1=0
P 2.6066725 2.518253 6 P 0 0 ;0=2,1=0
P 2.6066825 0.878873 6 P 0 0 ;0=2,1=0
P 2.6066825 1.038313 6 P 0 0 ;0=2,1=0
P 2.6240151 0.1377953 8 P 0 0 ;0=4,1=0
P 2.6263625 2.358813 6 P 0 0 ;0=2,1=0
P 2.6263625 2.518253 6 P 0 0 ;0=2,1=0
P 2.6263725 0.878873 6 P 0 0 ;0=2,1=0
P 2.6263725 1.038313 6 P 0 0 ;0=2,1=0
P 2.6398425 3.5356299 49 P 0 0 ;0=45,1=0
P 2.6398425 3.6064961 49 P 0 0 ;0=45,1=0
P 2.6460425 2.358813 6 P 0 0 ;0=2,1=0
P 2.6460425 2.518253 6 P 0 0 ;0=2,1=0
P 2.6460525 0.878873 6 P 0 0 ;0=2,1=0
P 2.6460525 1.038313 6 P 0 0 ;0=2,1=0
P 2.6633851 0.1377953 8 P 0 0 ;0=4,1=0
P 2.6657325 2.358813 6 P 0 0 ;0=2,1=0
P 2.6657325 2.518253 6 P 0 0 ;0=2,1=0
P 2.6657425 0.878873 6 P 0 0 ;0=2,1=0
P 2.6657425 1.038313 6 P 0 0 ;0=2,1=0
P 2.6854125 2.358813 6 P 0 0 ;0=2,1=0
P 2.6854125 2.518253 6 P 0 0 ;0=2,1=0
P 2.6854225 0.878873 6 P 0 0 ;0=2,1=0
P 2.6854225 1.038313 6 P 0 0 ;0=2,1=0
P 2.694252 3.7503543 31 P 0 0 ;0=27,1=0
P 2.7027551 0.1377953 8 P 0 0 ;0=4,1=0
P 2.7051025 2.358813 6 P 0 0 ;0=2,1=0
P 2.7051025 2.518253 6 P 0 0 ;0=2,1=0
P 2.7051125 0.878873 6 P 0 0 ;0=2,1=0
P 2.7051125 1.038313 6 P 0 0 ;0=2,1=0
P 2.7198425 3.6617716 31 P 0 0 ;0=27,1=0
P 2.7247825 2.358813 6 P 0 0 ;0=2,1=0
P 2.7247825 2.518253 6 P 0 0 ;0=2,1=0
P 2.7247925 0.878873 6 P 0 0 ;0=2,1=0
P 2.7247925 1.038313 6 P 0 0 ;0=2,1=0
P 2.7248425 3.5591338 51 P 0 0 ;0=47,1=0
P 2.7248425 3.5929921 51 P 0 0 ;0=47,1=0
P 2.7421251 0.1377953 8 P 0 0 ;0=4,1=0
P 2.7444725 2.358813 6 P 0 0 ;0=2,1=0
P 2.7444725 2.518253 6 P 0 0 ;0=2,1=0
P 2.7444825 0.878873 6 P 0 0 ;0=2,1=0
P 2.7444825 1.038313 6 P 0 0 ;0=2,1=0
P 2.7454331 3.7503543 31 P 0 0 ;0=27,1=0
P 2.7568898 2.9372047 19 P 0 0 ;0=15,1=0
P 2.7568898 2.9872047 19 P 0 0 ;0=15,1=0
P 2.7568898 3.0372047 19 P 0 0 ;0=15,1=0
P 2.7568898 3.0872047 19 P 0 0 ;0=15,1=0
P 2.7568898 3.1372047 19 P 0 0 ;0=15,1=0
P 2.7568898 3.1872047 19 P 0 0 ;0=15,1=0
P 2.7568898 3.2372047 19 P 0 0 ;0=15,1=0
P 2.7568898 3.2872047 19 P 0 0 ;0=15,1=0
P 2.7641525 2.358813 6 P 0 0 ;0=2,1=0
P 2.7641525 2.518253 6 P 0 0 ;0=2,1=0
P 2.7641625 0.878873 6 P 0 0 ;0=2,1=0
P 2.7641625 1.038313 6 P 0 0 ;0=2,1=0
P 2.7814951 0.1377953 8 P 0 0 ;0=4,1=0
P 2.7838425 2.358813 6 P 0 0 ;0=2,1=0
P 2.7838425 2.518253 6 P 0 0 ;0=2,1=0
P 2.7838525 0.878873 6 P 0 0 ;0=2,1=0
P 2.7838525 1.038313 6 P 0 0 ;0=2,1=0
P 2.8035225 2.358813 6 P 0 0 ;0=2,1=0
P 2.8035225 2.518253 6 P 0 0 ;0=2,1=0
P 2.8035325 0.878873 6 P 0 0 ;0=2,1=0
P 2.8035325 1.038313 6 P 0 0 ;0=2,1=0
P 2.809252 3.7503543 31 P 0 0 ;0=27,1=0
P 2.8208651 0.1377953 8 P 0 0 ;0=4,1=0
P 2.8232125 2.358813 6 P 0 0 ;0=2,1=0
P 2.8232125 2.518253 6 P 0 0 ;0=2,1=0
P 2.8232225 0.878873 6 P 0 0 ;0=2,1=0
P 2.8232225 1.038313 6 P 0 0 ;0=2,1=0
P 2.8348425 3.6617716 31 P 0 0 ;0=27,1=0
P 2.8428925 2.358813 6 P 0 0 ;0=2,1=0
P 2.8428925 2.518253 6 P 0 0 ;0=2,1=0
P 2.8429025 0.878873 6 P 0 0 ;0=2,1=0
P 2.8429025 1.038313 6 P 0 0 ;0=2,1=0
P 2.8602351 0.1377953 8 P 0 0 ;0=4,1=0
P 2.8604331 3.7503543 31 P 0 0 ;0=27,1=0
P 2.8625825 2.358813 6 P 0 0 ;0=2,1=0
P 2.8625825 2.518253 6 P 0 0 ;0=2,1=0
P 2.8625925 0.878873 6 P 0 0 ;0=2,1=0
P 2.8625925 1.038313 6 P 0 0 ;0=2,1=0
P 2.8822625 2.358813 6 P 0 0 ;0=2,1=0
P 2.8822625 2.518253 6 P 0 0 ;0=2,1=0
P 2.8822725 0.878873 6 P 0 0 ;0=2,1=0
P 2.8822725 1.038313 6 P 0 0 ;0=2,1=0
P 2.8996051 0.1377953 8 P 0 0 ;0=4,1=0
P 2.9019525 2.358813 6 P 0 0 ;0=2,1=0
P 2.9019525 2.518253 6 P 0 0 ;0=2,1=0
P 2.9019625 0.878873 6 P 0 0 ;0=2,1=0
P 2.9019625 1.038313 6 P 0 0 ;0=2,1=0
P 2.9216325 2.358813 6 P 0 0 ;0=2,1=0
P 2.9216325 2.518253 6 P 0 0 ;0=2,1=0
P 2.9216425 0.878873 6 P 0 0 ;0=2,1=0
P 2.9216425 1.038313 6 P 0 0 ;0=2,1=0
P 2.9389751 0.1377953 8 P 0 0 ;0=4,1=0
P 2.9413225 2.358813 6 P 0 0 ;0=2,1=0
P 2.9413225 2.518253 6 P 0 0 ;0=2,1=0
P 2.9413325 0.878873 6 P 0 0 ;0=2,1=0
P 2.9413325 1.038313 6 P 0 0 ;0=2,1=0
P 2.9448425 3.6666929 41 P 0 0 ;0=37,1=0
P 2.9448425 3.7454331 41 P 0 0 ;0=37,1=0
P 2.9448425 3.951063 40 P 0 0 ;0=36,1=0
P 2.9448425 4.2211417 40 P 0 0 ;0=36,1=0
P 2.9610025 2.358813 6 P 0 0 ;0=2,1=0
P 2.9610025 2.518253 6 P 0 0 ;0=2,1=0
P 2.9610125 0.878873 6 P 0 0 ;0=2,1=0
P 2.9610125 1.038313 6 P 0 0 ;0=2,1=0
P 2.9783451 0.1377953 8 P 0 0 ;0=4,1=0
P 2.9806925 2.358813 6 P 0 0 ;0=2,1=0
P 2.9806925 2.518253 6 P 0 0 ;0=2,1=0
P 2.9807025 0.878873 6 P 0 0 ;0=2,1=0
P 2.9807025 1.038313 6 P 0 0 ;0=2,1=0
P 2.9905325 2.438533 59 P 0 0 ;0=55,1=0
P 2.9905425 0.958593 59 P 0 0 ;0=55,1=0
P 2.9948425 4.0861024 67 P 0 0 ;0=61,1=0
P 3.0177151 0.1377953 8 P 0 0 ;0=4,1=0
P 3.0249825 2.438533 7 P 0 0 ;0=3,1=0
P 3.0249925 0.958593 7 P 0 0 ;0=3,1=0
P 3.0448425 3.6666929 41 P 0 0 ;0=37,1=0
P 3.0448425 3.7454331 41 P 0 0 ;0=37,1=0
P 3.0448425 3.951063 40 P 0 0 ;0=36,1=0
P 3.0448425 4.2211417 40 P 0 0 ;0=36,1=0
P 3.0551181 0.5738189 55 P 0 0 ;0=51,1=0
P 3.0551181 0.6072835 55 P 0 0 ;0=51,1=0
P 3.0570851 0.1572953 9 P 0 0 ;0=5,1=0
P 3.0964551 0.1377953 8 P 0 0 ;0=4,1=0
P 3.1112205 2.9372047 19 P 0 0 ;0=15,1=0
P 3.1112205 2.9872047 19 P 0 0 ;0=15,1=0
P 3.1112205 3.0372047 19 P 0 0 ;0=15,1=0
P 3.1112205 3.0872047 19 P 0 0 ;0=15,1=0
P 3.1112205 3.1372047 19 P 0 0 ;0=15,1=0
P 3.1112205 3.1872047 19 P 0 0 ;0=15,1=0
P 3.1112205 3.2372047 19 P 0 0 ;0=15,1=0
P 3.1112205 3.2872047 19 P 0 0 ;0=15,1=0
P 3.1448425 3.6666929 41 P 0 0 ;0=37,1=0
P 3.1448425 3.7454331 41 P 0 0 ;0=37,1=0
P 3.1448425 3.951063 40 P 0 0 ;0=36,1=0
P 3.1448425 4.2211417 40 P 0 0 ;0=36,1=0
P 3.2091732 2.7952756 11 P 0 0 ;0=7,1=0
P 3.2091732 2.8149606 11 P 0 0 ;0=7,1=0
P 3.2091732 2.8346456 11 P 0 0 ;0=7,1=0
P 3.219252 3.7503543 31 P 0 0 ;0=27,1=0
P 3.2293307 2.7849212 10 P 0 0 ;0=6,1=0
P 3.2293307 2.845 10 P 0 0 ;0=6,1=0
P 3.2448425 3.6617716 31 P 0 0 ;0=27,1=0
P 3.2448425 3.951063 40 P 0 0 ;0=36,1=0
P 3.2448425 4.2211417 40 P 0 0 ;0=36,1=0
P 3.2490157 2.7849212 10 P 0 0 ;0=6,1=0
P 3.2490157 2.845 10 P 0 0 ;0=6,1=0
P 3.2691732 2.7952756 11 P 0 0 ;0=7,1=0
P 3.2691732 2.8149606 11 P 0 0 ;0=7,1=0
P 3.2691732 2.8346456 11 P 0 0 ;0=7,1=0
P 3.2704331 3.7503543 31 P 0 0 ;0=27,1=0
P 3.2948425 4.0861024 67 P 0 0 ;0=61,1=0
P 3.3331103 3.2062205 36 P 0 0 ;0=32,1=0
P 3.3331103 3.3951969 36 P 0 0 ;0=32,1=0
P 3.3448425 3.951063 40 P 0 0 ;0=36,1=0
P 3.3448425 4.2211417 40 P 0 0 ;0=36,1=0
P 3.3498425 3.6666929 41 P 0 0 ;0=37,1=0
P 3.3498425 3.7454331 41 P 0 0 ;0=37,1=0
P 3.3921654 3.2062205 36 P 0 0 ;0=32,1=0
P 3.3921654 3.3951969 36 P 0 0 ;0=32,1=0
P 3.4385827 2.8923386 39 P 0 0 ;0=35,1=0
P 3.4385827 3.0517874 39 P 0 0 ;0=35,1=0
P 3.444252 3.7503543 31 P 0 0 ;0=27,1=0
P 3.4444882 2.948441 37 P 0 0 ;0=33,1=0
P 3.4444882 2.995685 37 P 0 0 ;0=33,1=0
P 3.4512205 3.2062205 36 P 0 0 ;0=32,1=0
P 3.4512205 3.3951969 36 P 0 0 ;0=32,1=0
P 3.4698425 3.6617716 31 P 0 0 ;0=27,1=0
P 3.4776771 2.797063 12 P 0 0 ;0=8,1=0
P 3.4848425 2.8923386 38 P 0 0 ;0=34,1=0
P 3.4848425 3.0517874 38 P 0 0 ;0=34,1=0
P 3.4920225 1.319633 4 P 0 0 ;0=0,1=0
P 3.4920225 1.339323 4 P 0 0 ;0=0,1=0
P 3.4920225 1.359003 4 P 0 0 ;0=0,1=0
P 3.4920225 1.378693 4 P 0 0 ;0=0,1=0
P 3.4920225 1.398373 4 P 0 0 ;0=0,1=0
P 3.4920225 1.418063 4 P 0 0 ;0=0,1=0
P 3.4920225 1.437743 4 P 0 0 ;0=0,1=0
P 3.4920225 1.457433 4 P 0 0 ;0=0,1=0
P 3.4920225 1.477113 4 P 0 0 ;0=0,1=0
P 3.4920225 1.496803 4 P 0 0 ;0=0,1=0
P 3.4920225 1.516483 4 P 0 0 ;0=0,1=0
P 3.4920225 1.536173 4 P 0 0 ;0=0,1=0
P 3.4920225 1.555853 4 P 0 0 ;0=0,1=0
P 3.4920225 1.575543 4 P 0 0 ;0=0,1=0
P 3.4920225 1.595223 4 P 0 0 ;0=0,1=0
P 3.4920225 1.614913 4 P 0 0 ;0=0,1=0
P 3.4920225 1.634593 4 P 0 0 ;0=0,1=0
P 3.4920225 1.654283 4 P 0 0 ;0=0,1=0
P 3.4920225 1.673963 4 P 0 0 ;0=0,1=0
P 3.4920225 1.693653 4 P 0 0 ;0=0,1=0
P 3.4920225 1.713333 4 P 0 0 ;0=0,1=0
P 3.4920225 1.733023 4 P 0 0 ;0=0,1=0
P 3.4920225 1.752703 4 P 0 0 ;0=0,1=0
P 3.4920225 1.772393 4 P 0 0 ;0=0,1=0
P 3.4920225 1.792073 4 P 0 0 ;0=0,1=0
P 3.4920225 1.811763 4 P 0 0 ;0=0,1=0
P 3.4920225 1.831443 4 P 0 0 ;0=0,1=0
P 3.4920225 1.851133 4 P 0 0 ;0=0,1=0
P 3.4920225 1.870813 4 P 0 0 ;0=0,1=0
P 3.4920225 1.890503 4 P 0 0 ;0=0,1=0
P 3.4920225 1.910183 4 P 0 0 ;0=0,1=0
P 3.4920225 1.929873 4 P 0 0 ;0=0,1=0
P 3.4920225 1.949553 4 P 0 0 ;0=0,1=0
P 3.4920225 1.969243 4 P 0 0 ;0=0,1=0
P 3.4920225 1.988923 4 P 0 0 ;0=0,1=0
P 3.4920225 2.008613 4 P 0 0 ;0=0,1=0
P 3.4920225 2.028293 4 P 0 0 ;0=0,1=0
P 3.4920225 2.047983 4 P 0 0 ;0=0,1=0
P 3.4920225 2.067663 4 P 0 0 ;0=0,1=0
P 3.4920225 2.087353 4 P 0 0 ;0=0,1=0
P 3.4954331 3.7503543 31 P 0 0 ;0=27,1=0
P 3.5102756 3.2062205 36 P 0 0 ;0=32,1=0
P 3.5102756 3.3951969 36 P 0 0 ;0=32,1=0
P 3.5251968 2.948441 37 P 0 0 ;0=33,1=0
P 3.5251968 2.995685 37 P 0 0 ;0=33,1=0
P 3.5311023 2.8923386 39 P 0 0 ;0=35,1=0
P 3.5311023 3.0517874 39 P 0 0 ;0=35,1=0
P 3.5320078 2.797063 12 P 0 0 ;0=8,1=0
P 3.5693307 3.2062205 36 P 0 0 ;0=32,1=0
P 3.5693307 3.3853543 35 P 0 0 ;0=31,1=0
P 3.5717425 1.275343 5 P 0 0 ;0=1,1=0
P 3.5717425 1.309793 59 P 0 0 ;0=55,1=0
P 3.5717425 2.097193 59 P 0 0 ;0=55,1=0
P 3.5717425 2.131643 5 P 0 0 ;0=1,1=0
P 3.5898425 3.7275197 48 P 0 0 ;0=44,1=0
P 3.5898425 3.7846063 48 P 0 0 ;0=44,1=0
P 3.5898425 3.8525197 48 P 0 0 ;0=44,1=0
P 3.5898425 3.9096063 48 P 0 0 ;0=44,1=0
P 3.6179425 0.916293 58 P 0 0 ;0=54,1=0
P 3.6179425 2.486293 58 P 0 0 ;0=54,1=0
P 3.6514625 1.319633 4 P 0 0 ;0=0,1=0
P 3.6514625 1.339323 4 P 0 0 ;0=0,1=0
P 3.6514625 1.359003 4 P 0 0 ;0=0,1=0
P 3.6514625 1.378693 4 P 0 0 ;0=0,1=0
P 3.6514625 1.398373 4 P 0 0 ;0=0,1=0
P 3.6514625 1.418063 4 P 0 0 ;0=0,1=0
P 3.6514625 1.437743 4 P 0 0 ;0=0,1=0
P 3.6514625 1.457433 4 P 0 0 ;0=0,1=0
P 3.6514625 1.477113 4 P 0 0 ;0=0,1=0
P 3.6514625 1.496803 4 P 0 0 ;0=0,1=0
P 3.6514625 1.516483 4 P 0 0 ;0=0,1=0
P 3.6514625 1.536173 4 P 0 0 ;0=0,1=0
P 3.6514625 1.555853 4 P 0 0 ;0=0,1=0
P 3.6514625 1.575543 4 P 0 0 ;0=0,1=0
P 3.6514625 1.595223 4 P 0 0 ;0=0,1=0
P 3.6514625 1.614913 4 P 0 0 ;0=0,1=0
P 3.6514625 1.634593 4 P 0 0 ;0=0,1=0
P 3.6514625 1.654283 4 P 0 0 ;0=0,1=0
P 3.6514625 1.673963 4 P 0 0 ;0=0,1=0
P 3.6514625 1.693653 4 P 0 0 ;0=0,1=0
P 3.6514625 1.713333 4 P 0 0 ;0=0,1=0
P 3.6514625 1.733023 4 P 0 0 ;0=0,1=0
P 3.6514625 1.752703 4 P 0 0 ;0=0,1=0
P 3.6514625 1.772393 4 P 0 0 ;0=0,1=0
P 3.6514625 1.792073 4 P 0 0 ;0=0,1=0
P 3.6514625 1.811763 4 P 0 0 ;0=0,1=0
P 3.6514625 1.831443 4 P 0 0 ;0=0,1=0
P 3.6514625 1.851133 4 P 0 0 ;0=0,1=0
P 3.6514625 1.870813 4 P 0 0 ;0=0,1=0
P 3.6514625 1.890503 4 P 0 0 ;0=0,1=0
P 3.6514625 1.910183 4 P 0 0 ;0=0,1=0
P 3.6514625 1.929873 4 P 0 0 ;0=0,1=0
P 3.6514625 1.949553 4 P 0 0 ;0=0,1=0
P 3.6514625 1.969243 4 P 0 0 ;0=0,1=0
P 3.6514625 1.988923 4 P 0 0 ;0=0,1=0
P 3.6514625 2.008613 4 P 0 0 ;0=0,1=0
P 3.6514625 2.028293 4 P 0 0 ;0=0,1=0
P 3.6514625 2.047983 4 P 0 0 ;0=0,1=0
P 3.6514625 2.067663 4 P 0 0 ;0=0,1=0
P 3.6514625 2.087353 4 P 0 0 ;0=0,1=0
P 3.6594094 0.726063 52 P 0 0 ;0=48,1=0
P 3.6681102 3.786063 56 P 0 0 ;0=52,1=0
P 3.6681102 3.861063 56 P 0 0 ;0=52,1=0
P 3.6829133 0.636063 53 P 0 0 ;0=49,1=0
P 3.6888425 3.266567 50 P 0 0 ;0=46,1=0
P 3.6888425 3.3295591 50 P 0 0 ;0=46,1=0
P 3.6938425 3.1176299 49 P 0 0 ;0=45,1=0
P 3.6938425 3.1884961 49 P 0 0 ;0=45,1=0
P 3.6962598 4.0276378 28 P 0 0 ;0=24,1=0
P 3.6962598 4.2441732 28 P 0 0 ;0=24,1=0
P 3.7015748 3.786063 56 P 0 0 ;0=52,1=0
P 3.7015748 3.861063 56 P 0 0 ;0=52,1=0
P 3.7167716 0.636063 53 P 0 0 ;0=49,1=0
P 3.7302756 0.726063 52 P 0 0 ;0=48,1=0
P 3.7698425 3.2011339 51 P 0 0 ;0=47,1=0
P 3.7698425 3.2349922 51 P 0 0 ;0=47,1=0
P 3.772559 3.683563 32 P 0 0 ;0=28,1=0
P 3.772559 3.708563 32 P 0 0 ;0=28,1=0
P 3.772559 3.733563 32 P 0 0 ;0=28,1=0
P 3.772559 3.758563 32 P 0 0 ;0=28,1=0
P 3.772559 3.783563 32 P 0 0 ;0=28,1=0
P 3.772559 3.808563 32 P 0 0 ;0=28,1=0
P 3.772559 3.833563 32 P 0 0 ;0=28,1=0
P 3.772559 3.858563 32 P 0 0 ;0=28,1=0
P 3.7848425 4.126063 66 P 0 0 ;0=60,1=0
P 3.8084646 4.0237008 27 P 0 0 ;0=23,1=0
P 3.8399606 4.0237008 27 P 0 0 ;0=23,1=0
P 3.8714567 4.0237008 27 P 0 0 ;0=23,1=0
P 3.9029528 4.0237008 27 P 0 0 ;0=23,1=0
P 3.9114214 1.5996232 17 P 0 0 ;0=13,1=0
P 3.9114214 1.6196232 17 P 0 0 ;0=13,1=0
P 3.9114214 1.6396232 17 P 0 0 ;0=13,1=0
P 3.9114214 1.6596232 17 P 0 0 ;0=13,1=0
P 3.9114214 1.6796232 17 P 0 0 ;0=13,1=0
P 3.9114214 1.6996232 17 P 0 0 ;0=13,1=0
P 3.9114214 1.7196232 17 P 0 0 ;0=13,1=0
P 3.9114214 1.7396232 17 P 0 0 ;0=13,1=0
P 3.9114214 1.7596232 17 P 0 0 ;0=13,1=0
P 3.9114214 1.7796232 17 P 0 0 ;0=13,1=0
P 3.9344488 4.0237008 27 P 0 0 ;0=23,1=0
P 3.9580709 4.126063 66 P 0 0 ;0=60,1=0
P 3.9598425 2.7806299 49 P 0 0 ;0=45,1=0
P 3.9598425 2.8514961 49 P 0 0 ;0=45,1=0
P 3.9797272 0.8906186 63 P 0 0 ;0=58,1=0
P 3.9797272 2.4890438 63 P 0 0 ;0=58,1=0
P 3.9871259 3.683563 32 P 0 0 ;0=28,1=0
P 3.9871259 3.708563 32 P 0 0 ;0=28,1=0
P 3.9871259 3.733563 32 P 0 0 ;0=28,1=0
P 3.9871259 3.758563 32 P 0 0 ;0=28,1=0
P 3.9871259 3.783563 32 P 0 0 ;0=28,1=0
P 3.9871259 3.808563 32 P 0 0 ;0=28,1=0
P 3.9871259 3.833563 32 P 0 0 ;0=28,1=0
P 3.9871259 3.858563 32 P 0 0 ;0=28,1=0
P 4.0398425 3.029567 50 P 0 0 ;0=46,1=0
P 4.0398425 3.0925591 50 P 0 0 ;0=46,1=0
P 4.0466536 4.0276378 28 P 0 0 ;0=24,1=0
P 4.0466536 4.2441732 28 P 0 0 ;0=24,1=0
P 4.0624044 2.595343 63 P 0 0 ;0=58,1=0
P 4.0648425 2.7806299 49 P 0 0 ;0=45,1=0
P 4.0648425 2.8514961 49 P 0 0 ;0=45,1=0
P 4.0689017 1.5996232 17 P 0 0 ;0=13,1=0
P 4.0689017 1.6196232 17 P 0 0 ;0=13,1=0
P 4.0689017 1.6396232 17 P 0 0 ;0=13,1=0
P 4.0689017 1.6596232 17 P 0 0 ;0=13,1=0
P 4.0689017 1.6796232 17 P 0 0 ;0=13,1=0
P 4.0689017 1.6996232 17 P 0 0 ;0=13,1=0
P 4.0689017 1.7196232 17 P 0 0 ;0=13,1=0
P 4.0689017 1.7396232 17 P 0 0 ;0=13,1=0
P 4.0689017 1.7596232 17 P 0 0 ;0=13,1=0
P 4.0689017 1.7796232 17 P 0 0 ;0=13,1=0
P 4.1048425 3.7706299 49 P 0 0 ;0=45,1=0
P 4.1048425 3.8414961 49 P 0 0 ;0=45,1=0
P 4.1098425 3.0441338 51 P 0 0 ;0=47,1=0
P 4.1098425 3.0779921 51 P 0 0 ;0=47,1=0
P 4.1126772 3.701063 12 P 0 0 ;0=8,1=0
P 4.1498425 2.7898819 45 P 0 0 ;0=41,1=0
P 4.1498425 2.8422441 45 P 0 0 ;0=41,1=0
P 4.1505905 3.6033465 12 P 0 0 ;0=8,1=0
P 4.1648425 3.0441338 51 P 0 0 ;0=47,1=0
P 4.1648425 3.0779921 51 P 0 0 ;0=47,1=0
P 4.1670079 3.701063 12 P 0 0 ;0=8,1=0
P 4.1805146 2.595343 63 P 0 0 ;0=58,1=0
P 4.1948425 3.774567 50 P 0 0 ;0=46,1=0
P 4.1948425 3.8375591 50 P 0 0 ;0=46,1=0
P 4.2049212 3.6033465 12 P 0 0 ;0=8,1=0
P 4.2094094 3.246063 52 P 0 0 ;0=48,1=0
P 4.2198425 3.0441338 51 P 0 0 ;0=47,1=0
P 4.2198425 3.0779921 51 P 0 0 ;0=47,1=0
P 4.2348425 2.7806299 49 P 0 0 ;0=45,1=0
P 4.2348425 2.8514961 49 P 0 0 ;0=45,1=0
P 4.2748425 3.0441338 51 P 0 0 ;0=47,1=0
P 4.2748425 3.0779921 51 P 0 0 ;0=47,1=0
P 4.2755905 3.6033465 13 P 0 0 ;0=9,1=0
P 4.2802756 3.246063 52 P 0 0 ;0=48,1=0
P 4.2986248 2.595343 63 P 0 0 ;0=58,1=0
P 4.3277559 1.0074803 65 P 0 0 ;0=59,1=0
P 4.3277559 2.3074803 64 P 0 0 ;0=59,1=0
P 4.3326771 3.6033465 13 P 0 0 ;0=9,1=0
P 4.3348425 3.0441338 51 P 0 0 ;0=47,1=0
P 4.3348425 3.0779921 51 P 0 0 ;0=47,1=0
P 4.3398425 2.7806299 49 P 0 0 ;0=45,1=0
P 4.3398425 2.8514961 49 P 0 0 ;0=45,1=0
P 4.3948425 3.0441338 51 P 0 0 ;0=47,1=0
P 4.3948425 3.0779921 51 P 0 0 ;0=47,1=0
P 4.4329134 4.206063 42 P 0 0 ;0=38,1=0
P 4.4348425 2.7898819 45 P 0 0 ;0=41,1=0
P 4.4348425 2.8422441 45 P 0 0 ;0=41,1=0
P 4.4548425 3.0441338 51 P 0 0 ;0=47,1=0
P 4.4548425 3.0779921 51 P 0 0 ;0=47,1=0
P 4.5667716 4.206063 42 P 0 0 ;0=38,1=0
P 4.6526771 4.206063 12 P 0 0 ;0=8,1=0
P 4.6526772 4.121063 12 P 0 0 ;0=8,1=0
P 4.7070078 4.206063 12 P 0 0 ;0=8,1=0
P 4.7070079 4.121063 12 P 0 0 ;0=8,1=0
P 4.7277559 2.3074803 64 P 0 0 ;0=59,1=0
P 4.9094488 2.8080708 18 P 0 0 ;0=14,1=0
P 4.9094488 3.9616142 18 P 0 0 ;0=14,1=0
P 4.9277559 1.0074803 64 P 0 0 ;0=59,1=0
P 4.9277559 2.3074803 64 P 0 0 ;0=59,1=0
P 4.9579134 4.206063 42 P 0 0 ;0=38,1=0
P 5.0917716 4.206063 42 P 0 0 ;0=38,1=0
P 5.1277559 1.0074803 64 P 0 0 ;0=59,1=0
P 5.1277559 2.3074803 64 P 0 0 ;0=59,1=0
P 5.2126771 4.206063 12 P 0 0 ;0=8,1=0
P 5.2126772 4.126063 12 P 0 0 ;0=8,1=0
P 5.2670078 4.206063 12 P 0 0 ;0=8,1=0
P 5.2670079 4.126063 12 P 0 0 ;0=8,1=0
P 5.3277559 1.0074803 64 P 0 0 ;0=59,1=0
P 5.3277559 2.3074803 64 P 0 0 ;0=59,1=0
P 5.5781524 0.8906186 63 P 0 0 ;0=58,1=0
P 5.5781524 1.6898312 63 P 0 0 ;0=58,1=0
P 5.5781524 2.4890438 63 P 0 0 ;0=58,1=0
P 5.6344488 3.359252 53 P 0 0 ;0=49,1=0
P 5.6683071 3.359252 53 P 0 0 ;0=49,1=0
P 5.7234252 3.8444882 68 P 0 0 ;0=62,1=0
P 5.7234252 4.0255906 68 P 0 0 ;0=62,1=0
P 5.7411417 3.3612205 52 P 0 0 ;0=48,1=0
P 5.8120079 3.3612205 52 P 0 0 ;0=48,1=0
P 5.8879921 3.701063 20 P 0 0 ;0=16,1=0
P 5.9348031 3.9379527 71 P 0 0 ;0=65,1=0
P 6.0048425 2.3388977 54 P 0 0 ;0=50,1=0
P 6.0048425 2.3932284 54 P 0 0 ;0=50,1=0
P 6.0316929 3.701063 20 P 0 0 ;0=16,1=0
P 6.0356772 3.556063 12 P 0 0 ;0=8,1=0
P 6.0648425 2.3441339 51 P 0 0 ;0=47,1=0
P 6.0648425 2.3779922 51 P 0 0 ;0=47,1=0
P 6.0900079 3.556063 12 P 0 0 ;0=8,1=0
P 6.0933464 2.171063 21 P 0 0 ;0=17,1=0
P 6.1198425 3.8198425 69 P 0 0 ;0=63,1=0
P 6.1198425 4.056063 70 P 0 0 ;0=64,1=0
P 6.1228425 2.4338976 54 P 0 0 ;0=50,1=0
P 6.1228425 2.4882283 54 P 0 0 ;0=50,1=0
P 6.1563385 2.171063 21 P 0 0 ;0=17,1=0
P 6.1574016 2.241063 33 P 0 0 ;0=29,1=0
P 6.1574016 2.291063 33 P 0 0 ;0=29,1=0
P 6.1574016 2.341063 33 P 0 0 ;0=29,1=0
P 6.1574016 2.391063 33 P 0 0 ;0=29,1=0
P 6.1979921 3.701063 20 P 0 0 ;0=16,1=0
P 6.2029921 3.566063 20 P 0 0 ;0=16,1=0
P 6.2348425 2.1288977 54 P 0 0 ;0=50,1=0
P 6.2348425 2.1832284 54 P 0 0 ;0=50,1=0
P 6.253937 2.7559055 49 P 0 0 ;0=45,1=0
P 6.253937 2.8267717 49 P 0 0 ;0=45,1=0
P 6.3126772 2.451063 12 P 0 0 ;0=8,1=0
P 6.3198425 1.4601181 46 P 0 0 ;0=42,1=0
P 6.3198425 1.8420079 46 P 0 0 ;0=42,1=0
P 6.3279134 2.501063 53 P 0 0 ;0=49,1=0
P 6.3279134 2.556063 53 P 0 0 ;0=49,1=0
P 6.3279134 2.611063 53 P 0 0 ;0=49,1=0
P 6.3279134 2.656063 53 P 0 0 ;0=49,1=0
P 6.3348425 2.1106299 49 P 0 0 ;0=45,1=0
P 6.3348425 2.1814961 49 P 0 0 ;0=45,1=0
P 6.3416929 3.701063 20 P 0 0 ;0=16,1=0
P 6.3466929 3.566063 20 P 0 0 ;0=16,1=0
P 6.3522834 2.241063 33 P 0 0 ;0=29,1=0
P 6.3522834 2.291063 33 P 0 0 ;0=29,1=0
P 6.3522834 2.341063 33 P 0 0 ;0=29,1=0
P 6.3522834 2.391063 33 P 0 0 ;0=29,1=0
P 6.3617717 2.501063 53 P 0 0 ;0=49,1=0
P 6.3617717 2.556063 53 P 0 0 ;0=49,1=0
P 6.3617717 2.611063 53 P 0 0 ;0=49,1=0
P 6.3617717 2.656063 53 P 0 0 ;0=49,1=0
P 6.3670079 2.451063 12 P 0 0 ;0=8,1=0
P 6.3720472 2.7559055 49 P 0 0 ;0=45,1=0
P 6.3720472 2.8267717 49 P 0 0 ;0=45,1=0
P 6.3883268 3.1524803 44 P 0 0 ;0=40,1=0
P 6.3883268 3.1721654 44 P 0 0 ;0=40,1=0
P 6.3883268 3.1918504 44 P 0 0 ;0=40,1=0
P 6.3883268 3.2115354 44 P 0 0 ;0=40,1=0
P 6.3883268 3.2312205 44 P 0 0 ;0=40,1=0
P 6.3883268 3.2509055 44 P 0 0 ;0=40,1=0
P 6.3883268 3.2705906 44 P 0 0 ;0=40,1=0
P 6.3883268 3.2902756 44 P 0 0 ;0=40,1=0
P 6.3883268 3.3099606 44 P 0 0 ;0=40,1=0
P 6.3883268 3.3296457 44 P 0 0 ;0=40,1=0
P 6.4203149 3.1500197 43 P 0 0 ;0=39,1=0
P 6.4203149 3.3321063 43 P 0 0 ;0=39,1=0
P 6.4394094 3.071063 52 P 0 0 ;0=48,1=0
P 6.44 3.1500197 43 P 0 0 ;0=39,1=0
P 6.44 3.3321063 43 P 0 0 ;0=39,1=0
P 6.459685 3.3321063 43 P 0 0 ;0=39,1=0
P 6.4598425 3.1500197 43 P 0 0 ;0=39,1=0
P 6.4698425 2.2395669 50 P 0 0 ;0=46,1=0
P 6.4698425 2.302559 50 P 0 0 ;0=46,1=0
P 6.4793701 3.1500197 43 P 0 0 ;0=39,1=0
P 6.4793701 3.3321063 43 P 0 0 ;0=39,1=0
P 6.5102756 3.071063 52 P 0 0 ;0=48,1=0
P 6.5113582 3.1524803 44 P 0 0 ;0=40,1=0
P 6.5113582 3.1721654 44 P 0 0 ;0=40,1=0
P 6.5113582 3.1918504 44 P 0 0 ;0=40,1=0
P 6.5113582 3.2115354 44 P 0 0 ;0=40,1=0
P 6.5113582 3.2312205 44 P 0 0 ;0=40,1=0
P 6.5113582 3.2509055 44 P 0 0 ;0=40,1=0
P 6.5113582 3.2705906 44 P 0 0 ;0=40,1=0
P 6.5113582 3.2902756 44 P 0 0 ;0=40,1=0
P 6.5113582 3.3099606 44 P 0 0 ;0=40,1=0
P 6.5113582 3.3296457 44 P 0 0 ;0=40,1=0
P 6.5198425 1.954567 50 P 0 0 ;0=46,1=0
P 6.5198425 2.0175591 50 P 0 0 ;0=46,1=0
P 6.5694882 3.5895276 68 P 0 0 ;0=69,1=0
P 6.5694882 3.806063 68 P 0 0 ;0=69,1=0
P 6.5694882 4.0934646 74 P 0 0 ;0=68,1=0
P 6.5848425 3.0391338 51 P 0 0 ;0=47,1=0
P 6.5848425 3.0729921 51 P 0 0 ;0=47,1=0
P 6.6048425 3.1295669 50 P 0 0 ;0=46,1=0
P 6.6048425 3.192559 50 P 0 0 ;0=46,1=0
P 6.6048425 3.264567 50 P 0 0 ;0=46,1=0
P 6.6048425 3.3275591 50 P 0 0 ;0=46,1=0
P 6.6294094 1.421063 52 P 0 0 ;0=48,1=0
P 6.6294094 1.531063 52 P 0 0 ;0=48,1=0
P 6.6374016 1.881063 33 P 0 0 ;0=29,1=0
P 6.6374016 1.931063 33 P 0 0 ;0=29,1=0
P 6.6374016 1.981063 33 P 0 0 ;0=29,1=0
P 6.6374016 2.031063 33 P 0 0 ;0=29,1=0
P 6.6429133 1.611063 53 P 0 0 ;0=49,1=0
P 6.6429133 1.671063 53 P 0 0 ;0=49,1=0
P 6.6429133 1.721063 53 P 0 0 ;0=49,1=0
P 6.6429133 1.776063 53 P 0 0 ;0=49,1=0
P 6.6598425 2.0956299 49 P 0 0 ;0=45,1=0
P 6.6598425 2.1664961 49 P 0 0 ;0=45,1=0
P 6.6767716 1.611063 53 P 0 0 ;0=49,1=0
P 6.6767716 1.671063 53 P 0 0 ;0=49,1=0
P 6.6767716 1.721063 53 P 0 0 ;0=49,1=0
P 6.6767716 1.776063 53 P 0 0 ;0=49,1=0
P 6.6798425 2.4201181 46 P 0 0 ;0=42,1=0
P 6.6798425 2.8020079 46 P 0 0 ;0=42,1=0
P 6.7002756 1.421063 52 P 0 0 ;0=48,1=0
P 6.7002756 1.531063 52 P 0 0 ;0=48,1=0
P 6.7265748 3.1680709 34 P 0 0 ;0=30,1=0
P 6.7265748 3.2940551 34 P 0 0 ;0=30,1=0
P 6.7276771 1.816063 12 P 0 0 ;0=8,1=0
P 6.7348425 3.5895276 68 P 0 0 ;0=69,1=0
P 6.7348425 3.806063 68 P 0 0 ;0=69,1=0
P 6.7498425 2.0888976 54 P 0 0 ;0=50,1=0
P 6.7498425 2.1432283 54 P 0 0 ;0=50,1=0
P 6.7820078 1.816063 12 P 0 0 ;0=8,1=0
P 6.8322834 1.881063 33 P 0 0 ;0=29,1=0
P 6.8322834 1.931063 33 P 0 0 ;0=29,1=0
P 6.8322834 1.981063 33 P 0 0 ;0=29,1=0
P 6.8322834 2.031063 33 P 0 0 ;0=29,1=0
P 6.8426771 1.816063 12 P 0 0 ;0=8,1=0
P 6.8433465 2.096063 21 P 0 0 ;0=17,1=0
P 6.8970078 1.816063 12 P 0 0 ;0=8,1=0
P 6.9001969 3.5895276 68 P 0 0 ;0=69,1=0
P 6.9001969 3.806063 68 P 0 0 ;0=69,1=0
P 6.9001969 4.0934646 74 P 0 0 ;0=70,1=0
P 6.9063386 2.096063 21 P 0 0 ;0=17,1=0
P 6.9398425 1.8891338 51 P 0 0 ;0=47,1=0
P 6.9398425 1.9229921 51 P 0 0 ;0=47,1=0
P 6.9431102 3.1680709 34 P 0 0 ;0=30,1=0
P 6.9431102 3.2940551 34 P 0 0 ;0=30,1=0
P 7.0098425 1.8838977 54 P 0 0 ;0=50,1=0
P 7.0098425 1.9382284 54 P 0 0 ;0=50,1=0
P 0.149508 2.830047 76 P 0 0 ;0=72,1=1
P 0.149508 3.853669 76 P 0 0 ;0=72,1=1
P 0.6538425 1.551063 75 P 0 0 ;0=71,1=1
P 0.6539669 2.5938902 75 P 0 0 ;0=71,1=1
P 0.6548425 0.790063 75 P 0 0 ;0=71,1=1
P 0.6548425 1.314063 75 P 0 0 ;0=71,1=1
P 0.6548425 1.839063 75 P 0 0 ;0=71,1=1
P 0.6548425 2.073063 75 P 0 0 ;0=71,1=1
P 0.6548425 2.365063 75 P 0 0 ;0=71,1=1
P 0.6558425 1.028063 75 P 0 0 ;0=71,1=1
P 0.9370078 2.3179133 75 P 0 0 ;0=71,1=1
P 0.988189 1.7175197 75 P 0 0 ;0=71,1=1
P 0.9901575 0.6870079 75 P 0 0 ;0=71,1=1
P 0.996063 1.1870079 75 P 0 0 ;0=71,1=1
P 0.9968357 2.256036 75 P 0 0 ;0=71,1=1
P 1.0048425 0.906063 75 P 0 0 ;0=71,1=1
P 1.0088425 1.430063 75 P 0 0 ;0=71,1=1
P 1.0098425 1.956063 75 P 0 0 ;0=71,1=1
P 1.0208425 2.481063 75 P 0 0 ;0=71,1=1
P 1.2428425 1.472063 75 P 0 0 ;0=71,1=1
P 1.2488425 2.000063 75 P 0 0 ;0=71,1=1
P 1.2568425 0.942063 75 P 0 0 ;0=71,1=1
P 1.2618425 2.482063 75 P 0 0 ;0=71,1=1
P 1.2948425 4.256063 75 P 0 0 ;0=71,1=1
P 1.3454724 4.1751969 75 P 0 0 ;0=71,1=1
P 1.3937008 1.8169291 75 P 0 0 ;0=71,1=1
P 1.4084645 3.980315 75 P 0 0 ;0=71,1=1
P 1.4408425 3.557063 75 P 0 0 ;0=71,1=1
P 1.4598425 3.147063 75 P 0 0 ;0=71,1=1
P 1.5498425 3.621063 75 P 0 0 ;0=71,1=1
P 1.5578425 4.229063 75 P 0 0 ;0=71,1=1
P 1.5679134 1.2854331 75 P 0 0 ;0=71,1=1
P 1.5682025 2.067703 75 P 0 0 ;0=71,1=1
P 1.5698819 4.1712599 75 P 0 0 ;0=71,1=1
P 1.5748425 3.596063 75 P 0 0 ;0=71,1=1
P 1.6198425 2.121063 75 P 0 0 ;0=71,1=1
P 1.6708425 1.595063 75 P 0 0 ;0=71,1=1
P 1.6708425 1.694063 75 P 0 0 ;0=71,1=1
P 1.6718425 1.399063 75 P 0 0 ;0=71,1=1
P 1.6718425 1.497063 75 P 0 0 ;0=71,1=1
P 1.6718425 1.792063 75 P 0 0 ;0=71,1=1
P 1.6748425 1.989063 75 P 0 0 ;0=71,1=1
P 1.6758425 1.891063 75 P 0 0 ;0=71,1=1
P 1.6918425 4.079063 75 P 0 0 ;0=71,1=1
P 1.7148425 1.595063 75 P 0 0 ;0=71,1=1
P 1.7168425 1.399063 75 P 0 0 ;0=71,1=1
P 1.7188425 1.497063 75 P 0 0 ;0=71,1=1
P 1.7188425 1.792063 75 P 0 0 ;0=71,1=1
P 1.7198425 1.536063 75 P 0 0 ;0=71,1=1
P 1.7218425 1.694063 75 P 0 0 ;0=71,1=1
P 1.7218425 1.890063 75 P 0 0 ;0=71,1=1
P 1.7218425 1.989063 75 P 0 0 ;0=71,1=1
P 1.7268425 4.329374 75 P 0 0 ;0=71,1=1
P 1.7498425 4.110063 75 P 0 0 ;0=71,1=1
P 1.7548425 2.126063 75 P 0 0 ;0=71,1=1
P 1.7548425 3.661063 75 P 0 0 ;0=71,1=1
P 1.7798425 4.156063 75 P 0 0 ;0=71,1=1
P 1.7888425 4.329374 75 P 0 0 ;0=71,1=1
P 1.7978425 0.355063 75 P 0 0 ;0=71,1=1
P 1.7982283 1.3041339 75 P 0 0 ;0=71,1=1
P 1.8227825 1.674003 75 P 0 0 ;0=71,1=1
P 1.8326771 0.2559055 75 P 0 0 ;0=71,1=1
P 1.8326771 0.2874016 75 P 0 0 ;0=71,1=1
P 1.8498425 3.701063 75 P 0 0 ;0=71,1=1
P 1.8523622 0.2559055 75 P 0 0 ;0=71,1=1
P 1.8523622 0.2874016 75 P 0 0 ;0=71,1=1
P 1.8720472 0.2559055 75 P 0 0 ;0=71,1=1
P 1.8720472 0.2874016 75 P 0 0 ;0=71,1=1
P 1.8799377 1.811803 75 P 0 0 ;0=71,1=1
P 1.8848425 2.071063 75 P 0 0 ;0=71,1=1
P 1.8848425 3.601063 75 P 0 0 ;0=71,1=1
P 1.8938425 1.693063 75 P 0 0 ;0=71,1=1
P 1.8973025 1.516523 75 P 0 0 ;0=71,1=1
P 1.9038425 4.018063 75 P 0 0 ;0=71,1=1
P 1.9161425 0.244763 75 P 0 0 ;0=71,1=1
P 2.0048425 1.336063 75 P 0 0 ;0=71,1=1
P 2.0048425 3.816063 75 P 0 0 ;0=71,1=1
P 2.0288425 1.361663 75 P 0 0 ;0=71,1=1
P 2.0298425 3.836063 75 P 0 0 ;0=71,1=1
P 2.0348425 0.246063 75 P 0 0 ;0=71,1=1
P 2.0598425 1.386063 75 P 0 0 ;0=71,1=1
P 2.0598425 3.871063 75 P 0 0 ;0=71,1=1
P 2.0767716 0.2559055 75 P 0 0 ;0=71,1=1
P 2.0767716 0.2874016 75 P 0 0 ;0=71,1=1
P 2.0838425 1.411663 75 P 0 0 ;0=71,1=1
P 2.0848425 3.896063 75 P 0 0 ;0=71,1=1
P 2.1122047 0.2559055 75 P 0 0 ;0=71,1=1
P 2.1122047 0.2874016 75 P 0 0 ;0=71,1=1
P 2.1398425 3.611063 75 P 0 0 ;0=71,1=1
P 2.1398425 3.738063 75 P 0 0 ;0=71,1=1
P 2.1460663 4.1037909 75 P 0 0 ;0=71,1=1
P 2.1468425 2.753063 75 P 0 0 ;0=71,1=1
P 2.1515748 0.2559055 75 P 0 0 ;0=71,1=1
P 2.1515748 0.2874016 75 P 0 0 ;0=71,1=1
P 2.2058425 3.200063 75 P 0 0 ;0=71,1=1
P 2.2068425 1.298063 75 P 0 0 ;0=71,1=1
P 2.2317425 2.584163 75 P 0 0 ;0=71,1=1
P 2.2348425 3.506063 75 P 0 0 ;0=71,1=1
P 2.2523425 2.613563 75 P 0 0 ;0=71,1=1
P 2.2538425 2.279063 75 P 0 0 ;0=71,1=1
P 2.253937 4.0866142 75 P 0 0 ;0=71,1=1
P 2.2548425 3.536063 75 P 0 0 ;0=71,1=1
P 2.2588425 3.741063 75 P 0 0 ;0=71,1=1
P 2.2598425 3.261063 75 P 0 0 ;0=71,1=1
P 2.2720325 2.463873 75 P 0 0 ;0=71,1=1
P 2.2748425 1.506063 75 P 0 0 ;0=71,1=1
P 2.2908425 4.217063 75 P 0 0 ;0=71,1=1
P 2.2998425 1.916063 75 P 0 0 ;0=71,1=1
P 2.3098425 0.246063 75 P 0 0 ;0=71,1=1
P 2.3114125 1.0900094 75 P 0 0 ;0=71,1=1
P 2.3118425 0.934063 75 P 0 0 ;0=71,1=1
P 2.3215354 2.586063 75 P 0 0 ;0=71,1=1
P 2.3215354 3.361063 75 P 0 0 ;0=71,1=1
P 2.3308425 2.215063 75 P 0 0 ;0=71,1=1
P 2.3503937 0.4055118 75 P 0 0 ;0=71,1=1
P 2.3533464 4.0177165 75 P 0 0 ;0=71,1=1
P 2.3848425 1.941063 75 P 0 0 ;0=71,1=1
P 2.3897638 0.4055118 75 P 0 0 ;0=71,1=1
P 2.3898425 3.481063 75 P 0 0 ;0=71,1=1
P 2.394685 2.7204724 75 P 0 0 ;0=71,1=1
P 2.4048425 2.412063 75 P 0 0 ;0=71,1=1
P 2.4098325 0.932053 75 P 0 0 ;0=71,1=1
P 2.4098325 1.088053 75 P 0 0 ;0=71,1=1
P 2.4098425 1.967063 75 P 0 0 ;0=71,1=1
P 2.4098425 2.283063 75 P 0 0 ;0=71,1=1
P 2.4098425 2.314063 75 P 0 0 ;0=71,1=1
P 2.4098425 2.579063 75 P 0 0 ;0=71,1=1
P 2.4133858 0.2795276 75 P 0 0 ;0=71,1=1
P 2.4138425 3.295063 75 P 0 0 ;0=71,1=1
P 2.4140551 3.1998504 75 P 0 0 ;0=71,1=1
P 2.4187174 3.1185066 75 P 0 0 ;0=71,1=1
P 2.4192759 2.7886295 75 P 0 0 ;0=71,1=1
P 2.4291925 2.621063 75 P 0 0 ;0=71,1=1
P 2.4348425 3.546063 75 P 0 0 ;0=71,1=1
P 2.4448819 0.2795276 75 P 0 0 ;0=71,1=1
P 2.4468425 1.437063 75 P 0 0 ;0=71,1=1
P 2.4470546 0.2425914 75 P 0 0 ;0=71,1=1
P 2.4508425 2.282063 75 P 0 0 ;0=71,1=1
P 2.462374 3.1722441 75 P 0 0 ;0=71,1=1
P 2.4698827 0.4109883 75 P 0 0 ;0=71,1=1
P 2.4738425 2.980063 75 P 0 0 ;0=71,1=1
P 2.4758425 2.291063 75 P 0 0 ;0=71,1=1
P 2.4758425 2.456063 75 P 0 0 ;0=71,1=1
P 2.4788425 0.937063 75 P 0 0 ;0=71,1=1
P 2.4888425 2.413063 75 P 0 0 ;0=71,1=1
P 2.4948425 2.661063 75 P 0 0 ;0=71,1=1
P 2.4948425 2.696063 75 P 0 0 ;0=71,1=1
P 2.4998425 2.236063 75 P 0 0 ;0=71,1=1
P 2.5028425 1.316063 75 P 0 0 ;0=71,1=1
P 2.5082625 0.931483 75 P 0 0 ;0=71,1=1
P 2.5088425 1.090063 75 P 0 0 ;0=71,1=1
P 2.511811 0.4055118 75 P 0 0 ;0=71,1=1
P 2.5258425 2.463063 75 P 0 0 ;0=71,1=1
P 2.531398 2.830047 76 P 0 0 ;0=72,1=1
P 2.531398 3.853669 76 P 0 0 ;0=72,1=1
P 2.5460625 0.244843 75 P 0 0 ;0=71,1=1
P 2.5498425 1.755063 75 P 0 0 ;0=71,1=1
P 2.5708425 4.283063 75 P 0 0 ;0=71,1=1
P 2.5758425 2.412063 75 P 0 0 ;0=71,1=1
P 2.5787402 0.2795276 75 P 0 0 ;0=71,1=1
P 2.5798425 1.790063 75 P 0 0 ;0=71,1=1
P 2.5798425 2.281063 75 P 0 0 ;0=71,1=1
P 2.5798425 3.486063 75 P 0 0 ;0=71,1=1
P 2.5818425 2.308063 75 P 0 0 ;0=71,1=1
P 2.5868425 2.569063 75 P 0 0 ;0=71,1=1
P 2.5908425 3.288063 75 P 0 0 ;0=71,1=1
P 2.5918425 3.1862205 75 P 0 0 ;0=71,1=1
P 2.5984252 0.7952756 75 P 0 0 ;0=71,1=1
P 2.5998425 2.436063 75 P 0 0 ;0=71,1=1
P 2.6048425 1.734063 75 P 0 0 ;0=71,1=1
P 2.6066825 0.931903 75 P 0 0 ;0=71,1=1
P 2.6068425 1.091063 75 P 0 0 ;0=71,1=1
P 2.6102362 0.2795276 75 P 0 0 ;0=71,1=1
P 2.6220472 0.976378 75 P 0 0 ;0=71,1=1
P 2.6248425 2.461063 75 P 0 0 ;0=71,1=1
P 2.6259843 0.7952756 75 P 0 0 ;0=71,1=1
P 2.6268425 1.770063 75 P 0 0 ;0=71,1=1
P 2.6318425 2.876063 75 P 0 0 ;0=71,1=1
P 2.6348425 3.406063 75 P 0 0 ;0=71,1=1
P 2.636874 0.2479055 75 P 0 0 ;0=71,1=1
P 2.6438425 1.616063 75 P 0 0 ;0=71,1=1
P 2.6458425 2.274063 75 P 0 0 ;0=71,1=1
P 2.6496063 0.976378 75 P 0 0 ;0=71,1=1
P 2.6653543 0.4055118 75 P 0 0 ;0=71,1=1
P 2.6653543 0.7952756 75 P 0 0 ;0=71,1=1
P 2.6658425 1.092063 75 P 0 0 ;0=71,1=1
P 2.6658425 2.291063 75 P 0 0 ;0=71,1=1
P 2.6668425 1.640063 75 P 0 0 ;0=71,1=1
P 2.6748425 3.501063 75 P 0 0 ;0=71,1=1
P 2.6798425 3.661063 75 P 0 0 ;0=71,1=1
P 2.6811024 0.976378 75 P 0 0 ;0=71,1=1
P 2.6858425 2.311063 75 P 0 0 ;0=71,1=1
P 2.6858425 2.568063 75 P 0 0 ;0=71,1=1
P 2.6929134 0.7952756 75 P 0 0 ;0=71,1=1
P 2.6929134 2.7214567 75 P 0 0 ;0=71,1=1
P 2.6948425 1.481063 75 P 0 0 ;0=71,1=1
P 2.7028425 2.289063 75 P 0 0 ;0=71,1=1
P 2.7047244 0.4055118 75 P 0 0 ;0=71,1=1
P 2.7086614 0.976378 75 P 0 0 ;0=71,1=1
P 2.7198425 1.591063 75 P 0 0 ;0=71,1=1
P 2.7224094 3.7860709 75 P 0 0 ;0=71,1=1
P 2.7244825 1.093063 75 P 0 0 ;0=71,1=1
P 2.7248425 3.521063 75 P 0 0 ;0=71,1=1
P 2.7248425 3.729063 75 P 0 0 ;0=71,1=1
P 2.7268425 2.293063 75 P 0 0 ;0=71,1=1
P 2.7322835 0.7952756 75 P 0 0 ;0=71,1=1
P 2.7401575 0.976378 75 P 0 0 ;0=71,1=1
P 2.74882 0.282312 75 P 0 0 ;0=71,1=1
P 2.7598425 0.7952756 75 P 0 0 ;0=71,1=1
P 2.7677165 0.976378 75 P 0 0 ;0=71,1=1
P 2.7748425 3.566063 75 P 0 0 ;0=71,1=1
P 2.7795276 0.2795276 75 P 0 0 ;0=71,1=1
P 2.7838425 2.429063 75 P 0 0 ;0=71,1=1
P 2.7838425 2.568063 75 P 0 0 ;0=71,1=1
P 2.7841625 1.094063 75 P 0 0 ;0=71,1=1
P 2.7992126 0.7952756 75 P 0 0 ;0=71,1=1
P 2.7992126 0.976378 75 P 0 0 ;0=71,1=1
P 2.7998425 3.616063 75 P 0 0 ;0=71,1=1
P 2.7999951 0.2519685 75 P 0 0 ;0=71,1=1
P 2.8038425 2.307063 75 P 0 0 ;0=71,1=1
P 2.8218425 2.601063 75 P 0 0 ;0=71,1=1
P 2.8219832 0.4078519 75 P 0 0 ;0=71,1=1
P 2.8267717 0.7952756 75 P 0 0 ;0=71,1=1
P 2.8267717 0.976378 75 P 0 0 ;0=71,1=1
P 2.8418425 2.263063 75 P 0 0 ;0=71,1=1
P 2.8428425 1.095063 75 P 0 0 ;0=71,1=1
P 2.8543307 0.4055118 75 P 0 0 ;0=71,1=1
P 2.8608425 3.787063 75 P 0 0 ;0=71,1=1
P 2.8622047 0.7952756 75 P 0 0 ;0=71,1=1
P 2.8718425 2.297063 75 P 0 0 ;0=71,1=1
P 2.8782843 0.2495967 75 P 0 0 ;0=71,1=1
P 2.8818425 2.566063 75 P 0 0 ;0=71,1=1
P 2.8888425 4.221063 75 P 0 0 ;0=71,1=1
P 2.8937008 0.7952756 75 P 0 0 ;0=71,1=1
P 2.8948425 1.561063 75 P 0 0 ;0=71,1=1
P 2.8948425 2.431063 75 P 0 0 ;0=71,1=1
P 2.9018425 1.095063 75 P 0 0 ;0=71,1=1
P 2.9054946 0.2795104 75 P 0 0 ;0=71,1=1
P 2.9198425 1.536063 75 P 0 0 ;0=71,1=1
P 2.9208425 2.428063 75 P 0 0 ;0=71,1=1
P 2.9338425 0.953063 75 P 0 0 ;0=71,1=1
P 2.9370079 0.2795276 75 P 0 0 ;0=71,1=1
P 2.9428425 2.286063 75 P 0 0 ;0=71,1=1
P 2.9488425 2.456063 75 P 0 0 ;0=71,1=1
P 2.9574751 0.2519685 75 P 0 0 ;0=71,1=1
P 2.9588425 2.621063 75 P 0 0 ;0=71,1=1
P 2.980457 0.4091539 75 P 0 0 ;0=71,1=1
P 2.9858425 2.287063 75 P 0 0 ;0=71,1=1
P 2.9933858 3.751063 75 P 0 0 ;0=71,1=1
P 3.0148425 3.831063 75 P 0 0 ;0=71,1=1
P 3.019685 0.4055118 75 P 0 0 ;0=71,1=1
P 3.0568817 1.811803 75 P 0 0 ;0=71,1=1
P 3.0688976 3.3956693 75 P 0 0 ;0=71,1=1
P 3.0974409 0.2519685 75 P 0 0 ;0=71,1=1
P 3.1830708 3.1358268 75 P 0 0 ;0=71,1=1
P 3.1889764 3.1870079 75 P 0 0 ;0=71,1=1
P 3.1972633 1.714063 75 P 0 0 ;0=71,1=1
P 3.1978425 2.970063 75 P 0 0 ;0=71,1=1
P 3.2198425 3.806063 75 P 0 0 ;0=71,1=1
P 3.2248425 1.6613472 75 P 0 0 ;0=71,1=1
P 3.2308425 3.235063 75 P 0 0 ;0=71,1=1
P 3.2398425 3.596063 75 P 0 0 ;0=71,1=1
P 3.2528425 1.661063 75 P 0 0 ;0=71,1=1
P 3.2636972 3.3039177 75 P 0 0 ;0=71,1=1
P 3.2698425 3.788063 75 P 0 0 ;0=71,1=1
P 3.2755905 3.1417323 75 P 0 0 ;0=71,1=1
P 3.277559 2.9635827 75 P 0 0 ;0=71,1=1
P 3.2988425 1.971063 75 P 0 0 ;0=71,1=1
P 3.3028425 3.344063 75 P 0 0 ;0=71,1=1
P 3.3291721 1.826063 75 P 0 0 ;0=71,1=1
P 3.3308425 3.301063 75 P 0 0 ;0=71,1=1
P 3.3428425 2.263063 75 P 0 0 ;0=71,1=1
P 3.3448425 2.996063 75 P 0 0 ;0=71,1=1
P 3.3588425 3.448063 75 P 0 0 ;0=71,1=1
P 3.3688425 3.050063 75 P 0 0 ;0=71,1=1
P 3.3708425 2.888063 75 P 0 0 ;0=71,1=1
P 3.3748425 3.273063 75 P 0 0 ;0=71,1=1
P 3.3798425 1.336063 75 P 0 0 ;0=71,1=1
P 3.3798425 1.386063 75 P 0 0 ;0=71,1=1
P 3.3928425 1.871063 75 P 0 0 ;0=71,1=1
P 3.3948425 3.447063 75 P 0 0 ;0=71,1=1
P 3.3958425 4.222063 75 P 0 0 ;0=71,1=1
P 3.4048425 1.363323 75 P 0 0 ;0=71,1=1
P 3.4068425 1.461063 75 P 0 0 ;0=71,1=1
P 3.4072822 1.411323 75 P 0 0 ;0=71,1=1
P 3.4108425 1.7136509 75 P 0 0 ;0=71,1=1
P 3.4138425 1.573063 75 P 0 0 ;0=71,1=1
P 3.4144661 1.805063 75 P 0 0 ;0=71,1=1
P 3.4248425 3.636063 75 P 0 0 ;0=71,1=1
P 3.4368425 3.457063 75 P 0 0 ;0=71,1=1
P 3.4392507 1.870938 75 P 0 0 ;0=71,1=1
P 3.4698425 3.456063 75 P 0 0 ;0=71,1=1
P 3.4918425 3.103063 75 P 0 0 ;0=71,1=1
P 3.4918425 3.297063 75 P 0 0 ;0=71,1=1
P 3.4988425 2.341063 75 P 0 0 ;0=71,1=1
P 3.5048425 4.086063 75 P 0 0 ;0=71,1=1
P 3.5298425 3.481063 75 P 0 0 ;0=71,1=1
P 3.5318425 3.660063 75 P 0 0 ;0=71,1=1
P 3.5398425 3.806063 75 P 0 0 ;0=71,1=1
P 3.542865 3.3190405 75 P 0 0 ;0=71,1=1
P 3.5498425 1.413063 75 P 0 0 ;0=71,1=1
P 3.5498425 1.441063 75 P 0 0 ;0=71,1=1
P 3.5548425 1.841063 75 P 0 0 ;0=71,1=1
P 3.5548425 1.891063 75 P 0 0 ;0=71,1=1
P 3.5548425 1.941063 75 P 0 0 ;0=71,1=1
P 3.5548425 1.991063 75 P 0 0 ;0=71,1=1
P 3.5718425 2.033063 75 P 0 0 ;0=71,1=1
P 3.5718425 2.058063 75 P 0 0 ;0=71,1=1
P 3.5898425 1.711063 75 P 0 0 ;0=71,1=1
P 3.5908425 1.662063 75 P 0 0 ;0=71,1=1
P 3.5948425 1.514063 75 P 0 0 ;0=71,1=1
P 3.6038425 0.682063 75 P 0 0 ;0=71,1=1
P 3.6228425 3.486063 75 P 0 0 ;0=71,1=1
P 3.6238425 2.587063 75 P 0 0 ;0=71,1=1
P 3.6428425 0.636063 75 P 0 0 ;0=71,1=1
P 3.6538425 3.293063 75 P 0 0 ;0=71,1=1
P 3.6998425 3.751063 75 P 0 0 ;0=71,1=1
P 3.6998425 3.836063 75 P 0 0 ;0=71,1=1
P 3.7178425 3.072063 75 P 0 0 ;0=71,1=1
P 3.7188425 1.713063 75 P 0 0 ;0=71,1=1
P 3.7198425 1.766063 75 P 0 0 ;0=71,1=1
P 3.7198425 1.921063 75 P 0 0 ;0=71,1=1
P 3.7198425 1.996063 75 P 0 0 ;0=71,1=1
P 3.7248425 1.675063 75 P 0 0 ;0=71,1=1
P 3.7328425 1.418063 75 P 0 0 ;0=71,1=1
P 3.7448425 3.261063 75 P 0 0 ;0=71,1=1
P 3.7448425 3.342063 75 P 0 0 ;0=71,1=1
P 3.7738632 1.6661021 75 P 0 0 ;0=71,1=1
P 3.7778425 4.023063 75 P 0 0 ;0=71,1=1
P 3.7998425 3.201063 75 P 0 0 ;0=71,1=1
P 3.8038425 1.691063 75 P 0 0 ;0=71,1=1
P 3.8048425 1.840063 75 P 0 0 ;0=71,1=1
P 3.8068425 3.235063 75 P 0 0 ;0=71,1=1
P 3.8298425 3.176063 75 P 0 0 ;0=71,1=1
P 3.8298425 3.806063 75 P 0 0 ;0=71,1=1
P 3.8308425 3.762063 75 P 0 0 ;0=71,1=1
P 3.8348425 1.481063 75 P 0 0 ;0=71,1=1
P 3.8548425 3.151063 75 P 0 0 ;0=71,1=1
P 3.8648425 1.511063 75 P 0 0 ;0=71,1=1
P 3.8808425 3.109063 75 P 0 0 ;0=71,1=1
P 3.8948425 1.566063 75 P 0 0 ;0=71,1=1
P 3.9248425 1.536063 75 P 0 0 ;0=71,1=1
P 3.9398425 3.121063 75 P 0 0 ;0=71,1=1
P 3.9448425 1.816063 75 P 0 0 ;0=71,1=1
P 3.9608425 2.724063 75 P 0 0 ;0=71,1=1
P 3.9688425 1.671063 75 P 0 0 ;0=71,1=1
P 3.9698425 1.552063 75 P 0 0 ;0=71,1=1
P 3.9948425 1.551063 75 P 0 0 ;0=71,1=1
P 3.9968425 1.711063 75 P 0 0 ;0=71,1=1
P 4.0348425 1.546063 75 P 0 0 ;0=71,1=1
P 4.0398425 2.406063 75 P 0 0 ;0=71,1=1
P 4.0398425 3.784063 75 P 0 0 ;0=71,1=1
P 4.0498425 3.665063 75 P 0 0 ;0=71,1=1
P 4.0648425 1.511063 75 P 0 0 ;0=71,1=1
P 4.0648425 1.796063 75 P 0 0 ;0=71,1=1
P 4.0648425 2.722063 75 P 0 0 ;0=71,1=1
P 4.0688425 3.135063 75 P 0 0 ;0=71,1=1
P 4.0858425 3.892063 75 P 0 0 ;0=71,1=1
P 4.1148425 3.135063 75 P 0 0 ;0=71,1=1
P 4.1203866 3.5941508 75 P 0 0 ;0=71,1=1
P 4.1318425 1.686063 75 P 0 0 ;0=71,1=1
P 4.1348425 1.651063 75 P 0 0 ;0=71,1=1
P 4.1348425 1.751063 75 P 0 0 ;0=71,1=1
P 4.1513063 1.6236232 75 P 0 0 ;0=71,1=1
P 4.1528425 3.135063 75 P 0 0 ;0=71,1=1
P 4.1798425 1.601063 75 P 0 0 ;0=71,1=1
P 4.1948425 3.884063 75 P 0 0 ;0=71,1=1
P 4.2088425 3.135063 75 P 0 0 ;0=71,1=1
P 4.2348425 2.725063 75 P 0 0 ;0=71,1=1
P 4.2548425 3.776063 75 P 0 0 ;0=71,1=1
P 4.2728425 3.135063 75 P 0 0 ;0=71,1=1
P 4.3338425 3.135063 75 P 0 0 ;0=71,1=1
P 4.3398425 2.725063 75 P 0 0 ;0=71,1=1
P 4.3878425 4.206063 75 P 0 0 ;0=71,1=1
P 4.4318425 3.135063 75 P 0 0 ;0=71,1=1
P 4.4778425 3.135063 75 P 0 0 ;0=71,1=1
P 4.5036614 2.7898819 75 P 0 0 ;0=71,1=1
P 4.7547119 4.1159324 75 P 0 0 ;0=71,1=1
P 4.7942913 2.8080709 75 P 0 0 ;0=71,1=1
P 4.9108425 4.203063 75 P 0 0 ;0=71,1=1
P 5.2670079 4.0888976 75 P 0 0 ;0=71,1=1
P 5.2748425 3.511063 75 P 0 0 ;0=71,1=1
P 5.5778425 2.214063 75 P 0 0 ;0=71,1=1
P 5.6348425 2.236063 75 P 0 0 ;0=71,1=1
P 5.6768425 3.546063 75 P 0 0 ;0=71,1=1
P 5.7338425 3.556063 75 P 0 0 ;0=71,1=1
P 5.9948425 3.552063 75 P 0 0 ;0=71,1=1
P 6.0048425 2.434063 75 P 0 0 ;0=71,1=1
P 6.0488425 2.171063 75 P 0 0 ;0=71,1=1
P 6.253937 2.9094488 75 P 0 0 ;0=71,1=1
P 6.2748425 2.391063 75 P 0 0 ;0=71,1=1
P 6.2824161 3.226063 75 P 0 0 ;0=71,1=1
P 6.2848425 2.501063 75 P 0 0 ;0=71,1=1
P 6.2948425 3.701063 75 P 0 0 ;0=71,1=1
P 6.3048425 3.121063 75 P 0 0 ;0=71,1=1
P 6.3094161 3.199063 75 P 0 0 ;0=71,1=1
P 6.3348425 3.266063 75 P 0 0 ;0=71,1=1
P 6.3398425 3.151063 75 P 0 0 ;0=71,1=1
P 6.3547483 3.3311384 75 P 0 0 ;0=71,1=1
P 6.3720472 2.9094488 75 P 0 0 ;0=71,1=1
P 6.3958425 2.111063 75 P 0 0 ;0=71,1=1
P 6.3968425 2.556063 75 P 0 0 ;0=71,1=1
P 6.3978425 2.501063 75 P 0 0 ;0=71,1=1
P 6.3978425 2.610063 75 P 0 0 ;0=71,1=1
P 6.3988425 2.453063 75 P 0 0 ;0=71,1=1
P 6.3988425 2.657063 75 P 0 0 ;0=71,1=1
P 6.4098425 3.371063 75 P 0 0 ;0=71,1=1
P 6.4248425 2.181063 75 P 0 0 ;0=71,1=1
P 6.4398425 3.191063 75 P 0 0 ;0=71,1=1
P 6.4448425 3.291063 75 P 0 0 ;0=71,1=1
P 6.4475772 3.396063 75 P 0 0 ;0=71,1=1
P 6.4568425 3.009063 75 P 0 0 ;0=71,1=1
P 6.4768425 3.231063 75 P 0 0 ;0=71,1=1
P 6.4798425 3.426063 75 P 0 0 ;0=71,1=1
P 6.5098425 3.456063 75 P 0 0 ;0=71,1=1
P 6.5488425 1.531063 75 P 0 0 ;0=71,1=1
P 6.6018425 1.777063 75 P 0 0 ;0=71,1=1
P 6.6028425 1.612063 75 P 0 0 ;0=71,1=1
P 6.6028425 1.672063 75 P 0 0 ;0=71,1=1
P 6.6028425 1.722063 75 P 0 0 ;0=71,1=1
P 6.6078425 2.176063 75 P 0 0 ;0=71,1=1
P 6.6268425 3.032063 75 P 0 0 ;0=71,1=1
P 6.6288425 1.372063 75 P 0 0 ;0=71,1=1
P 6.6476378 3.1299213 75 P 0 0 ;0=71,1=1
P 6.6488425 3.341063 75 P 0 0 ;0=71,1=1
P 6.6858425 1.828063 75 P 0 0 ;0=71,1=1
P 6.6998425 1.881063 75 P 0 0 ;0=71,1=1
P 6.8448425 1.661063 75 P 0 0 ;0=71,1=1
P 6.9498425 2.095063 75 P 0 0 ;0=71,1=1
P 6.9744094 1.9399606 75 P 0 0 ;0=71,1=1

### steps/pcb/layers/comp_+_bot/components
#
#Component attribute names
#
@0 .comp_mount_type
@1 .comp_height

# CMP 0
CMP 22 2.6628937 3.9668583 90 N U14 RCB-F9T ;0=1,1=0.0000
PRP CATEGORY 'MOD'
PRP DATE ''
PRP DESC 'MOD BLE 4.2'
PRP MAXTEMP '80C'
PRP MFG_Name 'UBLOCKS'
PRP MFG_PART_NUM 'RCB-F9T'
PRP MINTEMP '-40C'
PRP MODIFY_DATE '9/11/13'
PRP OTHER ''
PRP P1 'GPS'
PRP P2 ''
PRP P3 ''
PRP SHEETPART ''
PRP SIZE ''
PRP SUB ''
PRP Supplier_1 'Digi-Key'
PRP Supplier_Part_Number_1 '672-RCB-F9T-ND'
PRP VELENTIUM_PART_NUM '<V PART NUM>'
TOP 0 2.4223425 3.0822126 90 N 0 27 U14-0
TOP 1 2.4223425 3.2396929 90 N 0 28 U14-0
TOP 2 2.5098425 3.0428426 90 N 145 2 U14-1
TOP 3 2.3348425 3.0428426 90 N 137 2 U14-2
TOP 4 2.5098425 3.1215827 90 N 96 0 U14-3
TOP 5 2.3348425 3.1215827 90 N 100 0 U14-4
TOP 6 2.5098425 3.2003229 90 N 99 0 U14-5
TOP 7 2.3348425 3.2003229 90 N 98 0 U14-6
TOP 8 2.5098425 3.279063 90 N 97 0 U14-7
TOP 9 2.3348425 3.279063 90 N 135 2 U14-8
#
# CMP 1
CMP 7 2.3628425 2.944063 180 N C87 CAP_0805_10UF_25V ;0=1,1=0.0551
PRP CATEGORY 'CAP, CER'
PRP DATE '4/11/2006 3:37:28 PM'
PRP DESC 'CAP, CER, 10.UF, 10V, 10%, X5R, 0805'
PRP MAXTEMP '85C'
PRP MFG_Name 'TAIYO YUDEN'
PRP MFG_PART_NUM 'TMK212BBJ106KG-T'
PRP MINTEMP '-55C'
PRP MODIFY_DATE '10/23/2013'
PRP OTHER ''
PRP P1 '10%'
PRP P2 '25V'
PRP P3 'X5R'
PRP SHEETPART ''
PRP SIZE '0805'
PRP SUB ''
PRP Supplier_1 'MOUSER'
PRP Supplier_Part_Number_1 '963-TMK212BBJ106KG-T'
PRP VALENTIUM_PART_NUM '<VALENTIUM>'
PRP VALUE '10uF'
TOP 0 2.3274094 2.944063 90 N 137 4 C87-1
TOP 1 2.3982756 2.944063 90 N 135 6 C87-2
#
# CMP 2
CMP 5 2.3688425 2.854063 180 N C88 CAP_0402_0.1UF_50V ;0=1,1=0.0236
PRP CATEGORY 'CAP, CER'
PRP DATE ''
PRP DESC 'CAP, CER, 0.1UF, 50V, 10%, X7R, AEC-Q200, 0402'
PRP MAXTEMP '125C'
PRP MFG_Name 'TDK'
PRP MFG_PART_NUM 'CGA2B3X7R1H104K050BB'
PRP MINTEMP '-55C'
PRP MODIFY_DATE '10/23/2013'
PRP OTHER 'AEC-Q200'
PRP P1 '10%'
PRP P2 '50V'
PRP P3 'X7R'
PRP SHEETPART ''
PRP SIZE '0402'
PRP SUB ''
PRP Supplier_1 'Digi-Key'
PRP Supplier_Part_Number_1 '445-6899-1-ND'
PRP VALENTIUM_PART_NUM '<VALENTIUM>'
PRP VALUE '0.1UF'
TOP 0 2.3519134 2.854063 90 N 137 3 C88-1
TOP 1 2.3857717 2.854063 90 N 135 3 C88-2
#
# CMP 3
CMP 7 2.6328425 3.007063 90 N C89 CAP_0805_10UF_25V ;0=1,1=0.0551
PRP CATEGORY 'CAP, CER'
PRP DATE '4/11/2006 3:37:28 PM'
PRP DESC 'CAP, CER, 10.UF, 10V, 10%, X5R, 0805'
PRP MAXTEMP '85C'
PRP MFG_Name 'TAIYO YUDEN'
PRP MFG_PART_NUM 'TMK212BBJ106KG-T'
PRP MINTEMP '-55C'
PRP MODIFY_DATE '10/23/2013'
PRP OTHER ''
PRP P1 '10%'
PRP P2 '25V'
PRP P3 'X5R'
PRP SHEETPART ''
PRP SIZE '0805'
PRP SUB ''
PRP Supplier_1 'MOUSER'
PRP Supplier_Part_Number_1 '963-TMK212BBJ106KG-T'
PRP VALENTIUM_PART_NUM '<VALENTIUM>'
PRP VALUE '10uF'
TOP 0 2.6328425 3.0424961 180 N 145 3 C89-1
TOP 1 2.6328425 2.9716299 180 N 135 4 C89-2
#
# CMP 4
CMP 5 2.7118425 3.020063 90 N C90 CAP_0402_0.1UF_50V ;0=1,1=0.0236
PRP CATEGORY 'CAP, CER'
PRP DATE ''
PRP DESC 'CAP, CER, 0.1UF, 50V, 10%, X7R, AEC-Q200, 0402'
PRP MAXTEMP '125C'
PRP MFG_Name 'TDK'
PRP MFG_PART_NUM 'CGA2B3X7R1H104K050BB'
PRP MINTEMP '-55C'
PRP MODIFY_DATE '10/23/2013'
PRP OTHER 'AEC-Q200'
PRP P1 '10%'
PRP P2 '50V'
PRP P3 'X7R'
PRP SHEETPART ''
PRP SIZE '0402'
PRP SUB ''
PRP Supplier_1 'Digi-Key'
PRP Supplier_Part_Number_1 '445-6899-1-ND'
PRP VALENTIUM_PART_NUM '<VALENTIUM>'
PRP VALUE '0.1UF'
TOP 0 2.7118425 3.0369921 180 N 145 4 C90-1
TOP 1 2.7118425 3.0031338 180 N 135 5 C90-2
#
# CMP 5
CMP 5 3.0198425 0.346063 270 N C53 CAP_0402_0.1UF_50V ;0=1,1=0.0236
PRP CATEGORY 'CAP, CER'
PRP DATE ''
PRP DESC 'CAP, CER, 0.1UF, 50V, 10%, X7R, AEC-Q200, 0402'
PRP MAXTEMP '125C'
PRP MFG_Name 'TDK'
PRP MFG_PART_NUM 'CGA2B3X7R1H104K050BB'
PRP MINTEMP '-55C'
PRP MODIFY_DATE '10/23/2013'
PRP OTHER 'AEC-Q200'
PRP P1 '10%'
PRP P2 '50V'
PRP P3 'X7R'
PRP SHEETPART ''
PRP SIZE '0402'
PRP SUB ''
PRP Supplier_1 'Digi-Key'
PRP Supplier_Part_Number_1 '445-6899-1-ND'
PRP VALENTIUM_PART_NUM '<VALENTIUM>'
PRP VALUE '0.1UF'
TOP 0 3.0198425 0.3291339 0 N 12 0 C53-1
TOP 1 3.0198425 0.3629922 0 N 114 0 C53-2
#
# CMP 6
CMP 5 2.9798425 0.346063 270 N C52 CAP_0402_0.1UF_50V ;0=1,1=0.0236
PRP CATEGORY 'CAP, CER'
PRP DATE ''
PRP DESC 'CAP, CER, 0.1UF, 50V, 10%, X7R, AEC-Q200, 0402'
PRP MAXTEMP '125C'
PRP MFG_Name 'TDK'
PRP MFG_PART_NUM 'CGA2B3X7R1H104K050BB'
PRP MINTEMP '-55C'
PRP MODIFY_DATE '10/23/2013'
PRP OTHER 'AEC-Q200'
PRP P1 '10%'
PRP P2 '50V'
PRP P3 'X7R'
PRP SHEETPART ''
PRP SIZE '0402'
PRP SUB ''
PRP Supplier_1 'Digi-Key'
PRP Supplier_Part_Number_1 '445-6899-1-ND'
PRP VALENTIUM_PART_NUM '<VALENTIUM>'
PRP VALUE '0.1UF'
TOP 0 2.9798425 0.3291339 0 N 11 0 C52-1
TOP 1 2.9798425 0.3629922 0 N 115 0 C52-2
#
# CMP 7
CMP 5 2.8548425 0.346063 270 N C51 CAP_0402_0.1UF_50V ;0=1,1=0.0236
PRP CATEGORY 'CAP, CER'
PRP DATE ''
PRP DESC 'CAP, CER, 0.1UF, 50V, 10%, X7R, AEC-Q200, 0402'
PRP MAXTEMP '125C'
PRP MFG_Name 'TDK'
PRP MFG_PART_NUM 'CGA2B3X7R1H104K050BB'
PRP MINTEMP '-55C'
PRP MODIFY_DATE '10/23/2013'
PRP OTHER 'AEC-Q200'
PRP P1 '10%'
PRP P2 '50V'
PRP P3 'X7R'
PRP SHEETPART ''
PRP SIZE '0402'
PRP SUB ''
PRP Supplier_1 'Digi-Key'
PRP Supplier_Part_Number_1 '445-6899-1-ND'
PRP VALENTIUM_PART_NUM '<VALENTIUM>'
PRP VALUE '0.1UF'
TOP 0 2.8548425 0.3291339 0 N 10 0 C51-1
TOP 1 2.8548425 0.3629922 0 N 116 1 C51-2
#
# CMP 8
CMP 5 2.8198425 0.346063 270 N C50 CAP_0402_0.1UF_50V ;0=1,1=0.0236
PRP CATEGORY 'CAP, CER'
PRP DATE ''
PRP DESC 'CAP, CER, 0.1UF, 50V, 10%, X7R, AEC-Q200, 0402'
PRP MAXTEMP '125C'
PRP MFG_Name 'TDK'
PRP MFG_PART_NUM 'CGA2B3X7R1H104K050BB'
PRP MINTEMP '-55C'
PRP MODIFY_DATE '10/23/2013'
PRP OTHER 'AEC-Q200'
PRP P1 '10%'
PRP P2 '50V'
PRP P3 'X7R'
PRP SHEETPART ''
PRP SIZE '0402'
PRP SUB ''
PRP Supplier_1 'Digi-Key'
PRP Supplier_Part_Number_1 '445-6899-1-ND'
PRP VALENTIUM_PART_NUM '<VALENTIUM>'
PRP VALUE '0.1UF'
TOP 0 2.8198425 0.3291339 0 N 9 0 C50-1
TOP 1 2.8198425 0.3629922 0 N 117 1 C50-2
#
# CMP 9
CMP 5 2.7048425 0.346063 270 N C49 CAP_0402_0.1UF_50V ;0=1,1=0.0236
PRP CATEGORY 'CAP, CER'
PRP DATE ''
PRP DESC 'CAP, CER, 0.1UF, 50V, 10%, X7R, AEC-Q200, 0402'
PRP MAXTEMP '125C'
PRP MFG_Name 'TDK'
PRP MFG_PART_NUM 'CGA2B3X7R1H104K050BB'
PRP MINTEMP '-55C'
PRP MODIFY_DATE '10/23/2013'
PRP OTHER 'AEC-Q200'
PRP P1 '10%'
PRP P2 '50V'
PRP P3 'X7R'
PRP SHEETPART ''
PRP SIZE '0402'
PRP SUB ''
PRP Supplier_1 'Digi-Key'
PRP Supplier_Part_Number_1 '445-6899-1-ND'
PRP VALENTIUM_PART_NUM '<VALENTIUM>'
PRP VALUE '0.1UF'
TOP 0 2.7048425 0.3291339 0 N 56 0 C49-1
TOP 1 2.7048425 0.3629922 0 N 118 1 C49-2
#
# CMP 10
CMP 5 2.6648425 0.346063 270 N C48 CAP_0402_0.1UF_50V ;0=1,1=0.0236
PRP CATEGORY 'CAP, CER'
PRP DATE ''
PRP DESC 'CAP, CER, 0.1UF, 50V, 10%, X7R, AEC-Q200, 0402'
PRP MAXTEMP '125C'
PRP MFG_Name 'TDK'
PRP MFG_PART_NUM 'CGA2B3X7R1H104K050BB'
PRP MINTEMP '-55C'
PRP MODIFY_DATE '10/23/2013'
PRP OTHER 'AEC-Q200'
PRP P1 '10%'
PRP P2 '50V'
PRP P3 'X7R'
PRP SHEETPART ''
PRP SIZE '0402'
PRP SUB ''
PRP Supplier_1 'Digi-Key'
PRP Supplier_Part_Number_1 '445-6899-1-ND'
PRP VALENTIUM_PART_NUM '<VALENTIUM>'
PRP VALUE '0.1UF'
TOP 0 2.6648425 0.3291339 0 N 8 0 C48-1
TOP 1 2.6648425 0.3629922 0 N 119 1 C48-2
#
# CMP 11
CMP 5 2.5118425 0.346063 270 N C47 CAP_0402_0.1UF_50V ;0=1,1=0.0236
PRP CATEGORY 'CAP, CER'
PRP DATE ''
PRP DESC 'CAP, CER, 0.1UF, 50V, 10%, X7R, AEC-Q200, 0402'
PRP MAXTEMP '125C'
PRP MFG_Name 'TDK'
PRP MFG_PART_NUM 'CGA2B3X7R1H104K050BB'
PRP MINTEMP '-55C'
PRP MODIFY_DATE '10/23/2013'
PRP OTHER 'AEC-Q200'
PRP P1 '10%'
PRP P2 '50V'
PRP P3 'X7R'
PRP SHEETPART ''
PRP SIZE '0402'
PRP SUB ''
PRP Supplier_1 'Digi-Key'
PRP Supplier_Part_Number_1 '445-6899-1-ND'
PRP VALENTIUM_PART_NUM '<VALENTIUM>'
PRP VALUE '0.1UF'
TOP 0 2.5118425 0.3291339 0 N 7 0 C47-1
TOP 1 2.5118425 0.3629922 0 N 120 1 C47-2
#
# CMP 12
CMP 5 2.4688425 0.346063 270 N C46 CAP_0402_0.1UF_50V ;0=1,1=0.0236
PRP CATEGORY 'CAP, CER'
PRP DATE ''
PRP DESC 'CAP, CER, 0.1UF, 50V, 10%, X7R, AEC-Q200, 0402'
PRP MAXTEMP '125C'
PRP MFG_Name 'TDK'
PRP MFG_PART_NUM 'CGA2B3X7R1H104K050BB'
PRP MINTEMP '-55C'
PRP MODIFY_DATE '10/23/2013'
PRP OTHER 'AEC-Q200'
PRP P1 '10%'
PRP P2 '50V'
PRP P3 'X7R'
PRP SHEETPART ''
PRP SIZE '0402'
PRP SUB ''
PRP Supplier_1 'Digi-Key'
PRP Supplier_Part_Number_1 '445-6899-1-ND'
PRP VALENTIUM_PART_NUM '<VALENTIUM>'
PRP VALUE '0.1UF'
TOP 0 2.4688425 0.3291339 0 N 6 0 C46-1
TOP 1 2.4688425 0.3629922 0 N 121 1 C46-2
#
# CMP 13
CMP 5 2.3898425 0.346063 270 N C45 CAP_0402_0.1UF_50V ;0=1,1=0.0236
PRP CATEGORY 'CAP, CER'
PRP DATE ''
PRP DESC 'CAP, CER, 0.1UF, 50V, 10%, X7R, AEC-Q200, 0402'
PRP MAXTEMP '125C'
PRP MFG_Name 'TDK'
PRP MFG_PART_NUM 'CGA2B3X7R1H104K050BB'
PRP MINTEMP '-55C'
PRP MODIFY_DATE '10/23/2013'
PRP OTHER 'AEC-Q200'
PRP P1 '10%'
PRP P2 '50V'
PRP P3 'X7R'
PRP SHEETPART ''
PRP SIZE '0402'
PRP SUB ''
PRP Supplier_1 'Digi-Key'
PRP Supplier_Part_Number_1 '445-6899-1-ND'
PRP VALENTIUM_PART_NUM '<VALENTIUM>'
PRP VALUE '0.1UF'
TOP 0 2.3898425 0.3291339 0 N 5 0 C45-1
TOP 1 2.3898425 0.3629922 0 N 123 1 C45-2
#
# CMP 14
CMP 5 2.3498425 0.346063 270 N C44 CAP_0402_0.1UF_50V ;0=1,1=0.0236
PRP CATEGORY 'CAP, CER'
PRP DATE ''
PRP DESC 'CAP, CER, 0.1UF, 50V, 10%, X7R, AEC-Q200, 0402'
PRP MAXTEMP '125C'
PRP MFG_Name 'TDK'
PRP MFG_PART_NUM 'CGA2B3X7R1H104K050BB'
PRP MINTEMP '-55C'
PRP MODIFY_DATE '10/23/2013'
PRP OTHER 'AEC-Q200'
PRP P1 '10%'
PRP P2 '50V'
PRP P3 'X7R'
PRP SHEETPART ''
PRP SIZE '0402'
PRP SUB ''
PRP Supplier_1 'Digi-Key'
PRP Supplier_Part_Number_1 '445-6899-1-ND'
PRP VALENTIUM_PART_NUM '<VALENTIUM>'
PRP VALUE '0.1UF'
TOP 0 2.3498425 0.3291339 0 N 4 0 C44-1
TOP 1 2.3498425 0.3629922 0 N 122 1 C44-2
#

### steps/pcb/layers/comp_+_top/components
#
#Component attribute names
#
@0 .comp_mount_type
@1 .comp_height

# CMP 0
CMP 4 3.2391732 2.8149606 0 N IC? BMP388 ;0=1,1=0.0000
PRP Arrow_Part_Number 'BMP388'
PRP Arrow_Price/Stock 'https://www.arrow.com/en/products/bmp388/bosch'
PRP Datasheet_Link 'https://ae-bst.resource.bosch.com/media/_tech/media/datasheets/BST-BMP388-DS001-01.pdf'
PRP Height '0mm'
PRP Manufacturer_Name 'Bosch Sensortec'
PRP Manufacturer_Part_Number 'BMP388'
PRP Mouser_Part_Number '262-BMP388'
PRP Mouser_Price/Stock 'https://www.mouser.co.uk/ProductDetail/Bosch-Sensortec/BMP388?qs=rrS6PyfT74eIcD5Rv1Kf7A%3D%3D'
TOP 0 3.2490157 2.845 270 N 108 23 IC?-1
TOP 1 3.2293307 2.845 270 N 39 4 IC?-2
TOP 2 3.2091732 2.8346456 0 N 135 190 IC?-3
TOP 3 3.2091732 2.8149606 0 N 38 4 IC?-4
TOP 4 3.2091732 2.7952756 0 N 0 94 IC?-5
TOP 5 3.2293307 2.7849212 270 N 108 22 IC?-6
TOP 6 3.2490157 2.7849212 270 N 0 93 IC?-7
TOP 7 3.2691732 2.7952756 0 N 135 189 IC?-8
TOP 8 3.2691732 2.8149606 0 N 135 188 IC?-9
TOP 9 3.2691732 2.8346456 0 N 108 21 IC?-10
#
# CMP 1
CMP 15 0.9311023 0.7185039 180 N R36 MAC10M ;0=1,1=0.0354
PRP LatestRevisionDate '29-May-2009'
PRP LatestRevisionNote 'IPC-7351 Footprint Added.'
PRP PackageDescription 'Chip Resistor'
PRP PackageReference 'J1-0603'
PRP Published '8-Jun-2000'
PRP Publisher 'Altium Limited'
PRP VALUE '0 Ohm'
TOP 0 0.9606298 0.7185038 90 N 2 3 R36-1
TOP 1 0.9015747 0.7185038 90 N 104 4 R36-2
#
# CMP 2
CMP 1 2.0433071 4.257874 90 N JP2 JUMPER_3PIN ;0=2,1=0.0000
PRP CATEGORY 'CONN, HDR'
PRP DATE ''
PRP DESC 'CONN, HDR, 1X3, VERT, .1, JUMPER, TH'
PRP MAXTEMP 'C'
PRP MFG_Name 'SAMTEC'
PRP MFG_PART_NUM 'TSW-103-08-G-S'
PRP MINTEMP 'C'
PRP MODIFY_DATE '10/10/2013'
PRP OTHER 'TSW-1XX'
PRP P1 'VERT'
PRP P2 '.1'
PRP P3 'FEATURE'
PRP SHEETPART ''
PRP SIZE 'TH'
PRP SUB ''
PRP Supplier_1 'Digi-Key'
PRP Supplier_Part_Number_1 'SAM1038-02-ND'
PRP VALENTIUM_PART_NUM '<VALENTIUM>'
PRP VALUE '1X3'
TOP 0 2.0433071 4.257874 90 N 3 0 JP2-1
TOP 1 2.0433071 4.157874 90 N 33 0 JP2-2
TOP 2 2.0433071 4.057874 90 N 93 0 JP2-3
#
# CMP 3
CMP 1 1.4576771 4.253937 90 N JP1 JUMPER_3PIN ;0=2,1=0.0000
PRP CATEGORY 'CONN, HDR'
PRP DATE ''
PRP DESC 'CONN, HDR, 1X3, VERT, .1, JUMPER, TH'
PRP MAXTEMP 'C'
PRP MFG_Name 'SAMTEC'
PRP MFG_PART_NUM 'TSW-103-08-G-S'
PRP MINTEMP 'C'
PRP MODIFY_DATE '10/10/2013'
PRP OTHER 'TSW-1XX'
PRP P1 'VERT'
PRP P2 '.1'
PRP P3 'FEATURE'
PRP SHEETPART ''
PRP SIZE 'TH'
PRP SUB ''
PRP Supplier_1 'Digi-Key'
PRP Supplier_Part_Number_1 'SAM1038-02-ND'
PRP VALENTIUM_PART_NUM '<VALENTIUM>'
PRP VALUE '1X3'
TOP 0 1.4576771 4.253937 90 N 1 0 JP1-1
TOP 1 1.4576771 4.153937 90 N 34 0 JP1-2
TOP 2 1.4576771 4.053937 90 N 91 0 JP1-3
#
# CMP 4
CMP 15 0.9340551 1.2244095 180 N R16 MAC10M ;0=1,1=0.0354
PRP LatestRevisionDate '29-May-2009'
PRP LatestRevisionNote 'IPC-7351 Footprint Added.'
PRP PackageDescription 'Chip Resistor'
PRP PackageReference 'J1-0603'
PRP Published '8-Jun-2000'
PRP Publisher 'Altium Limited'
PRP VALUE '0 Ohm'
TOP 0 0.9635826 1.2244094 90 N 41 6 R16-1
TOP 1 0.9045275 1.2244094 90 N 105 4 R16-2
#
# CMP 5
CMP 15 0.9301181 1.7470473 180 N R15 MACPPSO ;0=1,1=0.0354
PRP LatestRevisionDate '29-May-2009'
PRP LatestRevisionNote 'IPC-7351 Footprint Added.'
PRP PackageDescription 'Chip Resistor'
PRP PackageReference 'J1-0603'
PRP Published '8-Jun-2000'
PRP Publisher 'Altium Limited'
PRP VALUE '0 Ohm'
TOP 0 0.9596456 1.7470472 90 N 75 3 R15-1
TOP 1 0.9005905 1.7470472 90 N 106 4 R15-2
#
# CMP 6
CMP 15 0.9379921 2.2844488 180 N R14 MACPPSI ;0=1,1=0.0354
PRP LatestRevisionDate '29-May-2009'
PRP LatestRevisionNote 'IPC-7351 Footprint Added.'
PRP PackageDescription 'Chip Resistor'
PRP PackageReference 'J1-0603'
PRP Published '8-Jun-2000'
PRP Publisher 'Altium Limited'
PRP VALUE '0 Ohm'
TOP 0 0.9675196 2.2844487 90 N 79 4 R14-1
TOP 1 0.9084645 2.2844487 90 N 107 4 R14-2
#
# CMP 7
CMP 15 2.3877953 2.9291339 90 N R17 MACPPS ;0=1,1=0.0354
PRP LatestRevisionDate '29-May-2009'
PRP LatestRevisionNote 'IPC-7351 Footprint Added.'
PRP PackageDescription 'Chip Resistor'
PRP PackageReference 'J1-0603'
PRP Published '8-Jun-2000'
PRP Publisher 'Altium Limited'
PRP VALUE '0 Ohm'
TOP 0 2.3877954 2.9586614 0 N 2 1 R17-1
TOP 1 2.3877954 2.8996063 0 N 79 3 R17-2
#
# CMP 8
CMP 15 2.2125983 4.0452757 90 N R13 MACRX ;0=1,1=0.0354
PRP LatestRevisionDate '29-May-2009'
PRP LatestRevisionNote 'IPC-7351 Footprint Added.'
PRP PackageDescription 'Chip Resistor'
PRP PackageReference 'J1-0603'
PRP Published '8-Jun-2000'
PRP Publisher 'Altium Limited'
PRP VALUE '0 Ohm'
TOP 0 2.2125984 4.0748032 0 N 73 3 R13-1
TOP 1 2.2125984 4.0157481 0 N 93 1 R13-2
#
# CMP 9
CMP 15 2.1515747 4.0452757 90 N R12 GPS2RX ;0=1,1=0.0354
PRP LatestRevisionDate '29-May-2009'
PRP LatestRevisionNote 'IPC-7351 Footprint Added.'
PRP PackageDescription 'Chip Resistor'
PRP PackageReference 'J1-0603'
PRP Published '8-Jun-2000'
PRP Publisher 'Altium Limited'
PRP VALUE '0 Ohm'
TOP 0 2.1515748 4.0748032 0 N 99 1 R12-1
TOP 1 2.1515748 4.0157481 0 N 93 2 R12-2
#
# CMP 10
CMP 15 1.3464568 4.007874 270 N R11 MACTX ;0=1,1=0.0354
PRP LatestRevisionDate '29-May-2009'
PRP LatestRevisionNote 'IPC-7351 Footprint Added.'
PRP PackageDescription 'Chip Resistor'
PRP PackageReference 'J1-0603'
PRP Published '8-Jun-2000'
PRP Publisher 'Altium Limited'
PRP VALUE '0 Ohm'
TOP 0 1.3464567 3.9783465 180 N 72 3 R11-1
TOP 1 1.3464567 4.0374016 180 N 91 1 R11-2
#
# CMP 11
CMP 15 1.3464566 4.1122048 90 N R10 GPS2TX ;0=1,1=0.0354
PRP LatestRevisionDate '29-May-2009'
PRP LatestRevisionNote 'IPC-7351 Footprint Added.'
PRP PackageDescription 'Chip Resistor'
PRP PackageReference 'J1-0603'
PRP Published '8-Jun-2000'
PRP Publisher 'Altium Limited'
PRP VALUE '0 Ohm'
TOP 0 1.3464567 4.1417323 0 N 96 2 R10-1
TOP 1 1.3464567 4.0826772 0 N 91 2 R10-2
#
# CMP 12
CMP 37 2.9340551 3.1122047 0 N U3 DS3231SN ;0=1,1=0.1043
PRP Code_IPC 'SOIC127P1030-16'
PRP Code_JEDEC 'MS-013-AA'
PRP ComponentLink1Description 'Manufacturer URL'
PRP ComponentLink1URL 'http://www.maxim-ic.com'
PRP ComponentLink2Description 'Datasheet'
PRP ComponentLink2URL 'http://datasheets.maxim-ic.com/en/ds/DS3231.pdf'
PRP ComponentLink3Description 'Package Specification'
PRP ComponentLink3URL 'http://pdfserv.maxim-ic.com/package_dwgs/21-0042.PDF'
PRP DatasheetVersion 'Rev 8, Jul-2010'
PRP PackageDescription '16-Pin Small-Outline IC, Wide (0.3in), 1.27 mm Pitch, SOIC (W)'
PRP PackageReference 'W16-H2'
PRP PackageVersion 'revD, 2010'
TOP 0 2.7568898 3.2872047 270 N 0 76 U3-1
TOP 1 2.7568898 3.2372047 270 N 108 20 U3-2
TOP 2 2.7568898 3.1872047 270 N 94 1 U3-3
TOP 3 2.7568898 3.1372047 270 N 0 77 U3-4
TOP 4 2.7568898 3.0872047 270 N 0 78 U3-5
TOP 5 2.7568898 3.0372047 270 N 0 79 U3-6
TOP 6 2.7568898 2.9872047 270 N 0 80 U3-7
TOP 7 2.7568898 2.9372047 270 N 0 81 U3-8
TOP 8 3.1112205 2.9372047 270 N 0 85 U3-9
TOP 9 3.1112205 2.9872047 270 N 0 84 U3-10
TOP 10 3.1112205 3.0372047 270 N 0 83 U3-11
TOP 11 3.1112205 3.0872047 270 N 0 82 U3-12
TOP 12 3.1112205 3.1372047 270 N 135 181 U3-13
TOP 13 3.1112205 3.1872047 270 N 80 0 U3-14
TOP 14 3.1112205 3.2372047 270 N 38 3 U3-15
TOP 15 3.1112205 3.2872047 270 N 39 3 U3-16
#
# CMP 13
CMP 19 4.8277559 1.6574803 270 N U10AL SA.45s ;0=2,1=0.4500
PRP Datasheet_URL 'https://media.digikey.com/pdf/Data%20Sheets/Microsemi%20PDFs/090-02984-001.pdf'
PRP Datasheet_Version '03/2017'
PRP Manufacturer 'Microsemi'
PRP Manufacturer_URL 'http://www.microsemi.com/'
PRP Mounting_Technology 'ThroughHole'
PRP Package_Description '9-Pin Through Hole Device, Body 40.64 x 35.306 mm'
PRP Package_Reference '090-02984-00X'
TOP 0 4.3277559 1.0074803 270 N 0 12 U10AL-1
TOP 1 4.9277559 1.0074803 270 N 81 0 U10AL-4
TOP 2 5.1277559 1.0074803 270 N 72 0 U10AL-5
TOP 3 5.3277559 1.0074803 270 N 73 0 U10AL-6
TOP 4 5.3277559 2.3074803 270 N 108 1 U10AL-7
TOP 5 5.1277559 2.3074803 270 N 135 38 U10AL-8
TOP 6 4.9277559 2.3074803 270 N 79 0 U10AL-9
TOP 7 4.7277559 2.3074803 270 N 75 0 U10AL-10
TOP 8 4.3277559 2.3074803 270 N 41 0 U10AL-12
#
# CMP 14
CMP 11 4.9094488 3.3848425 270 N BT1 BU2032SM-BT-GTR ;0=1,1=0.0000
PRP Case/Package 'SMD/SMT'
PRP Max_Operating_Temperature '280°C'
PRP Min_Operating_Temperature '-40°C'
PRP Mount 'Surface Mount'
PRP Number_of_Cells '1'
PRP Package_Quantity '400'
PRP Termination 'SMD/SMT'
TOP 0 4.9094488 3.9616142 270 N 135 182 BT1-1
TOP 1 4.9094488 2.8080708 270 N 80 1 BT1-2
#
# CMP 15
CMP 7 4.3398425 2.816063 270 N C72 CAP_0805_22UF_16V ;0=1,1=0.0551
PRP CATEGORY 'CAP, CER'
PRP DATE '4/11/2006 3:37:28 PM'
PRP DESC 'CAP, CER, 22.UF, 16V, 20%, X5R, 0805'
PRP MAXTEMP '85C'
PRP MFG_Name 'MURATA'
PRP MFG_PART_NUM 'GRM219R61C226ME15L'
PRP MINTEMP '-55C'
PRP MODIFY_DATE '10/23/2013'
PRP OTHER ''
PRP P1 '20%'
PRP P2 '16V'
PRP P3 'X5R'
PRP SHEETPART ''
PRP SIZE '0805'
PRP SUB ''
PRP Supplier_1 'Digi-Key'
PRP Supplier_Part_Number_1 '490-9952-1-ND'
PRP VALENTIUM_PART_NUM '<VALENTIUM>'
PRP VALUE '22uF'
TOP 0 4.3398425 2.7806299 180 N 135 163 C72-1
TOP 1 4.3398425 2.8514961 180 N 13 2 C72-2
#
# CMP 16
CMP 7 4.2348425 2.816063 270 N C73 CAP_0805_22UF_16V ;0=1,1=0.0551
PRP CATEGORY 'CAP, CER'
PRP DATE '4/11/2006 3:37:28 PM'
PRP DESC 'CAP, CER, 22.UF, 16V, 20%, X5R, 0805'
PRP MAXTEMP '85C'
PRP MFG_Name 'MURATA'
PRP MFG_PART_NUM 'GRM219R61C226ME15L'
PRP MINTEMP '-55C'
PRP MODIFY_DATE '10/23/2013'
PRP OTHER ''
PRP P1 '20%'
PRP P2 '16V'
PRP P3 'X5R'
PRP SHEETPART ''
PRP SIZE '0805'
PRP SUB ''
PRP Supplier_1 'Digi-Key'
PRP Supplier_Part_Number_1 '490-9952-1-ND'
PRP VALENTIUM_PART_NUM '<VALENTIUM>'
PRP VALUE '22uF'
TOP 0 4.2348425 2.7806299 180 N 135 41 C73-1
TOP 1 4.2348425 2.8514961 180 N 13 0 C73-2
#
# CMP 17
CMP 7 3.9598425 2.816063 270 N C74 CAP_0805_22UF_16V ;0=1,1=0.0551
PRP CATEGORY 'CAP, CER'
PRP DATE '4/11/2006 3:37:28 PM'
PRP DESC 'CAP, CER, 22.UF, 16V, 20%, X5R, 0805'
PRP MAXTEMP '85C'
PRP MFG_Name 'MURATA'
PRP MFG_PART_NUM 'GRM219R61C226ME15L'
PRP MINTEMP '-55C'
PRP MODIFY_DATE '10/23/2013'
PRP OTHER ''
PRP P1 '20%'
PRP P2 '16V'
PRP P3 'X5R'
PRP SHEETPART ''
PRP SIZE '0805'
PRP SUB ''
PRP Supplier_1 'Digi-Key'
PRP Supplier_Part_Number_1 '490-9952-1-ND'
PRP VALENTIUM_PART_NUM '<VALENTIUM>'
PRP VALUE '22uF'
TOP 0 3.9598425 2.7806299 180 N 135 42 C74-1
TOP 1 3.9598425 2.8514961 180 N 108 2 C74-2
#
# CMP 18
CMP 7 4.0648425 2.816063 270 N C75 CAP_0805_22UF_16V ;0=1,1=0.0551
PRP CATEGORY 'CAP, CER'
PRP DATE '4/11/2006 3:37:28 PM'
PRP DESC 'CAP, CER, 22.UF, 16V, 20%, X5R, 0805'
PRP MAXTEMP '85C'
PRP MFG_Name 'MURATA'
PRP MFG_PART_NUM 'GRM219R61C226ME15L'
PRP MINTEMP '-55C'
PRP MODIFY_DATE '10/23/2013'
PRP OTHER ''
PRP P1 '20%'
PRP P2 '16V'
PRP P3 'X5R'
PRP SHEETPART ''
PRP SIZE '0805'
PRP SUB ''
PRP Supplier_1 'Digi-Key'
PRP Supplier_Part_Number_1 '490-9952-1-ND'
PRP VALENTIUM_PART_NUM '<VALENTIUM>'
PRP VALUE '22uF'
TOP 0 4.0648425 2.7806299 180 N 135 43 C75-1
TOP 1 4.0648425 2.8514961 180 N 108 3 C75-2
#
# CMP 19
CMP 6 4.0398425 3.061063 90 N C76 CAP_0603_0.01UF_50V ;0=1,1=0.0394
PRP CATEGORY 'CAP, CER'
PRP DATE '7/24/2013'
PRP DESC 'CAP, CER, 0.01UF, 50V, 10%, X7R, 0603'
PRP MAXTEMP '125C'
PRP MFG_Name 'KEMET'
PRP MFG_PART_NUM 'C0603C103K5RACTU'
PRP MINTEMP '-55C'
PRP MODIFY_DATE '10/23/2013'
PRP OTHER ''
PRP P1 '10%'
PRP P2 '50V'
PRP P3 'X7R'
PRP SHEETPART ''
PRP SIZE '0603'
PRP SUB ''
PRP Supplier_1 'Digi-Key'
PRP Supplier_Part_Number_1 '399-1091-1-ND'
PRP VALENTIUM_PART_NUM '<VALENTIUM>'
PRP VALUE '0.01uF'
TOP 0 4.0398425 3.0925591 0 N 135 162 C76-1
TOP 1 4.0398425 3.029567 0 N 108 15 C76-2
#
# CMP 20
CMP 5 4.1098425 3.061063 90 N C77 CAP_0402_0.1UF_50V ;0=1,1=0.0236
PRP CATEGORY 'CAP, CER'
PRP DATE ''
PRP DESC 'CAP, CER, 0.1UF, 50V, 10%, X7R, AEC-Q200, 0402'
PRP MAXTEMP '125C'
PRP MFG_Name 'TDK'
PRP MFG_PART_NUM 'CGA2B3X7R1H104K050BB'
PRP MINTEMP '-55C'
PRP MODIFY_DATE '10/23/2013'
PRP OTHER 'AEC-Q200'
PRP P1 '10%'
PRP P2 '50V'
PRP P3 'X7R'
PRP SHEETPART ''
PRP SIZE '0402'
PRP SUB ''
PRP Supplier_1 'Digi-Key'
PRP Supplier_Part_Number_1 '445-6899-1-ND'
PRP VALENTIUM_PART_NUM '<VALENTIUM>'
PRP VALUE '0.1UF'
TOP 0 4.1098425 3.0779921 0 N 135 161 C77-1
TOP 1 4.1098425 3.0441338 0 N 108 14 C77-2
#
# CMP 21
CMP 5 4.1648425 3.061063 90 N C78 CAP_0402_0.1UF_50V ;0=1,1=0.0236
PRP CATEGORY 'CAP, CER'
PRP DATE ''
PRP DESC 'CAP, CER, 0.1UF, 50V, 10%, X7R, AEC-Q200, 0402'
PRP MAXTEMP '125C'
PRP MFG_Name 'TDK'
PRP MFG_PART_NUM 'CGA2B3X7R1H104K050BB'
PRP MINTEMP '-55C'
PRP MODIFY_DATE '10/23/2013'
PRP OTHER 'AEC-Q200'
PRP P1 '10%'
PRP P2 '50V'
PRP P3 'X7R'
PRP SHEETPART ''
PRP SIZE '0402'
PRP SUB ''
PRP Supplier_1 'Digi-Key'
PRP Supplier_Part_Number_1 '445-6899-1-ND'
PRP VALENTIUM_PART_NUM '<VALENTIUM>'
PRP VALUE '0.1UF'
TOP 0 4.1648425 3.0779921 0 N 135 44 C78-1
TOP 1 4.1648425 3.0441338 0 N 108 4 C78-2
#
# CMP 22
CMP 5 4.2198425 3.061063 90 N C79 CAP_0402_0.1UF_50V ;0=1,1=0.0236
PRP CATEGORY 'CAP, CER'
PRP DATE ''
PRP DESC 'CAP, CER, 0.1UF, 50V, 10%, X7R, AEC-Q200, 0402'
PRP MAXTEMP '125C'
PRP MFG_Name 'TDK'
PRP MFG_PART_NUM 'CGA2B3X7R1H104K050BB'
PRP MINTEMP '-55C'
PRP MODIFY_DATE '10/23/2013'
PRP OTHER 'AEC-Q200'
PRP P1 '10%'
PRP P2 '50V'
PRP P3 'X7R'
PRP SHEETPART ''
PRP SIZE '0402'
PRP SUB ''
PRP Supplier_1 'Digi-Key'
PRP Supplier_Part_Number_1 '445-6899-1-ND'
PRP VALENTIUM_PART_NUM '<VALENTIUM>'
PRP VALUE '0.1UF'
TOP 0 4.2198425 3.0779921 0 N 135 45 C79-1
TOP 1 4.2198425 3.0441338 0 N 108 5 C79-2
#
# CMP 23
CMP 5 4.2748425 3.061063 90 N C80 CAP_0402_0.1UF_50V ;0=1,1=0.0236
PRP CATEGORY 'CAP, CER'
PRP DATE ''
PRP DESC 'CAP, CER, 0.1UF, 50V, 10%, X7R, AEC-Q200, 0402'
PRP MAXTEMP '125C'
PRP MFG_Name 'TDK'
PRP MFG_PART_NUM 'CGA2B3X7R1H104K050BB'
PRP MINTEMP '-55C'
PRP MODIFY_DATE '10/23/2013'
PRP OTHER 'AEC-Q200'
PRP P1 '10%'
PRP P2 '50V'
PRP P3 'X7R'
PRP SHEETPART ''
PRP SIZE '0402'
PRP SUB ''
PRP Supplier_1 'Digi-Key'
PRP Supplier_Part_Number_1 '445-6899-1-ND'
PRP VALENTIUM_PART_NUM '<VALENTIUM>'
PRP VALUE '0.1UF'
TOP 0 4.2748425 3.0779921 0 N 135 46 C80-1
TOP 1 4.2748425 3.0441338 0 N 108 6 C80-2
#
# CMP 24
CMP 5 4.3348425 3.061063 90 N C81 CAP_0402_0.1UF_50V ;0=1,1=0.0236
PRP CATEGORY 'CAP, CER'
PRP DATE ''
PRP DESC 'CAP, CER, 0.1UF, 50V, 10%, X7R, AEC-Q200, 0402'
PRP MAXTEMP '125C'
PRP MFG_Name 'TDK'
PRP MFG_PART_NUM 'CGA2B3X7R1H104K050BB'
PRP MINTEMP '-55C'
PRP MODIFY_DATE '10/23/2013'
PRP OTHER 'AEC-Q200'
PRP P1 '10%'
PRP P2 '50V'
PRP P3 'X7R'
PRP SHEETPART ''
PRP SIZE '0402'
PRP SUB ''
PRP Supplier_1 'Digi-Key'
PRP Supplier_Part_Number_1 '445-6899-1-ND'
PRP VALENTIUM_PART_NUM '<VALENTIUM>'
PRP VALUE '0.1UF'
TOP 0 4.3348425 3.0779921 0 N 135 47 C81-1
TOP 1 4.3348425 3.0441338 0 N 108 7 C81-2
#
# CMP 25
CMP 5 4.3948425 3.061063 90 N C82 CAP_0402_0.1UF_50V ;0=1,1=0.0236
PRP CATEGORY 'CAP, CER'
PRP DATE ''
PRP DESC 'CAP, CER, 0.1UF, 50V, 10%, X7R, AEC-Q200, 0402'
PRP MAXTEMP '125C'
PRP MFG_Name 'TDK'
PRP MFG_PART_NUM 'CGA2B3X7R1H104K050BB'
PRP MINTEMP '-55C'
PRP MODIFY_DATE '10/23/2013'
PRP OTHER 'AEC-Q200'
PRP P1 '10%'
PRP P2 '50V'
PRP P3 'X7R'
PRP SHEETPART ''
PRP SIZE '0402'
PRP SUB ''
PRP Supplier_1 'Digi-Key'
PRP Supplier_Part_Number_1 '445-6899-1-ND'
PRP VALENTIUM_PART_NUM '<VALENTIUM>'
PRP VALUE '0.1UF'
TOP 0 4.3948425 3.0779921 0 N 135 48 C82-1
TOP 1 4.3948425 3.0441338 0 N 108 8 C82-2
#
# CMP 26
CMP 5 4.4548425 3.061063 90 N C83 CAP_0402_0.1UF_50V ;0=1,1=0.0236
PRP CATEGORY 'CAP, CER'
PRP DATE ''
PRP DESC 'CAP, CER, 0.1UF, 50V, 10%, X7R, AEC-Q200, 0402'
PRP MAXTEMP '125C'
PRP MFG_Name 'TDK'
PRP MFG_PART_NUM 'CGA2B3X7R1H104K050BB'
PRP MINTEMP '-55C'
PRP MODIFY_DATE '10/23/2013'
PRP OTHER 'AEC-Q200'
PRP P1 '10%'
PRP P2 '50V'
PRP P3 'X7R'
PRP SHEETPART ''
PRP SIZE '0402'
PRP SUB ''
PRP Supplier_1 'Digi-Key'
PRP Supplier_Part_Number_1 '445-6899-1-ND'
PRP VALENTIUM_PART_NUM '<VALENTIUM>'
PRP VALUE '0.1UF'
TOP 0 4.4548425 3.0779921 0 N 135 49 C83-1
TOP 1 4.4548425 3.0441338 0 N 108 9 C83-2
#
# CMP 27
CMP 7 4.2448425 3.246063 0 N C84 CAP_0805_1UF_50V ;0=1,1=0.0551
PRP CATEGORY 'CAP, CER'
PRP DATE '10/31/2006 2:46:38 PM'
PRP DESC 'CAP, CER, 1.0UF, 50V, 10%, X7R, 0805'
PRP MAXTEMP '125C'
PRP MFG_Name 'MURATA'
PRP MFG_PART_NUM 'GCM21BR71H105KA03L'
PRP MINTEMP '-55C'
PRP MODIFY_DATE '10/23/2013'
PRP OTHER 'AEC-Q200'
PRP P1 '10%'
PRP P2 '50V'
PRP P3 'X7R'
PRP SHEETPART ''
PRP SIZE '0805'
PRP SUB ''
PRP Supplier_1 'Digi-Key'
PRP Supplier_Part_Number_1 '490-10675-1-ND'
PRP VALENTIUM_PART_NUM '<VALENTIUM>'
PRP VALUE '1.0UF'
TOP 0 4.2094094 3.246063 270 N 135 50 C84-1
TOP 1 4.2802756 3.246063 270 N 108 10 C84-2
#
# CMP 28
CMP 6 6.6048425 3.161063 270 N C85 CAP_0603_22PF_50V ;0=1,1=0.0394
PRP CATEGORY 'CAP, CER'
PRP DATE '7/25/2013'
PRP DESC 'CAP, CER, 22.PF, 50V, 5%, NPO, 0603'
PRP MAXTEMP '125C'
PRP MFG_Name 'KEMET'
PRP MFG_PART_NUM 'C0603C220J5GACTU'
PRP MINTEMP '-55C'
PRP MODIFY_DATE '10/23/2013'
PRP OTHER ''
PRP P1 '5%'
PRP P2 '50V'
PRP P3 'NP0'
PRP SHEETPART ''
PRP SIZE '0603'
PRP SUB ''
PRP Supplier_1 'Digi-Key'
PRP Supplier_Part_Number_1 '399-1053-1-ND'
PRP VALENTIUM_PART_NUM '<VALENTIUM>'
PRP VALUE '22pF'
TOP 0 6.6048425 3.1295669 180 N 135 51 C85-1
TOP 1 6.6048425 3.192559 180 N 14 0 C85-2
#
# CMP 29
CMP 6 6.6048425 3.296063 90 N C86 CAP_0603_22PF_50V ;0=1,1=0.0394
PRP CATEGORY 'CAP, CER'
PRP DATE '7/25/2013'
PRP DESC 'CAP, CER, 22.PF, 50V, 5%, NPO, 0603'
PRP MAXTEMP '125C'
PRP MFG_Name 'KEMET'
PRP MFG_PART_NUM 'C0603C220J5GACTU'
PRP MINTEMP '-55C'
PRP MODIFY_DATE '10/23/2013'
PRP OTHER ''
PRP P1 '5%'
PRP P2 '50V'
PRP P3 'NP0'
PRP SHEETPART ''
PRP SIZE '0603'
PRP SUB ''
PRP Supplier_1 'Digi-Key'
PRP Supplier_Part_Number_1 '399-1053-1-ND'
PRP VALENTIUM_PART_NUM '<VALENTIUM>'
PRP VALUE '22pF'
TOP 0 6.6048425 3.3275591 0 N 135 52 C86-1
TOP 1 6.6048425 3.264567 0 N 15 0 C86-2
#
# CMP 30
CMP 7 1.8378425 4.276063 0 N C91 CAP_0805_1UF_25V ;0=1,1=0.0551
PRP CATEGORY 'CAP, CER'
PRP DATE '4/11/2006 3:37:28 PM'
PRP DESC 'CAP, CER, 1.0UF, 25V, 10%, X5R, 0805'
PRP MAXTEMP '85C'
PRP MFG_Name 'AVX'
PRP MFG_PART_NUM '08053D105KAT2A'
PRP MINTEMP '-55C'
PRP MODIFY_DATE '10/23/2013'
PRP OTHER ''
PRP P1 '10%'
PRP P2 '25V'
PRP P3 'X5R'
PRP SHEETPART ''
PRP SIZE '0805'
PRP SUB ''
PRP Supplier_1 'Digi-Key'
PRP Supplier_Part_Number_1 '478-1409-1-ND'
PRP VALENTIUM_PART_NUM '<VALENTIUM>'
PRP VALUE '1.0UF'
TOP 0 1.8024094 4.276063 270 N 135 53 C91-1
TOP 1 1.8732756 4.276063 270 N 145 6 C91-2
#
# CMP 31
CMP 6 1.6958425 4.273063 180 N C92 GRT188R61E106ME13D ;0=1,1=0.0394
PRP CATEGORY 'CAP, CER'
PRP DATE '7/25/2013'
PRP DESC 'CAP, CER, 10.UF, 25V, 20%, X5R, AEC-Q200, 0603'
PRP MAXTEMP '85C'
PRP MFG_Name 'MURATA'
PRP MFG_PART_NUM 'GRT188R61E106ME13D'
PRP MINTEMP '-55C'
PRP MODIFY_DATE '10/23/2013'
PRP OTHER 'AEC-Q200'
PRP P1 '20%'
PRP P2 '25V'
PRP P3 'X5R'
PRP SHEETPART ''
PRP SIZE '0603'
PRP SUB ''
PRP Supplier_1 'Digi-Key'
PRP Supplier_Part_Number_1 '490-12323-6-ND'
PRP VALENTIUM_PART_NUM '<VALENTIUM>'
PRP VALUE '10.UF'
TOP 0 1.7273386 4.273063 90 N 135 54 C92-1
TOP 1 1.6643465 4.273063 90 N 145 7 C92-2
#
# CMP 32
CMP 24 3.5048425 2.797063 0 N R42 ERJ-3EKF1002V ;0=1,1=0.0197
PRP CATEGORY 'RES'
PRP DATE '7/26/2013'
PRP DESC 'RES, 10K, 1%, 1/10W, TF, 0603'
PRP MAXTEMP '125C'
PRP MFG_Name 'PANASONIC'
PRP MFG_PART_NUM 'ERJ-3EKF1002V'
PRP MINTEMP '-55C'
PRP ModifyDate '7/25/2013'
PRP OTHER '100PPM'
PRP P1 '1%'
PRP P2 '1/10W'
PRP P3 'TF'
PRP SHEETPART ''
PRP SIZE '0603'
PRP SUB 'GENERIC'
PRP Supplier_1 'Digi-Key'
PRP Supplier_Part_Number_1 'P10.0KHCT-ND'
PRP VALUE '10K'
PRP VELENTIUM_PART_NUM '<VELENTIUM>'
TOP 0 3.4776771 2.797063 270 N 29 0 R42-1
TOP 1 3.5320078 2.797063 270 N 108 17 R42-2
#
# CMP 33
CMP 24 1.9338425 4.102063 90 N R43 ERJ-3EKF1002V ;0=1,1=0.0197
PRP CATEGORY 'RES'
PRP DATE '7/26/2013'
PRP DESC 'RES, 10K, 1%, 1/10W, TF, 0603'
PRP MAXTEMP '125C'
PRP MFG_Name 'PANASONIC'
PRP MFG_PART_NUM 'ERJ-3EKF1002V'
PRP MINTEMP '-55C'
PRP ModifyDate '7/25/2013'
PRP OTHER '100PPM'
PRP P1 '1%'
PRP P2 '1/10W'
PRP P3 'TF'
PRP SHEETPART ''
PRP SIZE '0603'
PRP SUB 'GENERIC'
PRP Supplier_1 'Digi-Key'
PRP Supplier_Part_Number_1 'P10.0KHCT-ND'
PRP VALUE '10K'
PRP VELENTIUM_PART_NUM '<VELENTIUM>'
TOP 0 1.9338425 4.1292284 0 N 145 8 R43-1
TOP 1 1.9338425 4.0748977 0 N 30 0 R43-2
#
# CMP 34
CMP 32 1.7388425 4.112063 0 N U16 FT230XS-R ;0=1,1=0.0669
PRP CATEGORY 'IC, TCVR'
PRP DATE ''
PRP DESC 'IC, TCVR, FT230, USB TO UART, 5V, FTDI, 16SSOP'
PRP MAXTEMP '85C'
PRP MFG_Name 'FTDI'
PRP MFG_PART_NUM 'FT230XS-R'
PRP MINTEMP '-40C'
PRP MODIFY_DATE '8/14/2013'
PRP OTHER ''
PRP P1 'USB TO UART'
PRP P2 '5V'
PRP P3 'FTDI'
PRP SHEETPART ''
PRP SIZE '20SSOP'
PRP SUB ''
PRP Supplier_1 'Digi-Key'
PRP Supplier_Part_Number_1 '768-1135-1-ND'
PRP VALUE 'FT230XS'
PRP VELENTIUM_PART_NUM '<V PART NUM>'
TOP 0 1.631559 4.199563 270 N 33 1 U16-1
TOP 1 1.631559 4.174563 270 N 0 61 U16-2
TOP 2 1.631559 4.149563 270 N 32 1 U16-3
TOP 3 1.631559 4.124563 270 N 34 1 U16-4
TOP 4 1.631559 4.099563 270 N 135 174 U16-5
TOP 5 1.631559 4.074563 270 N 0 60 U16-6
TOP 6 1.631559 4.049563 270 N 0 59 U16-7
TOP 7 1.631559 4.024563 270 N 35 0 U16-8
TOP 8 1.8461259 4.024563 270 N 36 0 U16-9
TOP 9 1.8461259 4.049563 270 N 32 0 U16-10
TOP 10 1.8461259 4.074563 270 N 30 1 U16-11
TOP 11 1.8461259 4.099563 270 N 145 33 U16-12
TOP 12 1.8461259 4.124563 270 N 135 173 U16-13
TOP 13 1.8461259 4.149563 270 N 0 56 U16-14
TOP 14 1.8461259 4.174563 270 N 0 57 U16-15
TOP 15 1.8461259 4.199563 270 N 0 58 U16-16
#
# CMP 35
CMP 36 2.383748 4.1703386 180 N J4 473461001 ;0=1,1=0.0965
PRP CATEGORY 'CONN, REC'
PRP DATE ''
PRP DESC 'CONN, REC, USB, R/A, MICRO, TYPE B, 5 POS, SMT FLANGELESS'
PRP MAXTEMP '85C'
PRP MFG_Name 'MOLEX'
PRP MFG_PART_NUM '473461001'
PRP MINTEMP '-30C'
PRP MODIFY_DATE '10/10/2013'
PRP OTHER 'FLANGELESS'
PRP P1 'R/A'
PRP P2 '5 POS'
PRP P3 'USB MICRO B'
PRP SHEETPART ''
PRP SIZE 'SMT'
PRP SUB ''
PRP Supplier_1 'Digi-Key'
PRP Supplier_Part_Number_1 'WM11228CT-ND'
PRP VALENTIUM_PART_NUM '<VALENTIUM>'
PRP VALUE 'USB MICRO B'
TOP 0 2.2715433 4.275063 180 N 0 68 J4-0
TOP 1 2.3778425 4.275063 180 N 0 69 J4-0
TOP 2 2.2341417 4.1736851 180 N 0 70 J4-0
TOP 3 2.4309921 4.1736851 180 N 0 71 J4-0
TOP 4 2.4654409 4.275063 180 N 0 74 J4-0
TOP 5 2.1996929 4.275063 180 N 0 75 J4-0
TOP 6 2.383748 4.1703386 180 N 0 72 J4-1
TOP 7 2.3581575 4.1703386 180 N 36 1 J4-2
TOP 8 2.3325669 4.1703386 180 N 35 1 J4-3
TOP 9 2.3069763 4.1703386 180 N 0 73 J4-4
TOP 10 2.2813858 4.1703386 180 N 135 179 J4-5
#
# CMP 36
CMP 24 6.1228425 2.461063 270 N R5 ERJ-3EKF2612V ;0=1,1=0.0197
PRP CATEGORY 'RES'
PRP DATE '7/26/2013'
PRP DESC 'RES, 27.1K, 1%, 1/10W, TF, 0603'
PRP MAXTEMP '125C'
PRP MFG_Name 'PANASONIC'
PRP MFG_PART_NUM 'ERJ-3EKF2612V'
PRP MINTEMP '-55C'
PRP ModifyDate '7/25/2013'
PRP OTHER '100PPM'
PRP P1 '1%'
PRP P2 '1/10W'
PRP P3 'TF'
PRP SHEETPART ''
PRP SIZE '0603'
PRP SUB 'GENERIC'
PRP Supplier_1 'Digi-Key'
PRP Supplier_Part_Number_1 'P26.1KHCT-ND'
PRP VALUE '26.1K'
PRP VELENTIUM_PART_NUM '<VELENTIUM>'
TOP 0 6.1228425 2.4338976 180 N 22 0 R5-1
TOP 1 6.1228425 2.4882283 180 N 137 5 R5-2
#
# CMP 37
CMP 29 6.8348425 3.231063 0 N X1 MC306 ;0=1,1=0.0000
PRP CATEGORY 'XTAL'
PRP DATE ''
PRP DESC 'XTAL, <VAL>, P1, P2, P3, EIA, OTHER'
PRP MAXTEMP '85C'
PRP MFG_Name 'ABRACON CORPORATION'
PRP MFG_PART_NUM 'MC-306 32.768K-E3:ROHS'
PRP MINTEMP '-40C'
PRP MODIFY_DATE '9/5/2013'
PRP OTHER 'MC306, 3.8X8.00X2.54MM'
PRP P1 '6PF'
PRP P2 '20PPM'
PRP P3 'FUNDAMENTAL'
PRP SHEETPART ''
PRP SIZE '4-SOJ'
PRP SUB ''
PRP Supplier_1 'Digi-Key'
PRP Supplier_Part_Number_1 'SER2417CT-ND'
PRP VALENTIUM_PART_NUM '<VALENTIUM>'
PRP VALUE '32.768kHz'
TOP 0 6.7265748 3.1680709 270 N 14 2 X1-1
TOP 1 6.9431102 3.1680709 270 N 0 54 X1-2
TOP 2 6.9431102 3.2940551 270 N 0 55 X1-3
TOP 3 6.7265748 3.2940551 270 N 15 2 X1-4
#
# CMP 38
CMP 27 3.4848425 2.972063 0 N U13 SiT5356AI-FQA33-IT-10.000000 ;0=1,1=0.0000
PRP CATEGORY 'OSC'
PRP DATE '9/18/2013'
PRP DESC 'OSC, 10MHZ, 3.3V, 100PPB, DCTCXO, SMT'
PRP MAXTEMP '85C'
PRP MFG_Name 'SITIME'
PRP MFG_PART_NUM 'SiT5356AI-FQA33-IT-10.000000'
PRP MINTEMP '-30C'
PRP MODIFY_DATE '9/18/2013'
PRP OTHER ''
PRP P1 'OSC'
PRP P2 '3.3V'
PRP P3 '100PPB'
PRP SHEETPART ''
PRP SIZE '5.0X3.2MM'
PRP SUB ''
PRP VALUE '10MHZ'
PRP VELENTIUM_PART_NUM '<V PART NUM>'
TOP 0 3.4385827 3.0517874 0 N 42 1 U13-1
TOP 1 3.4444882 2.995685 0 N 39 1 U13-2
TOP 2 3.4444882 2.948441 0 N 0 47 U13-3
TOP 3 3.4385827 2.8923386 0 N 135 170 U13-4
TOP 4 3.4848425 2.8923386 270 N 29 1 U13-5
TOP 5 3.5311023 2.8923386 0 N 101 1 U13-6
TOP 6 3.5251968 2.948441 0 N 0 48 U13-7
TOP 7 3.5251968 2.995685 0 N 0 49 U13-8
TOP 8 3.5311023 3.0517874 0 N 108 18 U13-9
TOP 9 3.4848425 3.0517874 270 N 38 1 U13-10
#
# CMP 39
CMP 28 3.4512205 3.3007087 90 N U11 SiT5721AI-KWA33-T-10.000000 ;0=1,1=0.0394
PRP CATEGORY 'OSC'
PRP DATE '9/18/2013'
PRP DESC 'OSC, 10MHZ, 3.3V, 5PPB, DCOCXO, SMT'
PRP MAXTEMP '85C'
PRP MFG_Name 'SITIME'
PRP MFG_PART_NUM 'SiT5721AI-KWA33-T-10.000000'
PRP MINTEMP '-30C'
PRP MODIFY_DATE '9/18/2013'
PRP OTHER ''
PRP P1 'OSC'
PRP P2 '3.3V'
PRP P3 '5PPB'
PRP SHEETPART ''
PRP SIZE '9.0X7.0MM'
PRP SUB ''
PRP VALUE '10MHZ'
PRP VELENTIUM_PART_NUM '<V PART NUM>'
TOP 0 3.5693307 3.3853543 90 N 0 53 U11-1
TOP 1 3.5102756 3.3951969 90 N 37 1 U11-2
TOP 2 3.4512205 3.3951969 90 N 39 2 U11-3
TOP 3 3.3921654 3.3951969 90 N 38 2 U11-4
TOP 4 3.3331103 3.3951969 270 N 135 171 U11-5
TOP 5 3.3331103 3.2062205 90 N 102 1 U11-6
TOP 6 3.3921654 3.2062205 90 N 0 51 U11-7
TOP 7 3.4512205 3.2062205 90 N 0 50 U11-8
TOP 8 3.5102756 3.2062205 90 N 0 52 U11-9
TOP 9 3.5693307 3.2062205 270 N 108 19 U11-10
#
# CMP 40
CMP 18 3.7789398 2.6898312 90 N U10 MAC-SA5X ;0=1,1=0.0000
PRP CATEGORY 'MOD'
PRP DATE ''
PRP DESC 'MOD, MAC, MAC-SA5X, ATOMIC CLOCK'
PRP MAXTEMP '85C'
PRP MFG_Name 'MICROCHIP'
PRP MFG_PART_NUM 'MAC-SA5X'
PRP MINTEMP '-40C'
PRP MODIFY_DATE '3/22/2006 1:36:44 PM'
PRP OTHER 'AEC-Q200'
PRP P1 'ATOMIC CLOCK'
PRP P2 ''
PRP P3 ''
PRP SHEETPART ''
PRP SIZE ''
PRP SUB ''
PRP VALUE 'RV-3049-C3'
PRP VELENTIUM_PART_NUM '<V PART NUM>'
TOP 0 4.0689017 1.5996232 270 N 77 1 U10-1
TOP 1 3.9114214 1.5996232 270 N 71 1 U10-2
TOP 2 4.0689017 1.6196232 270 N 76 1 U10-3
TOP 3 3.9114214 1.6196232 270 N 70 1 U10-4
TOP 4 4.0689017 1.6396232 270 N 79 2 U10-5
TOP 5 3.9114214 1.6396232 270 N 69 1 U10-6
TOP 6 4.0689017 1.6596232 270 N 78 1 U10-7
TOP 7 3.9114214 1.6596232 270 N 135 183 U10-8
TOP 8 4.0689017 1.6796232 270 N 135 184 U10-9
TOP 9 3.9114214 1.6796232 270 N 0 86 U10-10
TOP 10 4.0689017 1.6996232 270 N 0 88 U10-11
TOP 11 3.9114214 1.6996232 270 N 0 87 U10-12
TOP 12 4.0689017 1.7196232 270 N 0 90 U10-13
TOP 13 3.9114214 1.7196232 270 N 0 89 U10-14
TOP 14 4.0689017 1.7396232 270 N 135 185 U10-15
TOP 15 3.9114214 1.7396232 270 N 0 91 U10-16
TOP 16 4.0689017 1.7596232 270 N 75 1 U10-17
TOP 17 3.9114214 1.7596232 270 N 0 92 U10-18
TOP 18 4.0689017 1.7796232 270 N 74 1 U10-19
TOP 19 3.9114214 1.7796232 270 N 82 1 U10-20
TOP 20 5.5781524 0.8906186 90 N 41 1 U10-P1
TOP 21 5.5781524 1.6898312 90 N 135 39 U10-P2
TOP 22 5.5781524 2.4890438 90 N 41 2 U10-P3
TOP 23 3.9797272 2.4890438 90 N 135 40 U10-P4
TOP 24 3.9797272 0.8906186 90 N 145 5 U10-P5
TOP 25 4.0624044 2.595343 90 N 81 1 U10-P6
TOP 26 4.1805146 2.595343 90 N 73 1 U10-P7
TOP 27 4.2986248 2.595343 90 N 72 1 U10-P8
#
# CMP 41
CMP 22 2.6628937 2.7167323 270 N U9 RCB-F9T ;0=1,1=0.0000
PRP CATEGORY 'MOD'
PRP DATE ''
PRP DESC 'MOD BLE 4.2'
PRP MAXTEMP '80C'
PRP MFG_Name 'UBLOCKS'
PRP MFG_PART_NUM 'RCB-F9T'
PRP MINTEMP '-40C'
PRP MODIFY_DATE '9/11/13'
PRP OTHER ''
PRP P1 'GPS'
PRP P2 ''
PRP P3 ''
PRP SHEETPART ''
PRP SIZE ''
PRP SUB ''
PRP Supplier_1 'Digi-Key'
PRP Supplier_Part_Number_1 '672-RCB-F9T-ND'
PRP VELENTIUM_PART_NUM '<V PART NUM>'
TOP 0 2.4223425 3.601378 270 N 0 13 U9-0
TOP 1 2.4223425 3.4438977 270 N 0 14 U9-0
TOP 2 2.5098425 3.640748 270 N 145 34 U9-1
TOP 3 2.3348425 3.640748 270 N 137 35 U9-2
TOP 4 2.5098425 3.5620079 270 N 1 2 U9-3
TOP 5 2.3348425 3.5620079 270 N 95 1 U9-4
TOP 6 2.5098425 3.4832677 270 N 3 2 U9-5
TOP 7 2.3348425 3.4832677 270 N 2 2 U9-6
TOP 8 2.5098425 3.4045276 270 N 92 1 U9-7
TOP 9 2.3348425 3.4045276 270 N 135 186 U9-8
#
# CMP 42
CMP 17 6.4498425 3.241063 90 N U8 BNO080 ;0=1,1=0.0000
PRP CATEGORY 'MOD'
PRP DATE ''
PRP DESC 'MOD, IMU, 5.2X3.8, SMT'
PRP MAXTEMP '+85C'
PRP MFG_Name 'HILLCREST'
PRP MFG_PART_NUM 'BNO080'
PRP MINTEMP '-40C'
PRP MODIFY_DATE '10/21/2013'
PRP OTHER 'IMU'
PRP P1 ''
PRP P2 ''
PRP P3 ''
PRP SHEETPART ''
PRP SIZE '5.2X3.8'
PRP SUB ''
PRP Supplier_1 'Digi-Key'
PRP Supplier_Part_Number_1 '1888-1000-1-ND'
PRP VALUE 'BNO080'
PRP VELENTIUM_PART_NUM '<V PART NUM>'
TOP 0 6.5113582 3.1524803 270 N 0 44 U8-1
TOP 1 6.4793701 3.1500197 90 N 135 166 U8-2
TOP 2 6.4598425 3.1500197 90 N 137 31 U8-3
TOP 3 6.44 3.1500197 90 N 90 1 U8-4
TOP 4 6.4203149 3.1500197 90 N 83 1 U8-5
TOP 5 6.3883268 3.1524803 270 N 84 1 U8-6
TOP 6 6.3883268 3.1721654 270 N 0 43 U8-7
TOP 7 6.3883268 3.1918504 270 N 0 42 U8-8
TOP 8 6.3883268 3.2115354 270 N 0 41 U8-9
TOP 9 6.3883268 3.2312205 270 N 89 1 U8-10
TOP 10 6.3883268 3.2509055 270 N 85 1 U8-11
TOP 11 6.3883268 3.2705906 270 N 0 40 U8-12
TOP 12 6.3883268 3.2902756 270 N 0 39 U8-13
TOP 13 6.3883268 3.3099606 270 N 86 1 U8-14
TOP 14 6.3883268 3.3296457 270 N 88 1 U8-15
TOP 15 6.4203149 3.3321063 270 N 87 1 U8-16
TOP 16 6.44 3.3321063 270 N 67 1 U8-17
TOP 17 6.459685 3.3321063 270 N 103 1 U8-18
TOP 18 6.4793701 3.3321063 270 N 40 1 U8-19
TOP 19 6.5113582 3.3296457 270 N 68 1 U8-20
TOP 20 6.5113582 3.3099606 270 N 0 38 U8-21
TOP 21 6.5113582 3.2902756 270 N 0 37 U8-22
TOP 22 6.5113582 3.2705906 270 N 0 36 U8-23
TOP 23 6.5113582 3.2509055 270 N 0 35 U8-24
TOP 24 6.5113582 3.2312205 270 N 135 165 U8-25
TOP 25 6.5113582 3.2115354 270 N 15 1 U8-26
TOP 26 6.5113582 3.1918504 270 N 14 1 U8-27
TOP 27 6.5113582 3.1721654 270 N 137 30 U8-28
#
# CMP 43
CMP 32 3.8798425 3.771063 0 N U6 FT230XS-R ;0=1,1=0.0669
PRP CATEGORY 'IC, TCVR'
PRP DATE ''
PRP DESC 'IC, TCVR, FT230, USB TO UART, 5V, FTDI, 16SSOP'
PRP MAXTEMP '85C'
PRP MFG_Name 'FTDI'
PRP MFG_PART_NUM 'FT230XS-R'
PRP MINTEMP '-40C'
PRP MODIFY_DATE '8/14/2013'
PRP OTHER ''
PRP P1 'USB TO UART'
PRP P2 '5V'
PRP P3 'FTDI'
PRP SHEETPART ''
PRP SIZE '20SSOP'
PRP SUB ''
PRP Supplier_1 'Digi-Key'
PRP Supplier_Part_Number_1 '768-1135-1-ND'
PRP VALUE 'FT230XS'
PRP VELENTIUM_PART_NUM '<V PART NUM>'
TOP 0 3.772559 3.858563 270 N 138 0 U6-1
TOP 1 3.772559 3.833563 270 N 0 34 U6-2
TOP 2 3.772559 3.808563 270 N 31 1 U6-3
TOP 3 3.772559 3.783563 270 N 139 0 U6-4
TOP 4 3.772559 3.758563 270 N 135 56 U6-5
TOP 5 3.772559 3.733563 270 N 0 33 U6-6
TOP 6 3.772559 3.708563 270 N 0 32 U6-7
TOP 7 3.772559 3.683563 270 N 45 0 U6-8
TOP 8 3.9871259 3.683563 270 N 46 0 U6-9
TOP 9 3.9871259 3.708563 270 N 31 0 U6-10
TOP 10 3.9871259 3.733563 270 N 26 0 U6-11
TOP 11 3.9871259 3.758563 270 N 145 9 U6-12
TOP 12 3.9871259 3.783563 270 N 135 55 U6-13
TOP 13 3.9871259 3.808563 270 N 0 29 U6-14
TOP 14 3.9871259 3.833563 270 N 0 30 U6-15
TOP 15 3.9871259 3.858563 270 N 0 31 U6-16
#
# CMP 44
CMP 26 3.1448425 4.0861023 0 N U5 HTST-105-01-L-DV-A ;0=1,1=0.0669
PRP CATEGORY 'CONN, HDR'
PRP DATE ''
PRP DESC 'CONN, HDR, 2X5, VERT, 0.1IN  SHROUDED, SMT, HTSH SERIES'
PRP MAXTEMP '125C'
PRP MFG_Name 'SAMTEC INC'
PRP MFG_PART_NUM 'HTST-105-01-L-DV-A'
PRP MINTEMP '-55C'
PRP MODIFY_DATE '10/10/2013'
PRP OTHER 'HTSH SERIES'
PRP P1 'VERT'
PRP P2 '0.1 IN'
PRP P3 'SHROUDED'
PRP SHEETPART ''
PRP SIZE 'SMT'
PRP SUB ''
PRP Supplier_1 'Digi-Key'
PRP Supplier_Part_Number_1 'SAM8809-ND'
PRP VALENTIUM_PART_NUM '<VALENTIUM>'
PRP VALUE '2X5'
TOP 0 2.9448425 3.951063 0 N 23 1 U5-1
TOP 1 2.9448425 4.2211417 0 N 135 169 U5-2
TOP 2 3.0448425 3.951063 0 N 43 1 U5-3
TOP 3 3.0448425 4.2211417 0 N 137 33 U5-4
TOP 4 3.1448425 3.951063 0 N 24 1 U5-5
TOP 5 3.1448425 4.2211417 0 N 137 32 U5-6
TOP 6 3.2448425 3.951063 0 N 0 46 U5-7
TOP 7 3.2448425 4.2211417 0 N 0 45 U5-8
TOP 8 3.3448425 3.951063 0 N 25 1 U5-9
TOP 9 3.3448425 4.2211417 0 N 135 168 U5-10
TOP 10 2.9948425 4.0861024 0 N 0 9 U5-empty-1
TOP 11 3.2948425 4.0861024 0 N 0 8 U5-empty-2
#
# CMP 45
CMP 31 6.2548425 2.316063 180 N U2 MP1482DS-LF ;0=1,1=0.0700
PRP CATEGORY 'IC, DC/DC'
PRP DATE ''
PRP DESC 'IC, DC/DC, MP1482DS, >4.75VIN, 0.923-15V OUT, SOIC8'
PRP MAXTEMP '+85C'
PRP MFG_Name 'MPS'
PRP MFG_PART_NUM 'MP1482DS-LF'
PRP MINTEMP '-40C'
PRP MODIFY_DATE '12/27/2005 8:34:25 AM'
PRP OTHER 'additional spec'
PRP P1 '>4.75V IN'
PRP P2 '0.923-15V OUT'
PRP P3 'W'
PRP SHEETPART ''
PRP SIZE '8SOIC'
PRP SUB ''
PRP Supplier_1 'Digi-Key'
PRP Supplier_Part_Number_1 '1589-1524-1-ND'
PRP VALUE 'MP1482DS'
PRP VELENTIUM_PART_NUM '<V PART NUM>'
TOP 0 6.3522834 2.241063 180 N 66 1 U2-1
TOP 1 6.3522834 2.291063 180 N 142 8 U2-2
TOP 2 6.3522834 2.341063 180 N 65 2 U2-3
TOP 3 6.3522834 2.391063 180 N 135 172 U2-4
TOP 4 6.1574016 2.391063 180 N 22 2 U2-5
TOP 5 6.1574016 2.341063 180 N 58 1 U2-6
TOP 6 6.1574016 2.291063 180 N 20 1 U2-7
TOP 7 6.1574016 2.241063 180 N 59 1 U2-8
#
# CMP 46
CMP 31 6.7348425 1.956063 0 N U1 MP1482DS-LF ;0=1,1=0.0700
PRP CATEGORY 'IC, DC/DC'
PRP DATE ''
PRP DESC 'IC, DC/DC, MP1482DS, >4.75VIN, 0.923-15V OUT, SOIC8'
PRP MAXTEMP '+85C'
PRP MFG_Name 'MPS'
PRP MFG_PART_NUM 'MP1482DS-LF'
PRP MINTEMP '-40C'
PRP MODIFY_DATE '12/27/2005 8:34:25 AM'
PRP OTHER 'additional spec'
PRP P1 '>4.75V IN'
PRP P2 '0.923-15V OUT'
PRP P3 'W'
PRP SHEETPART ''
PRP SIZE '8SOIC'
PRP SUB ''
PRP Supplier_1 'Digi-Key'
PRP Supplier_Part_Number_1 '1589-1524-1-ND'
PRP VALUE 'MP1482DS'
PRP VELENTIUM_PART_NUM '<V PART NUM>'
TOP 0 6.6374016 2.031063 0 N 64 0 U1-1
TOP 1 6.6374016 1.981063 0 N 142 1 U1-2
TOP 2 6.6374016 1.931063 0 N 63 0 U1-3
TOP 3 6.6374016 1.881063 0 N 135 57 U1-4
TOP 4 6.8322834 1.881063 0 N 21 0 U1-5
TOP 5 6.8322834 1.931063 0 N 61 0 U1-6
TOP 6 6.8322834 1.981063 0 N 44 0 U1-7
TOP 7 6.8322834 2.031063 0 N 62 0 U1-8
#
# CMP 47
CMP 16 5.6112205 3.8444882 180 N SW1 L101011MS02Q ;0=2,1=0.0000
PRP CATEGORY 'SW'
PRP DATE '9/5/2013'
PRP DESC 'SW, SPST, 250V, 2A, SLIDE, ON-OFF, TH'
PRP MAXTEMP '85C'
PRP MFG_Name 'C&K'
PRP MFG_PART_NUM 'L101011MS02Q'
PRP MINTEMP '-25C'
PRP MODIFY_DATE '1/21/2014'
PRP OTHER 'L101011MS02Q'
PRP P1 '250V'
PRP P2 '2A'
PRP P3 'SW, SPST, 250V, 2A, SLIDE, ON-OFF, TH'
PRP SHEETPART ''
PRP SIZE '19.1X10.79MM'
PRP SUB ''
PRP Supplier_1 'Digi-Key'
PRP Supplier_Part_Number_1 'CKC5106-ND'
PRP VALENTIUM_PART_NUM '<VALENTIUM>'
PRP VALUE 'SW-SPST'
TOP 0 5.7234252 4.0255906 180 N 53 0 SW1-1
TOP 1 5.7234252 3.8444882 180 N 55 0 SW1-2
#
# CMP 48
CMP 20 5.0248425 4.206063 0 N S6 B3U-1000P ;0=1,1=0.0630
PRP CATEGORY 'SW'
PRP DATE ''
PRP DESC 'SW, SPST-NO, TACT, 12V, 50MA, 3X2.5MM SMT, B3U SERIES'
PRP MAXTEMP '70C'
PRP MFG_Name 'OMRON'
PRP MFG_PART_NUM 'B3U-1000P'
PRP MINTEMP '-25C'
PRP MODIFY_DATE '9/5/2013'
PRP OTHER 'B3U SERIES'
PRP P1 '12V'
PRP P2 '50mA'
PRP P3 'TACT'
PRP SHEETPART ''
PRP SIZE '3X2.5MM'
PRP SUB ''
PRP Supplier_1 'Digi-Key'
PRP Supplier_Part_Number_1 'SW1020CT-ND'
PRP VALENTIUM_PART_NUM '<VALENTIUM>'
PRP VALUE 'SPST-NO'
TOP 0 4.9579134 4.206063 0 N 135 167 S6-1
TOP 1 5.0917716 4.206063 0 N 28 2 S6-2
#
# CMP 49
CMP 20 4.4998425 4.206063 0 N S5 B3U-1000P ;0=1,1=0.0630
PRP CATEGORY 'SW'
PRP DATE ''
PRP DESC 'SW, SPST-NO, TACT, 12V, 50MA, 3X2.5MM SMT, B3U SERIES'
PRP MAXTEMP '70C'
PRP MFG_Name 'OMRON'
PRP MFG_PART_NUM 'B3U-1000P'
PRP MINTEMP '-25C'
PRP MODIFY_DATE '9/5/2013'
PRP OTHER 'B3U SERIES'
PRP P1 '12V'
PRP P2 '50mA'
PRP P3 'TACT'
PRP SHEETPART ''
PRP SIZE '3X2.5MM'
PRP SUB ''
PRP Supplier_1 'Digi-Key'
PRP Supplier_Part_Number_1 'SW1020CT-ND'
PRP VALENTIUM_PART_NUM '<VALENTIUM>'
PRP VALUE 'SPST-NO'
TOP 0 4.4329134 4.206063 0 N 135 58 S5-1
TOP 1 4.5667716 4.206063 0 N 27 0 S5-2
#
# CMP 50
CMP 24 5.2398425 4.126063 180 N R35 ERJ-3EKF1001V ;0=1,1=0.0197
PRP CATEGORY 'RES'
PRP DATE '7/26/2013'
PRP DESC 'RES, 1.0K, 1%, 1/10W, TF, 0603'
PRP MAXTEMP '125C'
PRP MFG_Name 'PANASONIC'
PRP MFG_PART_NUM 'ERJ-3EKF1001V'
PRP MINTEMP '-55C'
PRP ModifyDate '7/25/2013'
PRP OTHER '100PPM'
PRP P1 '1%'
PRP P2 '1/10W'
PRP P3 'TF'
PRP SHEETPART ''
PRP SIZE '0603'
PRP SUB 'GENERIC'
PRP Supplier_1 'Digi-Key'
PRP Supplier_Part_Number_1 'P1.00KHCT-ND'
PRP VALUE '1.0K'
PRP VELENTIUM_PART_NUM '<VELENTIUM>'
TOP 0 5.2670079 4.126063 90 N 143 0 R35-1
TOP 1 5.2126772 4.126063 90 N 28 0 R35-2
#
# CMP 51
CMP 24 4.6798425 4.121063 180 N R34 ERJ-3EKF1001V ;0=1,1=0.0197
PRP CATEGORY 'RES'
PRP DATE '7/26/2013'
PRP DESC 'RES, 1.0K, 1%, 1/10W, TF, 0603'
PRP MAXTEMP '125C'
PRP MFG_Name 'PANASONIC'
PRP MFG_PART_NUM 'ERJ-3EKF1001V'
PRP MINTEMP '-55C'
PRP ModifyDate '7/25/2013'
PRP OTHER '100PPM'
PRP P1 '1%'
PRP P2 '1/10W'
PRP P3 'TF'
PRP SHEETPART ''
PRP SIZE '0603'
PRP SUB 'GENERIC'
PRP Supplier_1 'Digi-Key'
PRP Supplier_Part_Number_1 'P1.00KHCT-ND'
PRP VALUE '1.0K'
PRP VELENTIUM_PART_NUM '<VELENTIUM>'
TOP 0 4.7070079 4.121063 90 N 144 0 R34-1
TOP 1 4.6526772 4.121063 90 N 27 1 R34-2
#
# CMP 52
CMP 24 5.2398425 4.206063 0 N R33 ERJ-3EKF1002V ;0=1,1=0.0197
PRP CATEGORY 'RES'
PRP DATE '7/26/2013'
PRP DESC 'RES, 10K, 1%, 1/10W, TF, 0603'
PRP MAXTEMP '125C'
PRP MFG_Name 'PANASONIC'
PRP MFG_PART_NUM 'ERJ-3EKF1002V'
PRP MINTEMP '-55C'
PRP ModifyDate '7/25/2013'
PRP OTHER '100PPM'
PRP P1 '1%'
PRP P2 '1/10W'
PRP P3 'TF'
PRP SHEETPART ''
PRP SIZE '0603'
PRP SUB 'GENERIC'
PRP Supplier_1 'Digi-Key'
PRP Supplier_Part_Number_1 'P10.0KHCT-ND'
PRP VALUE '10K'
PRP VELENTIUM_PART_NUM '<VELENTIUM>'
TOP 0 5.2126771 4.206063 270 N 28 1 R33-1
TOP 1 5.2670078 4.206063 270 N 137 6 R33-2
#
# CMP 53
CMP 24 4.6798425 4.206063 0 N R32 ERJ-3EKF1002V ;0=1,1=0.0197
PRP CATEGORY 'RES'
PRP DATE '7/26/2013'
PRP DESC 'RES, 10K, 1%, 1/10W, TF, 0603'
PRP MAXTEMP '125C'
PRP MFG_Name 'PANASONIC'
PRP MFG_PART_NUM 'ERJ-3EKF1002V'
PRP MINTEMP '-55C'
PRP ModifyDate '7/25/2013'
PRP OTHER '100PPM'
PRP P1 '1%'
PRP P2 '1/10W'
PRP P3 'TF'
PRP SHEETPART ''
PRP SIZE '0603'
PRP SUB 'GENERIC'
PRP Supplier_1 'Digi-Key'
PRP Supplier_Part_Number_1 'P10.0KHCT-ND'
PRP VALUE '10K'
PRP VELENTIUM_PART_NUM '<VELENTIUM>'
TOP 0 4.6526771 4.206063 270 N 27 2 R32-1
TOP 1 4.7070078 4.206063 270 N 137 7 R32-2
#
# CMP 54
CMP 24 1.2439683 4.066063 270 N R31 ERJ-3EKF2000V ;0=1,1=0.0197
PRP CATEGORY 'RES'
PRP DATE '7/26/2013'
PRP DESC 'RES, 200 OHM, 1%, 1/10W, TF, 0603'
PRP MAXTEMP '125C'
PRP MFG_Name 'PANASONIC'
PRP MFG_PART_NUM 'ERJ-3EKF2000V'
PRP MINTEMP '-55C'
PRP ModifyDate '7/25/2013'
PRP OTHER '100PPM'
PRP P1 '1%'
PRP P2 '1/10W'
PRP P3 'TF'
PRP SHEETPART ''
PRP SIZE '0603'
PRP SUB 'GENERIC'
PRP Supplier_1 'Digi-Key'
PRP Supplier_Part_Number_1 'P200HCT-ND'
PRP VALUE '200 OHM'
PRP VELENTIUM_PART_NUM '<VELENTIUM>'
TOP 0 1.2439683 4.0388976 180 N 109 0 R31-1
TOP 1 1.2439683 4.0932283 180 N 47 0 R31-2
#
# CMP 55
CMP 24 1.0423017 4.066063 270 N R30 ERJ-3EKF2000V ;0=1,1=0.0197
PRP CATEGORY 'RES'
PRP DATE '7/26/2013'
PRP DESC 'RES, 200 OHM, 1%, 1/10W, TF, 0603'
PRP MAXTEMP '125C'
PRP MFG_Name 'PANASONIC'
PRP MFG_PART_NUM 'ERJ-3EKF2000V'
PRP MINTEMP '-55C'
PRP ModifyDate '7/25/2013'
PRP OTHER '100PPM'
PRP P1 '1%'
PRP P2 '1/10W'
PRP P3 'TF'
PRP SHEETPART ''
PRP SIZE '0603'
PRP SUB 'GENERIC'
PRP Supplier_1 'Digi-Key'
PRP Supplier_Part_Number_1 'P200HCT-ND'
PRP VALUE '200 OHM'
PRP VELENTIUM_PART_NUM '<VELENTIUM>'
TOP 0 1.0423017 4.0388976 180 N 110 0 R30-1
TOP 1 1.0423017 4.0932283 180 N 48 0 R30-2
#
# CMP 56
CMP 24 0.8406351 4.066063 270 N R29 ERJ-3EKF2000V ;0=1,1=0.0197
PRP CATEGORY 'RES'
PRP DATE '7/26/2013'
PRP DESC 'RES, 200 OHM, 1%, 1/10W, TF, 0603'
PRP MAXTEMP '125C'
PRP MFG_Name 'PANASONIC'
PRP MFG_PART_NUM 'ERJ-3EKF2000V'
PRP MINTEMP '-55C'
PRP ModifyDate '7/25/2013'
PRP OTHER '100PPM'
PRP P1 '1%'
PRP P2 '1/10W'
PRP P3 'TF'
PRP SHEETPART ''
PRP SIZE '0603'
PRP SUB 'GENERIC'
PRP Supplier_1 'Digi-Key'
PRP Supplier_Part_Number_1 'P200HCT-ND'
PRP VALUE '200 OHM'
PRP VELENTIUM_PART_NUM '<VELENTIUM>'
TOP 0 0.8406351 4.0388976 180 N 134 0 R29-1
TOP 1 0.8406351 4.0932283 180 N 17 0 R29-2
#
# CMP 57
CMP 24 0.6389685 4.066063 270 N R28 ERJ-3EKF2000V ;0=1,1=0.0197
PRP CATEGORY 'RES'
PRP DATE '7/26/2013'
PRP DESC 'RES, 200 OHM, 1%, 1/10W, TF, 0603'
PRP MAXTEMP '125C'
PRP MFG_Name 'PANASONIC'
PRP MFG_PART_NUM 'ERJ-3EKF2000V'
PRP MINTEMP '-55C'
PRP ModifyDate '7/25/2013'
PRP OTHER '100PPM'
PRP P1 '1%'
PRP P2 '1/10W'
PRP P3 'TF'
PRP SHEETPART ''
PRP SIZE '0603'
PRP SUB 'GENERIC'
PRP Supplier_1 'Digi-Key'
PRP Supplier_Part_Number_1 'P200HCT-ND'
PRP VALUE '200 OHM'
PRP VELENTIUM_PART_NUM '<VELENTIUM>'
TOP 0 0.6389685 4.0388976 180 N 133 0 R28-1
TOP 1 0.6389685 4.0932283 180 N 16 0 R28-2
#
# CMP 58
CMP 24 4.1398425 3.701063 180 N R27 ERJ-3EKF1002V ;0=1,1=0.0197
PRP CATEGORY 'RES'
PRP DATE '7/26/2013'
PRP DESC 'RES, 10K, 1%, 1/10W, TF, 0603'
PRP MAXTEMP '125C'
PRP MFG_Name 'PANASONIC'
PRP MFG_PART_NUM 'ERJ-3EKF1002V'
PRP MINTEMP '-55C'
PRP ModifyDate '7/25/2013'
PRP OTHER '100PPM'
PRP P1 '1%'
PRP P2 '1/10W'
PRP P3 'TF'
PRP SHEETPART ''
PRP SIZE '0603'
PRP SUB 'GENERIC'
PRP Supplier_1 'Digi-Key'
PRP Supplier_Part_Number_1 'P10.0KHCT-ND'
PRP VALUE '10K'
PRP VELENTIUM_PART_NUM '<VELENTIUM>'
TOP 0 4.1670079 3.701063 90 N 145 10 R27-1
TOP 1 4.1126772 3.701063 90 N 26 1 R27-2
#
# CMP 59
CMP 23 3.6848425 3.786063 180 N R26 ERJ-2RKF4990X ;0=1,1=0.0157
PRP CATEGORY 'RES'
PRP DATE '7/26/2013'
PRP DESC 'RES, 499. OHM, 1%, 1/16W, TF, AEC-Q200, 0402'
PRP MAXTEMP '155C'
PRP MFG_Name 'PANASONIC'
PRP MFG_PART_NUM 'ERJ-2RKF4990X'
PRP MINTEMP '-55C'
PRP ModifyDate '7/25/2013'
PRP OTHER '100PPM, AEC-Q200'
PRP P1 '1%'
PRP P2 '1/16W'
PRP P3 'TF'
PRP SHEETPART ''
PRP SIZE '0402'
PRP SUB 'GENERIC'
PRP Supplier_1 'Digi-Key'
PRP Supplier_Part_Number_1 'P499LCT-ND'
PRP VALUE '499. OHM'
PRP VELENTIUM_PART_NUM '<VELENTIUM>'
TOP 0 3.7015748 3.786063 90 N 139 1 R26-1
TOP 1 3.6681102 3.786063 90 N 49 0 R26-2
#
# CMP 60
CMP 23 3.6848425 3.861063 180 N R25 ERJ-2RKF4990X ;0=1,1=0.0157
PRP CATEGORY 'RES'
PRP DATE '7/26/2013'
PRP DESC 'RES, 499. OHM, 1%, 1/16W, TF, AEC-Q200, 0402'
PRP MAXTEMP '155C'
PRP MFG_Name 'PANASONIC'
PRP MFG_PART_NUM 'ERJ-2RKF4990X'
PRP MINTEMP '-55C'
PRP ModifyDate '7/25/2013'
PRP OTHER '100PPM, AEC-Q200'
PRP P1 '1%'
PRP P2 '1/16W'
PRP P3 'TF'
PRP SHEETPART ''
PRP SIZE '0402'
PRP SUB 'GENERIC'
PRP Supplier_1 'Digi-Key'
PRP Supplier_Part_Number_1 'P499LCT-ND'
PRP VALUE '499. OHM'
PRP VELENTIUM_PART_NUM '<VELENTIUM>'
TOP 0 3.7015748 3.861063 90 N 138 1 R25-1
TOP 1 3.6681102 3.861063 90 N 50 0 R25-2
#
# CMP 61
CMP 23 3.0551181 0.5905512 90 N R24 ERJ-2GE0R00X ;0=1,1=0.0157
PRP CATEGORY 'RES'
PRP DATE '7/26/2013'
PRP DESC 'RES, 0 OHM, 1%, 1/16W, TF, AEC-Q200, 0402'
PRP MAXTEMP '155C'
PRP MFG_Name 'PANASONIC'
PRP MFG_PART_NUM 'ERJ-2GE0R00X'
PRP MINTEMP '-55C'
PRP ModifyDate '7/25/2013'
PRP OTHER '100PPM, AEC-Q200'
PRP P1 '1%'
PRP P2 '1/16W'
PRP P3 'TF'
PRP SHEETPART ''
PRP SIZE '0402'
PRP SUB 'GENERIC'
PRP Supplier_1 'Digi-Key'
PRP Supplier_Part_Number_1 'P0.0JCT-ND'
PRP VALUE '0 OHM'
PRP VELENTIUM_PART_NUM '<VELENTIUM>'
TOP 0 3.0551181 0.6072835 0 N 113 1 R24-1
TOP 1 3.0551181 0.5738189 0 N 19 0 R24-2
#
# CMP 62
CMP 23 2.503937 0.5905512 90 N R23 ERJ-2GE0R00X ;0=1,1=0.0157
PRP CATEGORY 'RES'
PRP DATE '7/26/2013'
PRP DESC 'RES, 0 OHM, 1%, 1/16W, TF, AEC-Q200, 0402'
PRP MAXTEMP '155C'
PRP MFG_Name 'PANASONIC'
PRP MFG_PART_NUM 'ERJ-2GE0R00X'
PRP MINTEMP '-55C'
PRP ModifyDate '7/25/2013'
PRP OTHER '100PPM, AEC-Q200'
PRP P1 '1%'
PRP P2 '1/16W'
PRP P3 'TF'
PRP SHEETPART ''
PRP SIZE '0402'
PRP SUB 'GENERIC'
PRP Supplier_1 'Digi-Key'
PRP Supplier_Part_Number_1 'P0.0JCT-ND'
PRP VALUE '0 OHM'
PRP VELENTIUM_PART_NUM '<VELENTIUM>'
TOP 0 2.503937 0.6072835 0 N 113 0 R23-1
TOP 1 2.503937 0.5738189 0 N 18 0 R23-2
#
# CMP 63
CMP 24 2.1468425 2.652063 270 N R22 ERJ-3EKF4701V ;0=1,1=0.0197
PRP CATEGORY 'RES'
PRP DATE '7/26/2013'
PRP DESC 'RES, 4.7K, 1%, 1/10W, TF, 0603'
PRP MAXTEMP '125C'
PRP MFG_Name 'PANASONIC'
PRP MFG_PART_NUM 'ERJ-3EKF4701V'
PRP MINTEMP '-55C'
PRP ModifyDate '7/25/2013'
PRP OTHER '100PPM'
PRP P1 '1%'
PRP P2 '1/10W'
PRP P3 'TF'
PRP SHEETPART ''
PRP SIZE '0603'
PRP SUB 'GENERIC'
PRP Supplier_1 'Digi-Key'
PRP Supplier_Part_Number_1 'P4.70KHCT-ND'
PRP VALUE '4.7K'
PRP VELENTIUM_PART_NUM '<VELENTIUM>'
TOP 0 2.1468425 2.6248976 180 N 124 1 R22-1
TOP 1 2.1468425 2.6792283 180 N 137 8 R22-2
#
# CMP 64
CMP 25 3.3498425 3.706063 270 N R21 CRCW080533R0FKEA ;0=1,1=0.0197
PRP CATEGORY 'RES'
PRP DATE ''
PRP DESC 'RES, 33 OHM, 1%, 1/8W, TF, 0805'
PRP MAXTEMP '125C'
PRP MFG_Name 'VISHAY/DALE'
PRP MFG_PART_NUM 'CRCW080533R0FKEA'
PRP MINTEMP '-55C'
PRP ModifyDate '7/26/2013'
PRP OTHER '100PPM'
PRP P1 '1%'
PRP P2 '1/8W'
PRP P3 'TF'
PRP SHEETPART ''
PRP SIZE '0805'
PRP SUB ''
PRP Supplier_1 'Digi-Key'
PRP Supplier_Part_Number_1 '541-33.0CCT-ND'
PRP VALUE '33 OHM'
PRP VELENTIUM_PART_NUM '<VELENTIUM>'
TOP 0 3.3498425 3.6666929 180 N 146 1 R21-1
TOP 1 3.3498425 3.7454331 180 N 25 0 R21-2
#
# CMP 65
CMP 25 3.1448425 3.706063 270 N R20 CRCW080533R0FKEA ;0=1,1=0.0197
PRP CATEGORY 'RES'
PRP DATE ''
PRP DESC 'RES, 33 OHM, 1%, 1/8W, TF, 0805'
PRP MAXTEMP '125C'
PRP MFG_Name 'VISHAY/DALE'
PRP MFG_PART_NUM 'CRCW080533R0FKEA'
PRP MINTEMP '-55C'
PRP ModifyDate '7/26/2013'
PRP OTHER '100PPM'
PRP P1 '1%'
PRP P2 '1/8W'
PRP P3 'TF'
PRP SHEETPART ''
PRP SIZE '0805'
PRP SUB ''
PRP Supplier_1 'Digi-Key'
PRP Supplier_Part_Number_1 '541-33.0CCT-ND'
PRP VALUE '33 OHM'
PRP VELENTIUM_PART_NUM '<VELENTIUM>'
TOP 0 3.1448425 3.6666929 180 N 136 0 R20-1
TOP 1 3.1448425 3.7454331 180 N 24 0 R20-2
#
# CMP 66
CMP 25 3.0448425 3.706063 270 N R19 CRCW080533R0FKEA ;0=1,1=0.0197
PRP CATEGORY 'RES'
PRP DATE ''
PRP DESC 'RES, 33 OHM, 1%, 1/8W, TF, 0805'
PRP MAXTEMP '125C'
PRP MFG_Name 'VISHAY/DALE'
PRP MFG_PART_NUM 'CRCW080533R0FKEA'
PRP MINTEMP '-55C'
PRP ModifyDate '7/26/2013'
PRP OTHER '100PPM'
PRP P1 '1%'
PRP P2 '1/8W'
PRP P3 'TF'
PRP SHEETPART ''
PRP SIZE '0805'
PRP SUB ''
PRP Supplier_1 'Digi-Key'
PRP Supplier_Part_Number_1 '541-33.0CCT-ND'
PRP VALUE '33 OHM'
PRP VELENTIUM_PART_NUM '<VELENTIUM>'
TOP 0 3.0448425 3.6666929 180 N 140 0 R19-1
TOP 1 3.0448425 3.7454331 180 N 43 0 R19-2
#
# CMP 67
CMP 25 2.9448425 3.706063 270 N R18 CRCW080533R0FKEA ;0=1,1=0.0197
PRP CATEGORY 'RES'
PRP DATE ''
PRP DESC 'RES, 33 OHM, 1%, 1/8W, TF, 0805'
PRP MAXTEMP '125C'
PRP MFG_Name 'VISHAY/DALE'
PRP MFG_PART_NUM 'CRCW080533R0FKEA'
PRP MINTEMP '-55C'
PRP ModifyDate '7/26/2013'
PRP OTHER '100PPM'
PRP P1 '1%'
PRP P2 '1/8W'
PRP P3 'TF'
PRP SHEETPART ''
PRP SIZE '0805'
PRP SUB ''
PRP Supplier_1 'Digi-Key'
PRP Supplier_Part_Number_1 '541-33.0CCT-ND'
PRP VALUE '33 OHM'
PRP VELENTIUM_PART_NUM '<VELENTIUM>'
TOP 0 2.9448425 3.6666929 180 N 141 0 R18-1
TOP 1 2.9448425 3.7454331 180 N 23 0 R18-2
#
# CMP 68
CMP 24 6.0048425 2.366063 90 N R9 ERJ-3EKF2201V ;0=1,1=0.0197
PRP CATEGORY 'RES'
PRP DATE '8/15/2013'
PRP DESC 'RES, 2.2K, 1%, 1/10W, TF, 0603'
PRP MAXTEMP '125C'
PRP MFG_Name 'PANASONIC'
PRP MFG_PART_NUM 'ERJ-3EKF2201V'
PRP MINTEMP '-55C'
PRP ModifyDate '8/15/2013'
PRP OTHER '100PPM'
PRP P1 '1%'
PRP P2 '1/10W'
PRP P3 'TF'
PRP SHEETPART ''
PRP SIZE '0603'
PRP SUB 'GENERIC'
PRP Supplier_1 'Digi-Key'
PRP Supplier_Part_Number_1 'P2.20KHCT-ND'
PRP VALUE '2.2K'
PRP VELENTIUM_PART_NUM '<VELENTIUM>'
TOP 0 6.0048425 2.3932284 0 N 135 59 R9-1
TOP 1 6.0048425 2.3388977 0 N 57 0 R9-2
#
# CMP 69
CMP 24 7.0098425 1.911063 90 N R8 ERJ-3EKF2201V ;0=1,1=0.0197
PRP CATEGORY 'RES'
PRP DATE '8/15/2013'
PRP DESC 'RES, 2.2K, 1%, 1/10W, TF, 0603'
PRP MAXTEMP '125C'
PRP MFG_Name 'PANASONIC'
PRP MFG_PART_NUM 'ERJ-3EKF2201V'
PRP MINTEMP '-55C'
PRP ModifyDate '8/15/2013'
PRP OTHER '100PPM'
PRP P1 '1%'
PRP P2 '1/10W'
PRP P3 'TF'
PRP SHEETPART ''
PRP SIZE '0603'
PRP SUB 'GENERIC'
PRP Supplier_1 'Digi-Key'
PRP Supplier_Part_Number_1 'P2.20KHCT-ND'
PRP VALUE '2.2K'
PRP VELENTIUM_PART_NUM '<VELENTIUM>'
TOP 0 7.0098425 1.9382284 0 N 135 60 R8-1
TOP 1 7.0098425 1.8838977 0 N 60 0 R8-2
#
# CMP 70
CMP 24 6.3398425 2.451063 180 N R7 ERJ-3EKF1002V ;0=1,1=0.0197
PRP CATEGORY 'RES'
PRP DATE '7/26/2013'
PRP DESC 'RES, 10K, 1%, 1/10W, TF, 0603'
PRP MAXTEMP '125C'
PRP MFG_Name 'PANASONIC'
PRP MFG_PART_NUM 'ERJ-3EKF1002V'
PRP MINTEMP '-55C'
PRP ModifyDate '7/25/2013'
PRP OTHER '100PPM'
PRP P1 '1%'
PRP P2 '1/10W'
PRP P3 'TF'
PRP SHEETPART ''
PRP SIZE '0603'
PRP SUB 'GENERIC'
PRP Supplier_1 'Digi-Key'
PRP Supplier_Part_Number_1 'P10.0KHCT-ND'
PRP VALUE '10K'
PRP VELENTIUM_PART_NUM '<VELENTIUM>'
TOP 0 6.3670079 2.451063 90 N 135 61 R7-1
TOP 1 6.3126772 2.451063 90 N 22 1 R7-2
#
# CMP 71
CMP 24 6.7548425 1.816063 0 N R6 ERJ-3EKF1002V ;0=1,1=0.0197
PRP CATEGORY 'RES'
PRP DATE '7/26/2013'
PRP DESC 'RES, 10K, 1%, 1/10W, TF, 0603'
PRP MAXTEMP '125C'
PRP MFG_Name 'PANASONIC'
PRP MFG_PART_NUM 'ERJ-3EKF1002V'
PRP MINTEMP '-55C'
PRP ModifyDate '7/25/2013'
PRP OTHER '100PPM'
PRP P1 '1%'
PRP P2 '1/10W'
PRP P3 'TF'
PRP SHEETPART ''
PRP SIZE '0603'
PRP SUB 'GENERIC'
PRP Supplier_1 'Digi-Key'
PRP Supplier_Part_Number_1 'P10.0KHCT-ND'
PRP VALUE '10K'
PRP VELENTIUM_PART_NUM '<VELENTIUM>'
TOP 0 6.7276771 1.816063 270 N 135 62 R6-1
TOP 1 6.7820078 1.816063 270 N 21 1 R6-2
#
# CMP 72
CMP 24 6.8698425 1.816063 0 N R4 ERJ-3EKF4702V ;0=1,1=0.0197
PRP CATEGORY 'RES'
PRP DATE '1/22/2014'
PRP DESC 'RES, 47K, 1%, 1/10W, TF, 0603'
PRP MAXTEMP '125C'
PRP MFG_Name 'PANASONIC'
PRP MFG_PART_NUM 'ERJ-3EKF4702V'
PRP MINTEMP '-55C'
PRP ModifyDate '1/22/2014'
PRP OTHER '100PPM'
PRP P1 '1%'
PRP P2 '1/10W'
PRP P3 'TF'
PRP SHEETPART ''
PRP SIZE '0603'
PRP SUB 'GENERIC'
PRP Supplier_1 'Digi-Key'
PRP Supplier_Part_Number_1 'P47.0KHCT-ND'
PRP VALUE '47K'
PRP VELENTIUM_PART_NUM '<VELENTIUM>'
TOP 0 6.8426771 1.816063 270 N 145 11 R4-1
TOP 1 6.8970078 1.816063 270 N 21 2 R4-2
#
# CMP 73
CMP 24 6.2348425 2.156063 90 N R3 ERJ-3EKF4702V ;0=1,1=0.0197
PRP CATEGORY 'RES'
PRP DATE '1/22/2014'
PRP DESC 'RES, 47K, 1%, 1/10W, TF, 0603'
PRP MAXTEMP '125C'
PRP MFG_Name 'PANASONIC'
PRP MFG_PART_NUM 'ERJ-3EKF4702V'
PRP MINTEMP '-55C'
PRP ModifyDate '1/22/2014'
PRP OTHER '100PPM'
PRP P1 '1%'
PRP P2 '1/10W'
PRP P3 'TF'
PRP SHEETPART ''
PRP SIZE '0603'
PRP SUB 'GENERIC'
PRP Supplier_1 'Digi-Key'
PRP Supplier_Part_Number_1 'P47.0KHCT-ND'
PRP VALUE '47K'
PRP VELENTIUM_PART_NUM '<VELENTIUM>'
TOP 0 6.2348425 2.1832284 0 N 20 0 R3-1
TOP 1 6.2348425 2.1288977 0 N 142 2 R3-2
#
# CMP 74
CMP 24 6.7498425 2.116063 270 N R2 ERJ-3EKF4702V ;0=1,1=0.0197
PRP CATEGORY 'RES'
PRP DATE '1/22/2014'
PRP DESC 'RES, 47K, 1%, 1/10W, TF, 0603'
PRP MAXTEMP '125C'
PRP MFG_Name 'PANASONIC'
PRP MFG_PART_NUM 'ERJ-3EKF4702V'
PRP MINTEMP '-55C'
PRP ModifyDate '1/22/2014'
PRP OTHER '100PPM'
PRP P1 '1%'
PRP P2 '1/10W'
PRP P3 'TF'
PRP SHEETPART ''
PRP SIZE '0603'
PRP SUB 'GENERIC'
PRP Supplier_1 'Digi-Key'
PRP Supplier_Part_Number_1 'P47.0KHCT-ND'
PRP VALUE '47K'
PRP VELENTIUM_PART_NUM '<VELENTIUM>'
TOP 0 6.7498425 2.0888976 180 N 44 1 R2-1
TOP 1 6.7498425 2.1432283 180 N 142 3 R2-2
#
# CMP 75
CMP 24 4.1777559 3.6033465 0 N R1 ERJ-3EKF2000V ;0=1,1=0.0197
PRP CATEGORY 'RES'
PRP DATE '7/26/2013'
PRP DESC 'RES, 200 OHM, 1%, 1/10W, TF, 0603'
PRP MAXTEMP '125C'
PRP MFG_Name 'PANASONIC'
PRP MFG_PART_NUM 'ERJ-3EKF2000V'
PRP MINTEMP '-55C'
PRP ModifyDate '7/25/2013'
PRP OTHER '100PPM'
PRP P1 '1%'
PRP P2 '1/10W'
PRP P3 'TF'
PRP SHEETPART ''
PRP SIZE '0603'
PRP SUB 'GENERIC'
PRP Supplier_1 'Digi-Key'
PRP Supplier_Part_Number_1 'P200HCT-ND'
PRP VALUE '200 OHM'
PRP VELENTIUM_PART_NUM '<VELENTIUM>'
TOP 0 4.1505905 3.6033465 270 N 135 187 R1-1
TOP 1 4.2049212 3.6033465 270 N 51 1 R1-2
#
# CMP 76
CMP 21 2.4468451 0.2450353 0 N P2 PCIex4 ;0=1,1=0.0000
PRP Manufacturer 'NA'
PRP NOTE 'NC'
PRP Part_Number '451'
PRP Part_Type 'SMT'
PRP Vendor_P/N 'NA'
TOP 0 1.7972451 0.1572953 0 N 113 2 P2-A1
TOP 1 1.8366151 0.1377953 0 N 111 2 P2-A2
TOP 2 1.8759851 0.1377953 0 N 111 3 P2-A3
TOP 3 1.9153551 0.1377953 0 N 135 7 P2-A4
TOP 4 1.9547251 0.1377953 0 N 0 4 P2-A5
TOP 5 1.9940951 0.1377953 0 N 0 3 P2-A6
TOP 6 2.0334651 0.1377953 0 N 0 2 P2-A7
TOP 7 2.0728351 0.1377953 0 N 0 1 P2-A8
TOP 8 2.1122051 0.1377953 0 N 112 2 P2-A9
TOP 9 2.1515751 0.1377953 0 N 112 3 P2-A10
TOP 10 2.1909451 0.1377953 0 N 124 0 P2-A11
TOP 11 2.3090551 0.1377953 0 N 135 15 P2-A12
TOP 12 2.3484251 0.1377953 0 N 4 1 P2-A13
TOP 13 2.3877951 0.1377953 0 N 5 1 P2-A14
TOP 14 2.4271651 0.1377953 0 N 135 16 P2-A15
TOP 15 2.4665351 0.1377953 0 N 6 1 P2-A16
TOP 16 2.5059051 0.1377953 0 N 7 1 P2-A17
TOP 17 2.5452751 0.1377953 0 N 135 8 P2-A18
TOP 18 2.5846451 0.1377953 0 N 0 0 P2-A19
TOP 19 2.6240151 0.1377953 0 N 135 9 P2-A20
TOP 20 2.6633851 0.1377953 0 N 8 1 P2-A21
TOP 21 2.7027551 0.1377953 0 N 56 1 P2-A22
TOP 22 2.7421251 0.1377953 0 N 135 12 P2-A23
TOP 23 2.7814951 0.1377953 0 N 135 14 P2-A24
TOP 24 2.8208651 0.1377953 0 N 9 1 P2-A25
TOP 25 2.8602351 0.1377953 0 N 10 1 P2-A26
TOP 26 2.8996051 0.1377953 0 N 135 10 P2-A27
TOP 27 2.9389751 0.1377953 0 N 135 13 P2-A28
TOP 28 2.9783451 0.1377953 0 N 11 1 P2-A29
TOP 29 3.0177151 0.1377953 0 N 12 1 P2-A30
TOP 30 3.0570851 0.1377953 0 N 135 11 P2-A31
TOP 31 3.0964551 0.1377953 0 N 0 5 P2-A32
TOP 32 1.7972451 0.1377953 0 N 111 5 P2-B1
TOP 33 1.8366151 0.1377953 0 N 111 6 P2-B2
TOP 34 1.8759851 0.1377953 0 N 111 7 P2-B3
TOP 35 1.9153551 0.1377953 0 N 135 195 P2-B4
TOP 36 1.9547251 0.1377953 0 N 0 97 P2-B5
TOP 37 1.9940951 0.1377953 0 N 0 96 P2-B6
TOP 38 2.0334651 0.1377953 0 N 135 196 P2-B7
TOP 39 2.0728351 0.1377953 0 N 112 4 P2-B8
TOP 40 2.1122051 0.1377953 0 N 0 100 P2-B9
TOP 41 2.1515751 0.1377953 0 N 0 101 P2-B10
TOP 42 2.1909451 0.1377953 0 N 0 95 P2-B11
TOP 43 2.3090551 0.1377953 0 N 0 99 P2-B12
TOP 44 2.3484251 0.1377953 0 N 135 193 P2-B13
TOP 45 2.3877951 0.1377953 0 N 132 1 P2-B14
TOP 46 2.4271651 0.1377953 0 N 131 1 P2-B15
TOP 47 2.4665351 0.1377953 0 N 135 192 P2-B16
TOP 48 2.5059051 0.1377953 0 N 18 1 P2-B17
TOP 49 2.5452751 0.1377953 0 N 135 191 P2-B18
TOP 50 2.5846451 0.1377953 0 N 130 1 P2-B19
TOP 51 2.6240151 0.1377953 0 N 129 1 P2-B20
TOP 52 2.6633851 0.1377953 0 N 135 197 P2-B21
TOP 53 2.7027551 0.1377953 0 N 135 198 P2-B22
TOP 54 2.7421251 0.1377953 0 N 128 1 P2-B23
TOP 55 2.7814951 0.1377953 0 N 127 1 P2-B24
TOP 56 2.8208651 0.1377953 0 N 135 194 P2-B25
TOP 57 2.8602351 0.1377953 0 N 135 199 P2-B26
TOP 58 2.8996051 0.1377953 0 N 126 1 P2-B27
TOP 59 2.9389751 0.1377953 0 N 125 0 P2-B28
TOP 60 2.9783451 0.1377953 0 N 135 200 P2-B29
TOP 61 3.0177151 0.1377953 0 N 0 98 P2-B30
TOP 62 3.0570851 0.1572953 0 N 19 1 P2-B31
TOP 63 3.0964551 0.1377953 0 N 135 201 P2-B32
#
# CMP 77
CMP 2 2.6084325 1.699543 0 N P1 MOD,_FPGA,_AC7100 ;0=1,1=0.0000
PRP CATEGORY 'MOD, FPGA'
PRP DATE ''
PRP DESC 'CONN, HDR, 2X40, VERT, .05, ALIGN, SMT, TFM-1XX'
PRP MAXTEMP 'C'
PRP MFG_Name 'Panasonic'
PRP MFG_PART_NUM 'AXK680337YG'
PRP MINTEMP 'C'
PRP MODIFY_DATE '10/10/2013'
PRP OTHER ''
PRP P1 'VERT'
PRP P2 '.05'
PRP P3 'ALIGN, LOCK'
PRP SHEETPART ''
PRP SIZE 'SMT'
PRP SUB ''
PRP VALENTIUM_PART_NUM '<VALENTIUM>'
TOP 0 3.6179425 2.486293 0 N 0 26 P1-1
TOP 1 1.6529425 0.916293 0 N 0 25 P1-1
TOP 2 1.6519425 2.486293 0 N 0 24 P1-1
TOP 3 3.6179425 0.916293 0 N 0 23 P1-1
TOP 4 3.4920225 2.087353 0 N 145 25 P1-1-1
TOP 5 3.6514625 2.087353 0 N 145 29 P1-1-2
TOP 6 3.4920225 2.067663 0 N 145 26 P1-1-3
TOP 7 3.6514625 2.067663 0 N 145 30 P1-1-4
TOP 8 3.4920225 2.047983 0 N 145 27 P1-1-5
TOP 9 3.6514625 2.047983 0 N 145 31 P1-1-6
TOP 10 3.4920225 2.028293 0 N 145 28 P1-1-7
TOP 11 3.6514625 2.028293 0 N 145 32 P1-1-8
TOP 12 3.4920225 2.008613 0 N 135 105 P1-1-9
TOP 13 3.6514625 2.008613 0 N 135 112 P1-1-10
TOP 14 3.4920225 1.988923 0 N 0 273 P1-1-11
TOP 15 3.6514625 1.988923 0 N 0 275 P1-1-12
TOP 16 3.4920225 1.969243 0 N 0 272 P1-1-13
TOP 17 3.6514625 1.969243 0 N 0 274 P1-1-14
TOP 18 3.4920225 1.949553 0 N 0 263 P1-1-15
TOP 19 3.6514625 1.949553 0 N 0 276 P1-1-16
TOP 20 3.4920225 1.929873 0 N 0 265 P1-1-17
TOP 21 3.6514625 1.929873 0 N 0 279 P1-1-18
TOP 22 3.4920225 1.910183 0 N 135 106 P1-1-19
TOP 23 3.6514625 1.910183 0 N 135 113 P1-1-20
TOP 24 3.4920225 1.890503 0 N 67 0 P1-1-21
TOP 25 3.6514625 1.890503 0 N 95 0 P1-1-22
TOP 26 3.4920225 1.870813 0 N 68 0 P1-1-23
TOP 27 3.6514625 1.870813 0 N 0 280 P1-1-24
TOP 28 3.4920225 1.851133 0 N 40 0 P1-1-25
TOP 29 3.6514625 1.851133 0 N 0 278 P1-1-26
TOP 30 3.4920225 1.831443 0 N 103 0 P1-1-27
TOP 31 3.6514625 1.831443 0 N 0 277 P1-1-28
TOP 32 3.4920225 1.811763 0 N 135 107 P1-1-29
TOP 33 3.6514625 1.811763 0 N 135 114 P1-1-30
TOP 34 3.4920225 1.792073 0 N 0 281 P1-1-31
TOP 35 3.6514625 1.792073 0 N 2 0 P1-1-32
TOP 36 3.4920225 1.772393 0 N 0 283 P1-1-33
TOP 37 3.6514625 1.772393 0 N 92 0 P1-1-34
TOP 38 3.4920225 1.752703 0 N 100 1 P1-1-35
TOP 39 3.6514625 1.752703 0 N 0 267 P1-1-36
TOP 40 3.4920225 1.733023 0 N 0 250 P1-1-37
TOP 41 3.6514625 1.733023 0 N 0 268 P1-1-38
TOP 42 3.4920225 1.713333 0 N 135 108 P1-1-39
TOP 43 3.6514625 1.713333 0 N 135 115 P1-1-40
TOP 44 3.4920225 1.693653 0 N 0 269 P1-1-41
TOP 45 3.6514625 1.693653 0 N 0 271 P1-1-42
TOP 46 3.4920225 1.673963 0 N 98 1 P1-1-43
TOP 47 3.6514625 1.673963 0 N 0 266 P1-1-44
TOP 48 3.4920225 1.654283 0 N 97 1 P1-1-45
TOP 49 3.6514625 1.654283 0 N 86 0 P1-1-46
TOP 50 3.4920225 1.634593 0 N 0 270 P1-1-47
TOP 51 3.6514625 1.634593 0 N 85 0 P1-1-48
TOP 52 3.4920225 1.614913 0 N 135 109 P1-1-49
TOP 53 3.6514625 1.614913 0 N 135 116 P1-1-50
TOP 54 3.4920225 1.595223 0 N 0 247 P1-1-51
TOP 55 3.6514625 1.595223 0 N 0 262 P1-1-52
TOP 56 3.4920225 1.575543 0 N 0 248 P1-1-53
TOP 57 3.6514625 1.575543 0 N 84 0 P1-1-54
TOP 58 3.4920225 1.555853 0 N 0 264 P1-1-55
TOP 59 3.6514625 1.555853 0 N 83 0 P1-1-56
TOP 60 3.4920225 1.536173 0 N 0 261 P1-1-57
TOP 61 3.6514625 1.536173 0 N 0 249 P1-1-58
TOP 62 3.4920225 1.516483 0 N 135 110 P1-1-59
TOP 63 3.6514625 1.516483 0 N 135 117 P1-1-60
TOP 64 3.4920225 1.496803 0 N 0 282 P1-1-61
TOP 65 3.6514625 1.496803 0 N 90 0 P1-1-62
TOP 66 3.4920225 1.477113 0 N 0 284 P1-1-63
TOP 67 3.6514625 1.477113 0 N 89 0 P1-1-64
TOP 68 3.4920225 1.457433 0 N 0 285 P1-1-65
TOP 69 3.6514625 1.457433 0 N 0 260 P1-1-66
TOP 70 3.4920225 1.437743 0 N 143 1 P1-1-67
TOP 71 3.6514625 1.437743 0 N 0 259 P1-1-68
TOP 72 3.4920225 1.418063 0 N 135 111 P1-1-69
TOP 73 3.6514625 1.418063 0 N 135 118 P1-1-70
TOP 74 3.4920225 1.398373 0 N 109 1 P1-1-71
TOP 75 3.6514625 1.398373 0 N 0 258 P1-1-72
TOP 76 3.4920225 1.378693 0 N 110 1 P1-1-73
TOP 77 3.6514625 1.378693 0 N 0 257 P1-1-74
TOP 78 3.4920225 1.359003 0 N 134 1 P1-1-75
TOP 79 3.6514625 1.359003 0 N 0 256 P1-1-76
TOP 80 3.4920225 1.339323 0 N 133 1 P1-1-77
TOP 81 3.6514625 1.339323 0 N 0 255 P1-1-78
TOP 82 3.4920225 1.319633 0 N 0 254 P1-1-79
TOP 83 3.6514625 1.319633 0 N 0 253 P1-1-80
TOP 84 2.2129725 2.358813 0 N 0 233 P1-2-1
TOP 85 2.2129725 2.518253 0 N 0 236 P1-2-2
TOP 86 2.2326625 2.358813 0 N 0 234 P1-2-3
TOP 87 2.2326625 2.518253 0 N 0 235 P1-2-4
TOP 88 2.2523425 2.358813 0 N 0 213 P1-2-5
TOP 89 2.2523425 2.518253 0 N 42 0 P1-2-6
TOP 90 2.2720325 2.358813 0 N 0 212 P1-2-7
TOP 91 2.2720325 2.518253 0 N 69 0 P1-2-8
TOP 92 2.2917125 2.358813 0 N 135 132 P1-2-9
TOP 93 2.2917125 2.518253 0 N 135 125 P1-2-10
TOP 94 2.3114025 2.358813 0 N 41 4 P1-2-11
TOP 95 2.3114025 2.518253 0 N 0 211 P1-2-12
TOP 96 2.3310825 2.358813 0 N 41 5 P1-2-13
TOP 97 2.3310825 2.518253 0 N 0 210 P1-2-14
TOP 98 2.3507725 2.358813 0 N 0 238 P1-2-15
TOP 99 2.3507725 2.518253 0 N 102 0 P1-2-16
TOP 100 2.3704525 2.358813 0 N 0 237 P1-2-17
TOP 101 2.3704525 2.518253 0 N 0 230 P1-2-18
TOP 102 2.3901425 2.358813 0 N 135 131 P1-2-19
TOP 103 2.3901425 2.518253 0 N 135 124 P1-2-20
TOP 104 2.4098225 2.358813 0 N 107 3 P1-2-21
TOP 105 2.4098225 2.518253 0 N 0 232 P1-2-22
TOP 106 2.4295125 2.358813 0 N 106 3 P1-2-23
TOP 107 2.4295125 2.518253 0 N 0 231 P1-2-24
TOP 108 2.4491925 2.358813 0 N 105 3 P1-2-25
TOP 109 2.4491925 2.518253 0 N 72 2 P1-2-26
TOP 110 2.4688825 2.358813 0 N 104 1 P1-2-27
TOP 111 2.4688825 2.518253 0 N 73 2 P1-2-28
TOP 112 2.4885625 2.358813 0 N 135 130 P1-2-29
TOP 113 2.4885625 2.518253 0 N 135 123 P1-2-30
TOP 114 2.5082525 2.358813 0 N 0 239 P1-2-31
TOP 115 2.5082525 2.518253 0 N 0 229 P1-2-32
TOP 116 2.5279325 2.358813 0 N 41 3 P1-2-33
TOP 117 2.5279325 2.518253 0 N 101 0 P1-2-34
TOP 118 2.5476225 2.358813 0 N 82 0 P1-2-35
TOP 119 2.5476225 2.518253 0 N 0 227 P1-2-36
TOP 120 2.5673025 2.358813 0 N 81 2 P1-2-37
TOP 121 2.5673025 2.518253 0 N 0 225 P1-2-38
TOP 122 2.5869925 2.358813 0 N 135 129 P1-2-39
TOP 123 2.5869925 2.518253 0 N 135 122 P1-2-40
TOP 124 2.6066725 2.358813 0 N 75 2 P1-2-41
TOP 125 2.6066725 2.518253 0 N 0 228 P1-2-42
TOP 126 2.6263625 2.358813 0 N 74 0 P1-2-43
TOP 127 2.6263625 2.518253 0 N 0 226 P1-2-44
TOP 128 2.6460425 2.358813 0 N 79 1 P1-2-45
TOP 129 2.6460425 2.518253 0 N 0 222 P1-2-46
TOP 130 2.6657325 2.358813 0 N 78 0 P1-2-47
TOP 131 2.6657325 2.518253 0 N 0 221 P1-2-48
TOP 132 2.6854125 2.358813 0 N 135 128 P1-2-49
TOP 133 2.6854125 2.518253 0 N 135 121 P1-2-50
TOP 134 2.7051025 2.358813 0 N 77 0 P1-2-51
TOP 135 2.7051025 2.518253 0 N 0 224 P1-2-52
TOP 136 2.7247825 2.358813 0 N 76 0 P1-2-53
TOP 137 2.7247825 2.518253 0 N 0 223 P1-2-54
TOP 138 2.7444725 2.358813 0 N 0 241 P1-2-55
TOP 139 2.7444725 2.518253 0 N 0 219 P1-2-56
TOP 140 2.7641525 2.358813 0 N 0 240 P1-2-57
TOP 141 2.7641525 2.518253 0 N 0 218 P1-2-58
TOP 142 2.7838425 2.358813 0 N 135 127 P1-2-59
TOP 143 2.7838425 2.518253 0 N 135 120 P1-2-60
TOP 144 2.8035225 2.358813 0 N 38 0 P1-2-61
TOP 145 2.8035225 2.518253 0 N 0 220 P1-2-62
TOP 146 2.8232125 2.358813 0 N 0 242 P1-2-63
TOP 147 2.8232125 2.518253 0 N 37 0 P1-2-64
TOP 148 2.8428925 2.358813 0 N 0 243 P1-2-65
TOP 149 2.8428925 2.518253 0 N 0 217 P1-2-66
TOP 150 2.8625825 2.358813 0 N 39 0 P1-2-67
TOP 151 2.8625825 2.518253 0 N 0 216 P1-2-68
TOP 152 2.8822625 2.358813 0 N 135 126 P1-2-69
TOP 153 2.8822625 2.518253 0 N 135 119 P1-2-70
TOP 154 2.9019525 2.358813 0 N 139 2 P1-2-71
TOP 155 2.9019525 2.518253 0 N 71 0 P1-2-72
TOP 156 2.9216325 2.358813 0 N 0 244 P1-2-73
TOP 157 2.9216325 2.518253 0 N 70 0 P1-2-74
TOP 158 2.9413225 2.358813 0 N 0 245 P1-2-75
TOP 159 2.9413225 2.518253 0 N 0 215 P1-2-76
TOP 160 2.9610025 2.358813 0 N 138 2 P1-2-77
TOP 161 2.9610025 2.518253 0 N 0 214 P1-2-78
TOP 162 2.9806925 2.358813 0 N 3 1 P1-2-79
TOP 163 2.9806925 2.518253 0 N 1 1 P1-2-80
TOP 164 1.7765525 1.319673 0 N 99 2 P1-3-1
TOP 165 1.6171125 1.319673 0 N 96 1 P1-3-2
TOP 166 1.7765525 1.339363 0 N 0 177 P1-3-3
TOP 167 1.6171125 1.339363 0 N 0 164 P1-3-4
TOP 168 1.7765525 1.359043 0 N 0 165 P1-3-5
TOP 169 1.6171125 1.359043 0 N 0 178 P1-3-6
TOP 170 1.7765525 1.378733 0 N 0 161 P1-3-7
TOP 171 1.6171125 1.378733 0 N 0 169 P1-3-8
TOP 172 1.7765525 1.398413 0 N 135 133 P1-3-9
TOP 173 1.6171125 1.398413 0 N 135 140 P1-3-10
TOP 174 1.7765525 1.418103 0 N 0 160 P1-3-11
TOP 175 1.6171125 1.418103 0 N 0 167 P1-3-12
TOP 176 1.7765525 1.437783 0 N 0 179 P1-3-13
TOP 177 1.6171125 1.437783 0 N 0 175 P1-3-14
TOP 178 1.7765525 1.457473 0 N 0 195 P1-3-15
TOP 179 1.6171125 1.457473 0 N 0 182 P1-3-16
TOP 180 1.7765525 1.477153 0 N 0 159 P1-3-17
TOP 181 1.6171125 1.477153 0 N 0 168 P1-3-18
TOP 182 1.7765525 1.496843 0 N 135 134 P1-3-19
TOP 183 1.6171125 1.496843 0 N 135 141 P1-3-20
TOP 184 1.7765525 1.516523 0 N 124 2 P1-3-21
TOP 185 1.6171125 1.516523 0 N 0 183 P1-3-22
TOP 186 1.7765525 1.536213 0 N 144 1 P1-3-23
TOP 187 1.6171125 1.536213 0 N 0 174 P1-3-24
TOP 188 1.7765525 1.555893 0 N 0 185 P1-3-25
TOP 189 1.6171125 1.555893 0 N 0 173 P1-3-26
TOP 190 1.7765525 1.575583 0 N 0 184 P1-3-27
TOP 191 1.6171125 1.575583 0 N 0 176 P1-3-28
TOP 192 1.7765525 1.595263 0 N 135 135 P1-3-29
TOP 193 1.6171125 1.595263 0 N 135 142 P1-3-30
TOP 194 1.7765525 1.614953 0 N 88 0 P1-3-31
TOP 195 1.6171125 1.614953 0 N 0 172 P1-3-32
TOP 196 1.7765525 1.634633 0 N 0 209 P1-3-33
TOP 197 1.6171125 1.634633 0 N 0 163 P1-3-34
TOP 198 1.7765525 1.654323 0 N 0 190 P1-3-35
TOP 199 1.6171125 1.654323 0 N 0 157 P1-3-36
TOP 200 1.7765525 1.674003 0 N 87 0 P1-3-37
TOP 201 1.6171125 1.674003 0 N 0 170 P1-3-38
TOP 202 1.7765525 1.693693 0 N 135 136 P1-3-39
TOP 203 1.6171125 1.693693 0 N 135 143 P1-3-40
TOP 204 1.7765525 1.713373 0 N 0 187 P1-3-41
TOP 205 1.6171125 1.713373 0 N 0 158 P1-3-42
TOP 206 1.7765525 1.733063 0 N 0 203 P1-3-43
TOP 207 1.6171125 1.733063 0 N 0 171 P1-3-44
TOP 208 1.7765525 1.752743 0 N 0 188 P1-3-45
TOP 209 1.6171125 1.752743 0 N 0 166 P1-3-46
TOP 210 1.7765525 1.772433 0 N 0 202 P1-3-47
TOP 211 1.6171125 1.772433 0 N 0 162 P1-3-48
TOP 212 1.7765525 1.792113 0 N 135 137 P1-3-49
TOP 213 1.6171125 1.792113 0 N 135 144 P1-3-50
TOP 214 1.7765525 1.811803 0 N 94 0 P1-3-51
TOP 215 1.6171125 1.811803 0 N 0 181 P1-3-52
TOP 216 1.7765525 1.831483 0 N 0 205 P1-3-53
TOP 217 1.6171125 1.831483 0 N 0 180 P1-3-54
TOP 218 1.7765525 1.851173 0 N 0 191 P1-3-55
TOP 219 1.6171125 1.851173 0 N 0 200 P1-3-56
TOP 220 1.7765525 1.870853 0 N 0 208 P1-3-57
TOP 221 1.6171125 1.870853 0 N 0 194 P1-3-58
TOP 222 1.7765525 1.890543 0 N 135 138 P1-3-59
TOP 223 1.6171125 1.890543 0 N 135 145 P1-3-60
TOP 224 1.7765525 1.910223 0 N 0 206 P1-3-61
TOP 225 1.6171125 1.910223 0 N 0 199 P1-3-62
TOP 226 1.7765525 1.929913 0 N 0 192 P1-3-63
TOP 227 1.6171125 1.929913 0 N 0 201 P1-3-64
TOP 228 1.7765525 1.949593 0 N 0 204 P1-3-65
TOP 229 1.6171125 1.949593 0 N 0 186 P1-3-66
TOP 230 1.7765525 1.969283 0 N 0 196 P1-3-67
TOP 231 1.6171125 1.969283 0 N 0 193 P1-3-68
TOP 232 1.7765525 1.988963 0 N 135 139 P1-3-69
TOP 233 1.6171125 1.988963 0 N 135 146 P1-3-70
TOP 234 1.7765525 2.008653 0 N 0 197 P1-3-71
TOP 235 1.6171125 2.008653 0 N 0 189 P1-3-72
TOP 236 1.7765525 2.028333 0 N 0 207 P1-3-73
TOP 237 1.6171125 2.028333 0 N 0 198 P1-3-74
TOP 238 1.7765525 2.048023 0 N 0 155 P1-3-75
TOP 239 1.6171125 2.048023 0 N 0 156 P1-3-76
TOP 240 1.7765525 2.067703 0 N 141 2 P1-3-77
TOP 241 1.6171125 2.067703 0 N 146 0 P1-3-78
TOP 242 1.7765525 2.087393 0 N 140 2 P1-3-79
TOP 243 1.6171125 2.087393 0 N 136 2 P1-3-80
TOP 244 2.9807025 1.038313 0 N 0 113 P1-4-1
TOP 245 2.9807025 0.878873 0 N 0 114 P1-4-2
TOP 246 2.9610125 1.038313 0 N 0 112 P1-4-3
TOP 247 2.9610125 0.878873 0 N 0 111 P1-4-4
TOP 248 2.9413325 1.038313 0 N 0 115 P1-4-5
TOP 249 2.9413325 0.878873 0 N 0 116 P1-4-6
TOP 250 2.9216425 1.038313 0 N 0 117 P1-4-7
TOP 251 2.9216425 0.878873 0 N 0 118 P1-4-8
TOP 252 2.9019625 1.038313 0 N 135 147 P1-4-9
TOP 253 2.9019625 0.878873 0 N 135 156 P1-4-10
TOP 254 2.8822725 1.038313 0 N 0 119 P1-4-11
TOP 255 2.8822725 0.878873 0 N 117 0 P1-4-12
TOP 256 2.8625925 1.038313 0 N 0 120 P1-4-13
TOP 257 2.8625925 0.878873 0 N 116 0 P1-4-14
TOP 258 2.8429025 1.038313 0 N 135 148 P1-4-15
TOP 259 2.8429025 0.878873 0 N 0 110 P1-4-16
TOP 260 2.8232225 1.038313 0 N 115 1 P1-4-17
TOP 261 2.8232225 0.878873 0 N 128 0 P1-4-18
TOP 262 2.8035325 1.038313 0 N 114 1 P1-4-19
TOP 263 2.8035325 0.878873 0 N 127 0 P1-4-20
TOP 264 2.7838525 1.038313 0 N 135 149 P1-4-21
TOP 265 2.7838525 0.878873 0 N 0 109 P1-4-22
TOP 266 2.7641625 1.038313 0 N 126 0 P1-4-23
TOP 267 2.7641625 0.878873 0 N 119 0 P1-4-24
TOP 268 2.7444825 1.038313 0 N 125 1 P1-4-25
TOP 269 2.7444825 0.878873 0 N 118 0 P1-4-26
TOP 270 2.7247925 1.038313 0 N 135 150 P1-4-27
TOP 271 2.7247925 0.878873 0 N 0 108 P1-4-28
TOP 272 2.7051125 1.038313 0 N 121 0 P1-4-29
TOP 273 2.7051125 0.878873 0 N 130 0 P1-4-30
TOP 274 2.6854225 1.038313 0 N 120 0 P1-4-31
TOP 275 2.6854225 0.878873 0 N 129 0 P1-4-32
TOP 276 2.6657425 1.038313 0 N 135 151 P1-4-33
TOP 277 2.6657425 0.878873 0 N 0 107 P1-4-34
TOP 278 2.6460525 1.038313 0 N 132 0 P1-4-35
TOP 279 2.6460525 0.878873 0 N 122 0 P1-4-36
TOP 280 2.6263725 1.038313 0 N 131 0 P1-4-37
TOP 281 2.6263725 0.878873 0 N 123 0 P1-4-38
TOP 282 2.6066825 1.038313 0 N 135 152 P1-4-39
TOP 283 2.6066825 0.878873 0 N 135 157 P1-4-40
TOP 284 2.5870025 1.038313 0 N 0 151 P1-4-41
TOP 285 2.5870025 0.878873 0 N 0 152 P1-4-42
TOP 286 2.5673125 1.038313 0 N 0 135 P1-4-43
TOP 287 2.5673125 0.878873 0 N 0 140 P1-4-44
TOP 288 2.5476325 1.038313 0 N 0 122 P1-4-45
TOP 289 2.5476325 0.878873 0 N 0 141 P1-4-46
TOP 290 2.5279425 1.038313 0 N 0 121 P1-4-47
TOP 291 2.5279425 0.878873 0 N 0 142 P1-4-48
TOP 292 2.5082625 1.038313 0 N 135 153 P1-4-49
TOP 293 2.5082625 0.878873 0 N 135 158 P1-4-50
TOP 294 2.4885725 1.038313 0 N 0 130 P1-4-51
TOP 295 2.4885725 0.878873 0 N 0 143 P1-4-52
TOP 296 2.4688925 1.038313 0 N 0 131 P1-4-53
TOP 297 2.4688925 0.878873 0 N 0 138 P1-4-54
TOP 298 2.4492025 1.038313 0 N 0 129 P1-4-55
TOP 299 2.4492025 0.878873 0 N 0 139 P1-4-56
TOP 300 2.4295225 1.038313 0 N 0 132 P1-4-57
TOP 301 2.4295225 0.878873 0 N 0 149 P1-4-58
TOP 302 2.4098325 1.038313 0 N 135 154 P1-4-59
TOP 303 2.4098325 0.878873 0 N 135 159 P1-4-60
TOP 304 2.3901525 1.038313 0 N 0 133 P1-4-61
TOP 305 2.3901525 0.878873 0 N 0 144 P1-4-62
TOP 306 2.3704625 1.038313 0 N 0 134 P1-4-63
TOP 307 2.3704625 0.878873 0 N 0 148 P1-4-64
TOP 308 2.3507825 1.038313 0 N 0 124 P1-4-65
TOP 309 2.3507825 0.878873 0 N 0 147 P1-4-66
TOP 310 2.3310925 1.038313 0 N 0 123 P1-4-67
TOP 311 2.3310925 0.878873 0 N 0 146 P1-4-68
TOP 312 2.3114125 1.038313 0 N 135 155 P1-4-69
TOP 313 2.3114125 0.878873 0 N 135 160 P1-4-70
TOP 314 2.2917225 1.038313 0 N 0 128 P1-4-71
TOP 315 2.2917225 0.878873 0 N 0 145 P1-4-72
TOP 316 2.2720425 1.038313 0 N 0 127 P1-4-73
TOP 317 2.2720425 0.878873 0 N 0 136 P1-4-74
TOP 318 2.2523525 1.038313 0 N 0 126 P1-4-75
TOP 319 2.2523525 0.878873 0 N 0 137 P1-4-76
TOP 320 2.2326725 1.038313 0 N 0 125 P1-4-77
TOP 321 2.2326725 0.878873 0 N 0 150 P1-4-78
TOP 322 2.2129825 1.038313 0 N 0 103 P1-4-79
TOP 323 2.2129825 0.878873 0 N 0 104 P1-4-80
TOP 324 3.5717425 2.131643 0 N 0 252 P1-81
TOP 325 2.1686825 2.438533 0 N 0 246 P1-81
TOP 326 1.6968325 1.275383 0 N 0 154 P1-81
TOP 327 3.0249925 0.958593 0 N 0 105 P1-81
TOP 328 3.5717425 2.097193 0 N 0 22 P1-82
TOP 329 2.2031325 2.438533 0 N 0 20 P1-82
TOP 330 1.6968325 1.309833 0 N 0 19 P1-82
TOP 331 2.9905425 0.958593 0 N 0 16 P1-82
TOP 332 3.5717425 1.309793 0 N 0 21 P1-83
TOP 333 1.6968325 2.097233 0 N 0 18 P1-83
TOP 334 2.2031425 0.958593 0 N 0 17 P1-83
TOP 335 2.9905325 2.438533 0 N 0 15 P1-83
TOP 336 3.5717425 1.275343 0 N 0 251 P1-84
TOP 337 1.6968325 2.131683 0 N 0 153 P1-84
TOP 338 2.1686925 0.958593 0 N 0 106 P1-84
TOP 339 3.0249825 2.438533 0 N 0 102 P1-84
#
# CMP 78
CMP 13 6.6798425 2.611063 90 N L2 PM124SH-100M-RC ;0=1,1=0.0000
PRP CATEGORY 'IND, PWR'
PRP DATE '10/23/2013'
PRP DESC 'IND, PWR, 10.uH, 20%, 4A, 0.04DCR, 12.5X12.5MM, SHLD'
PRP MAXTEMP '125C'
PRP MFG_Name 'BOURNS'
PRP MFG_PART_NUM 'PM124SH-100M-RC'
PRP MINTEMP '-40C'
PRP MODIFY_DATE '10/23/2013'
PRP OTHER 'SHLD'
PRP P1 '20%'
PRP P2 '4A'
PRP P3 '36mOhm'
PRP SHEETPART ''
PRP SIZE '12.5X12.5MM'
PRP SUB ''
PRP Supplier_1 'Digi-Key'
PRP Supplier_Part_Number_1 'PM124SH-100M-RCCT-ND'
PRP VALENTIUM_PART_NUM '<VALENTIUM>'
PRP VALUE '10.uH'
TOP 0 6.6798425 2.8020079 90 N 137 29 L2-1
TOP 1 6.6798425 2.4201181 90 N 65 1 L2-2
#
# CMP 79
CMP 13 6.3198425 1.651063 270 N L1 PM124SH-100M-RC ;0=1,1=0.0000
PRP CATEGORY 'IND, PWR'
PRP DATE '10/23/2013'
PRP DESC 'IND, PWR, 10.uH, 20%, 4A, 0.04DCR, 12.5X12.5MM, SHLD'
PRP MAXTEMP '125C'
PRP MFG_Name 'BOURNS'
PRP MFG_PART_NUM 'PM124SH-100M-RC'
PRP MINTEMP '-40C'
PRP MODIFY_DATE '10/23/2013'
PRP OTHER 'SHLD'
PRP P1 '20%'
PRP P2 '4A'
PRP P3 '36mOhm'
PRP SHEETPART ''
PRP SIZE '12.5X12.5MM'
PRP SUB ''
PRP Supplier_1 'Digi-Key'
PRP Supplier_Part_Number_1 'PM124SH-100M-RCCT-ND'
PRP VALENTIUM_PART_NUM '<VALENTIUM>'
PRP VALUE '10.uH'
TOP 0 6.3198425 1.4601181 270 N 145 12 L1-1
TOP 1 6.3198425 1.8420079 270 N 63 1 L1-2
#
# CMP 80
CMP 35 3.9344488 4.0237008 180 N J3 USB_B_1734035 ;0=1,1=0.1575
PRP CATEGORY 'CONN, REC'
PRP DATE ''
PRP DESC 'CONN, REC, USB, R/A, MINI, TYPE B, 5 POS, SMT W/BRD GUIDE'
PRP MAXTEMP 'C'
PRP MFG_Name 'TE CONNECTIVITY/AMP'
PRP MFG_PART_NUM '1734035-2'
PRP MINTEMP 'C'
PRP MODIFY_DATE '10/10/2013'
PRP OTHER 'USB'
PRP P1 'R/A'
PRP P2 '5 POS'
PRP P3 'USB MINI B'
PRP SHEETPART ''
PRP SIZE 'SMT'
PRP SUB ''
PRP Supplier_1 'Digi-Key'
PRP Supplier_Part_Number_1 'A31727CT-ND'
PRP VALENTIUM_PART_NUM '<VALENTIUM>'
PRP VALUE 'USB MINI B'
TOP 0 3.9580709 4.126063 180 N 0 10 J3-0
TOP 1 3.7848425 4.126063 180 N 0 11 J3-0
TOP 2 4.0466536 4.2441732 180 N 0 62 J3-0
TOP 3 4.0466536 4.0276378 180 N 0 63 J3-0
TOP 4 3.6962598 4.0276378 180 N 0 64 J3-0
TOP 5 3.6962598 4.2441732 180 N 0 65 J3-0
TOP 6 3.9344488 4.0237008 180 N 0 66 J3-1
TOP 7 3.9029528 4.0237008 180 N 46 1 J3-2
TOP 8 3.8714567 4.0237008 180 N 45 1 J3-3
TOP 9 3.8399606 4.0237008 180 N 0 67 J3-4
TOP 10 3.8084646 4.0237008 180 N 135 178 J3-5
#
# CMP 81
CMP 0 6.5694882 3.5895276 180 N J2 39-30-1060 ;0=2,1=0.0000
PRP CATEGORY 'CONN, HDR'
PRP DATE ''
PRP DESC 'CONN, HDR, 2X3, R/A, 2.5MM, TH, NANO-FIT'
PRP MAXTEMP '105C'
PRP MFG_Name 'MOLEX'
PRP MFG_PART_NUM '105314-1206'
PRP MINTEMP '-40C'
PRP MODIFY_DATE '10/10/2013'
PRP OTHER 'NANO-FIT'
PRP P1 'R/A'
PRP P2 '2.5MM'
PRP P3 ''
PRP SHEETPART ''
PRP SIZE 'TH'
PRP SUB ''
PRP Supplier_1 'Digi-Key'
PRP Supplier_Part_Number_1 'WM14977-ND'
PRP VALENTIUM_PART_NUM '<VALENTIUM>'
PRP VALUE '2X3'
TOP 0 6.9001969 4.0934646 180 N 0 6 J2-0
TOP 1 6.5694882 4.0934646 180 N 0 7 J2-0
TOP 2 6.5694882 3.806063 90 N 52 3 J2-1
TOP 3 6.7348425 3.806063 90 N 52 1 J2-2
TOP 4 6.9001969 3.806063 90 N 52 2 J2-3
TOP 5 6.5694882 3.5895276 90 N 135 31 J2-4
TOP 6 6.7348425 3.5895276 90 N 135 30 J2-5
TOP 7 6.9001969 3.5895276 90 N 135 29 J2-6
#
# CMP 82
CMP 8 6.1198425 3.8198425 270 N J1 PJ-002A ;0=2,1=0.0000
PRP CATEGORY 'CONN, JACK'
PRP DESC 'CONN, JACK, PJ-002A, 2.1X5.5MM, 24V 2.5A, R/A TH, SPST-NC'
PRP MAXTEMP '85C'
PRP MFG_Name 'CUI DEVICES'
PRP MFG_PART_NUM 'PJ-002A'
PRP MINTEMP '-25C'
PRP MODIFY_DATE ''
PRP OTHER 'SPST-NC'
PRP P1 '2.1X5.5MM'
PRP P2 '24V'
PRP P3 '2.5A'
PRP SHEETPART ''
PRP SIZE 'R/A TH'
PRP SUB ''
PRP Supplier_1 'Digi-Key'
PRP Supplier_Part_Number_1 'CP-002A-ND'
PRP VALENTIUM_PART_NUM '<VALENTIUM>'
PRP VALUE 'PJ-002A'
TOP 0 6.1198425 3.8198425 180 N 54 0 J1-1
TOP 1 6.1198425 4.056063 180 N 135 37 J1-2
TOP 2 5.9348031 3.9379527 90 N 135 36 J1-3
#
# CMP 83
CMP 14 4.1498425 2.816063 270 N FB3 MPZ1608_220OHM_0603 ;0=1,1=0.0374
PRP CATEGORY 'FERRITE'
PRP DATE '8/6/2013'
PRP DESC 'FER, 220 OHM, 100MHZ, 2.2A, 0.05OHM DC, MPZ1608, 0603'
PRP MAXTEMP '125C'
PRP MFG_Name 'TDK CORP'
PRP MFG_PART_NUM 'MPZ1608S221ATA00'
PRP MINTEMP '-55C'
PRP MODIFY_DATE '9/4/2013'
PRP OTHER 'MPZ1608'
PRP P1 '100MHZ'
PRP P2 '2.2A'
PRP P3 '0.05 OHM'
PRP SHEETPART ''
PRP SIZE '0603'
PRP SUB ''
PRP Supplier_1 'Digi-Key'
PRP Supplier_Part_Number_1 '445-1565-1-ND'
PRP VALENTIUM_PART_NUM '<VALENTIUM>'
PRP VALUE '220 OHM'
TOP 0 4.1498425 2.7898819 180 N 13 3 FB3-1
TOP 1 4.1498425 2.8422441 180 N 108 16 FB3-2
#
# CMP 84
CMP 14 4.4348425 2.816063 270 N FB2 MPZ1608_220OHM_0603 ;0=1,1=0.0374
PRP CATEGORY 'FERRITE'
PRP DATE '8/6/2013'
PRP DESC 'FER, 220 OHM, 100MHZ, 2.2A, 0.05OHM DC, MPZ1608, 0603'
PRP MAXTEMP '125C'
PRP MFG_Name 'TDK CORP'
PRP MFG_PART_NUM 'MPZ1608S221ATA00'
PRP MINTEMP '-55C'
PRP MODIFY_DATE '9/4/2013'
PRP OTHER 'MPZ1608'
PRP P1 '100MHZ'
PRP P2 '2.2A'
PRP P3 '0.05 OHM'
PRP SHEETPART ''
PRP SIZE '0603'
PRP SUB ''
PRP Supplier_1 'Digi-Key'
PRP Supplier_Part_Number_1 '445-1565-1-ND'
PRP VALENTIUM_PART_NUM '<VALENTIUM>'
PRP VALUE '220 OHM'
TOP 0 4.4348425 2.7898819 180 N 137 9 FB2-1
TOP 1 4.4348425 2.8422441 180 N 13 1 FB2-2
#
# CMP 85
CMP 12 6.0628425 3.556063 180 N F1 FUSE_0603_2.00A ;0=1,1=0.0197
PRP CATEGORY 'FUSE'
PRP DATE '20 OCT 15'
PRP DESC 'FUSE SLOW 1.25A 32V M 0603'
PRP MAXTEMP '105C'
PRP MFG_Name 'BOURNS'
PRP MFG_PART_NUM 'SF-0603S200-2'
PRP MINTEMP '-40C'
PRP MODIFY_DATE '9/4/2013'
PRP OTHER 'UL E141069'
PRP P1 'SLOW BLO'
PRP P2 '32V'
PRP P3 'M'
PRP SHEETPART ''
PRP SIZE '0603'
PRP SUB ''
PRP Supplier_1 'Digi-Key'
PRP Supplier_Part_Number_1 'SF-0603S200-2CT-ND'
PRP VALENTIUM_PART_NUM '<VALENTIUM>'
PRP VALUE '2.00A'
TOP 0 6.0900079 3.556063 90 N 53 2 F1-1
TOP 1 6.0356772 3.556063 90 N 142 9 F1-2
#
# CMP 86
CMP 10 1.0448425 0.906063 180 N D18 SMCJ6.5CA ;0=1,1=0.1031
PRP CATEGORY 'DIO, TVS'
PRP DATE ''
PRP DESC 'DIO, TVS, SMCJ6.5, 6.5V, BIDIR, 1.5KW, SMC'
PRP MAXTEMP '150C'
PRP MFG_Name 'LITTELFUSE'
PRP MFG_PART_NUM 'SMCJ6.5CA'
PRP MINTEMP '-55C'
PRP MODIFY_DATE '9/4/2013'
PRP OTHER 'SMCJ'
PRP P1 '6.5V'
PRP P2 'BIDIR'
PRP P3 '1.5KW'
PRP SHEETPART ''
PRP SIZE 'SMC'
PRP SUB ''
PRP Supplier_1 'Digi-Key'
PRP Supplier_Part_Number_1 'SMCJ6.5CALFCT-ND'
PRP VALENTIUM_PART_NUM '<VALENTIUM>'
PRP VALUE 'SMCJ6.5'
TOP 0 0.9326378 0.906063 90 N 104 2 D18-A
TOP 1 1.1570472 0.906063 90 N 135 164 D18-K
#
# CMP 87
CMP 10 1.0448425 1.431063 180 N D17 SMCJ6.5CA ;0=1,1=0.1031
PRP CATEGORY 'DIO, TVS'
PRP DATE ''
PRP DESC 'DIO, TVS, SMCJ6.5, 6.5V, BIDIR, 1.5KW, SMC'
PRP MAXTEMP '150C'
PRP MFG_Name 'LITTELFUSE'
PRP MFG_PART_NUM 'SMCJ6.5CA'
PRP MINTEMP '-55C'
PRP MODIFY_DATE '9/4/2013'
PRP OTHER 'SMCJ'
PRP P1 '6.5V'
PRP P2 'BIDIR'
PRP P3 '1.5KW'
PRP SHEETPART ''
PRP SIZE 'SMC'
PRP SUB ''
PRP Supplier_1 'Digi-Key'
PRP Supplier_Part_Number_1 'SMCJ6.5CALFCT-ND'
PRP VALENTIUM_PART_NUM '<VALENTIUM>'
PRP VALUE 'SMCJ6.5'
TOP 0 0.9326378 1.431063 90 N 105 1 D17-A
TOP 1 1.1570472 1.431063 90 N 135 63 D17-K
#
# CMP 88
CMP 10 1.0448425 2.481063 180 N D16 SMCJ6.5CA ;0=1,1=0.1031
PRP CATEGORY 'DIO, TVS'
PRP DATE ''
PRP DESC 'DIO, TVS, SMCJ6.5, 6.5V, BIDIR, 1.5KW, SMC'
PRP MAXTEMP '150C'
PRP MFG_Name 'LITTELFUSE'
PRP MFG_PART_NUM 'SMCJ6.5CA'
PRP MINTEMP '-55C'
PRP MODIFY_DATE '9/4/2013'
PRP OTHER 'SMCJ'
PRP P1 '6.5V'
PRP P2 'BIDIR'
PRP P3 '1.5KW'
PRP SHEETPART ''
PRP SIZE 'SMC'
PRP SUB ''
PRP Supplier_1 'Digi-Key'
PRP Supplier_Part_Number_1 'SMCJ6.5CALFCT-ND'
PRP VALENTIUM_PART_NUM '<VALENTIUM>'
PRP VALUE 'SMCJ6.5'
TOP 0 0.9326378 2.481063 90 N 107 1 D16-A
TOP 1 1.1570472 2.481063 90 N 135 64 D16-K
#
# CMP 89
CMP 10 1.0448425 1.956063 180 N D15 SMCJ6.5CA ;0=1,1=0.1031
PRP CATEGORY 'DIO, TVS'
PRP DATE ''
PRP DESC 'DIO, TVS, SMCJ6.5, 6.5V, BIDIR, 1.5KW, SMC'
PRP MAXTEMP '150C'
PRP MFG_Name 'LITTELFUSE'
PRP MFG_PART_NUM 'SMCJ6.5CA'
PRP MINTEMP '-55C'
PRP MODIFY_DATE '9/4/2013'
PRP OTHER 'SMCJ'
PRP P1 '6.5V'
PRP P2 'BIDIR'
PRP P3 '1.5KW'
PRP SHEETPART ''
PRP SIZE 'SMC'
PRP SUB ''
PRP Supplier_1 'Digi-Key'
PRP Supplier_Part_Number_1 'SMCJ6.5CALFCT-ND'
PRP VALENTIUM_PART_NUM '<VALENTIUM>'
PRP VALUE 'SMCJ6.5'
TOP 0 0.9326378 1.956063 90 N 106 1 D15-A
TOP 1 1.1570472 1.956063 90 N 135 65 D15-K
#
# CMP 90
CMP 9 1.2498423 4.226063 270 N D14 RED ;0=1,1=0.0236
PRP CATEGORY 'LED'
PRP DATE ''
PRP DESC 'LED, RED, SML-LX0603, 635NM, 2V, 20MA, 0603'
PRP MAXTEMP '85C'
PRP MFG_Name 'LUMEX'
PRP MFG_PART_NUM 'SML-LX0603IW-TR'
PRP MINTEMP '-25C'
PRP MODIFY_DATE '9/4/2013'
PRP OTHER 'SML-LX0603'
PRP P1 '635NM'
PRP P2 '2V'
PRP P3 '20MA'
PRP SHEETPART ''
PRP SIZE '0603'
PRP SUB ''
PRP Supplier_1 'Digi-Key'
PRP Supplier_Part_Number_1 '67-1548-1-ND'
PRP VALENTIUM_PART_NUM '<VALENTIUM>'
PRP VALUE 'RED'
TOP 0 1.2498423 4.1975197 180 N 47 1 D14-1
TOP 1 1.2498423 4.2546063 180 N 137 28 D14-2
#
# CMP 91
CMP 9 1.0481757 4.226063 270 N D13 RED ;0=1,1=0.0236
PRP CATEGORY 'LED'
PRP DATE ''
PRP DESC 'LED, RED, SML-LX0603, 635NM, 2V, 20MA, 0603'
PRP MAXTEMP '85C'
PRP MFG_Name 'LUMEX'
PRP MFG_PART_NUM 'SML-LX0603IW-TR'
PRP MINTEMP '-25C'
PRP MODIFY_DATE '9/4/2013'
PRP OTHER 'SML-LX0603'
PRP P1 '635NM'
PRP P2 '2V'
PRP P3 '20MA'
PRP SHEETPART ''
PRP SIZE '0603'
PRP SUB ''
PRP Supplier_1 'Digi-Key'
PRP Supplier_Part_Number_1 '67-1548-1-ND'
PRP VALENTIUM_PART_NUM '<VALENTIUM>'
PRP VALUE 'RED'
TOP 0 1.0481757 4.1975197 180 N 48 1 D13-1
TOP 1 1.0481757 4.2546063 180 N 137 10 D13-2
#
# CMP 92
CMP 9 0.8465091 4.226063 270 N D12 RED ;0=1,1=0.0236
PRP CATEGORY 'LED'
PRP DATE ''
PRP DESC 'LED, RED, SML-LX0603, 635NM, 2V, 20MA, 0603'
PRP MAXTEMP '85C'
PRP MFG_Name 'LUMEX'
PRP MFG_PART_NUM 'SML-LX0603IW-TR'
PRP MINTEMP '-25C'
PRP MODIFY_DATE '9/4/2013'
PRP OTHER 'SML-LX0603'
PRP P1 '635NM'
PRP P2 '2V'
PRP P3 '20MA'
PRP SHEETPART ''
PRP SIZE '0603'
PRP SUB ''
PRP Supplier_1 'Digi-Key'
PRP Supplier_Part_Number_1 '67-1548-1-ND'
PRP VALENTIUM_PART_NUM '<VALENTIUM>'
PRP VALUE 'RED'
TOP 0 0.8465091 4.1975197 180 N 17 1 D12-1
TOP 1 0.8465091 4.2546063 180 N 137 11 D12-2
#
# CMP 93
CMP 9 0.6448425 4.226063 270 N D11 RED ;0=1,1=0.0236
PRP CATEGORY 'LED'
PRP DATE ''
PRP DESC 'LED, RED, SML-LX0603, 635NM, 2V, 20MA, 0603'
PRP MAXTEMP '85C'
PRP MFG_Name 'LUMEX'
PRP MFG_PART_NUM 'SML-LX0603IW-TR'
PRP MINTEMP '-25C'
PRP MODIFY_DATE '9/4/2013'
PRP OTHER 'SML-LX0603'
PRP P1 '635NM'
PRP P2 '2V'
PRP P3 '20MA'
PRP SHEETPART ''
PRP SIZE '0603'
PRP SUB ''
PRP Supplier_1 'Digi-Key'
PRP Supplier_Part_Number_1 '67-1548-1-ND'
PRP VALENTIUM_PART_NUM '<VALENTIUM>'
PRP VALUE 'RED'
TOP 0 0.6448425 4.1975197 180 N 16 1 D11-1
TOP 1 0.6448425 4.2546063 180 N 137 12 D11-2
#
# CMP 94
CMP 9 3.5898425 3.756063 270 N D10 RED ;0=1,1=0.0236
PRP CATEGORY 'LED'
PRP DATE ''
PRP DESC 'LED, RED, SML-LX0603, 635NM, 2V, 20MA, 0603'
PRP MAXTEMP '85C'
PRP MFG_Name 'LUMEX'
PRP MFG_PART_NUM 'SML-LX0603IW-TR'
PRP MINTEMP '-25C'
PRP MODIFY_DATE '9/4/2013'
PRP OTHER 'SML-LX0603'
PRP P1 '635NM'
PRP P2 '2V'
PRP P3 '20MA'
PRP SHEETPART ''
PRP SIZE '0603'
PRP SUB ''
PRP Supplier_1 'Digi-Key'
PRP Supplier_Part_Number_1 '67-1548-1-ND'
PRP VALENTIUM_PART_NUM '<VALENTIUM>'
PRP VALUE 'RED'
TOP 0 3.5898425 3.7275197 180 N 49 1 D10-1
TOP 1 3.5898425 3.7846063 180 N 137 13 D10-2
#
# CMP 95
CMP 9 3.5898425 3.881063 90 N D9 RED ;0=1,1=0.0236
PRP CATEGORY 'LED'
PRP DATE ''
PRP DESC 'LED, RED, SML-LX0603, 635NM, 2V, 20MA, 0603'
PRP MAXTEMP '85C'
PRP MFG_Name 'LUMEX'
PRP MFG_PART_NUM 'SML-LX0603IW-TR'
PRP MINTEMP '-25C'
PRP MODIFY_DATE '9/4/2013'
PRP OTHER 'SML-LX0603'
PRP P1 '635NM'
PRP P2 '2V'
PRP P3 '20MA'
PRP SHEETPART ''
PRP SIZE '0603'
PRP SUB ''
PRP Supplier_1 'Digi-Key'
PRP Supplier_Part_Number_1 '67-1548-1-ND'
PRP VALENTIUM_PART_NUM '<VALENTIUM>'
PRP VALUE 'RED'
TOP 0 3.5898425 3.9096063 0 N 50 1 D9-1
TOP 1 3.5898425 3.8525197 0 N 137 14 D9-2
#
# CMP 96
CMP 33 3.4698425 3.706063 90 N D8 BAT54SW ;0=1,1=0.0433
PRP CATEGORY 'DIO, SCHOTTKY'
PRP DATE ''
PRP DESC 'DIO, SCHOTTKY, BAT54S, DUAL SERIES, 30V, 200MA, SC-70'
PRP MAXTEMP '150C'
PRP MFG_Name 'DIODES INC'
PRP MFG_PART_NUM 'BAT54SWQ-7-F'
PRP MINTEMP '-55C'
PRP MODIFY_DATE '9/4/2013'
PRP OTHER 'SERIES'
PRP P1 'SCHOTTKY'
PRP P2 '30V'
PRP P3 '200mA,200mW'
PRP SHEETPART ''
PRP SIZE 'SC-70'
PRP SUB ''
PRP Supplier_1 'Digi-Key'
PRP Supplier_Part_Number_1 'BAT54SWQ-7-FDICT-ND'
PRP VALENTIUM_PART_NUM '<VALENTIUM>'
PRP VALUE 'BAT54SW'
TOP 0 3.4954331 3.7503543 0 N 135 175 D8-1
TOP 1 3.444252 3.7503543 0 N 137 34 D8-2
TOP 2 3.4698425 3.6617716 0 N 146 2 D8-3
#
# CMP 97
CMP 33 3.2448425 3.706063 90 N D7 BAT54SW ;0=1,1=0.0433
PRP CATEGORY 'DIO, SCHOTTKY'
PRP DATE ''
PRP DESC 'DIO, SCHOTTKY, BAT54S, DUAL SERIES, 30V, 200MA, SC-70'
PRP MAXTEMP '150C'
PRP MFG_Name 'DIODES INC'
PRP MFG_PART_NUM 'BAT54SWQ-7-F'
PRP MINTEMP '-55C'
PRP MODIFY_DATE '9/4/2013'
PRP OTHER 'SERIES'
PRP P1 'SCHOTTKY'
PRP P2 '30V'
PRP P3 '200mA,200mW'
PRP SHEETPART ''
PRP SIZE 'SC-70'
PRP SUB ''
PRP Supplier_1 'Digi-Key'
PRP Supplier_Part_Number_1 'BAT54SWQ-7-FDICT-ND'
PRP VALENTIUM_PART_NUM '<VALENTIUM>'
PRP VALUE 'BAT54SW'
TOP 0 3.2704331 3.7503543 0 N 135 66 D7-1
TOP 1 3.219252 3.7503543 0 N 137 15 D7-2
TOP 2 3.2448425 3.6617716 0 N 136 1 D7-3
#
# CMP 98
CMP 33 2.7198425 3.706063 90 N D6 BAT54SW ;0=1,1=0.0433
PRP CATEGORY 'DIO, SCHOTTKY'
PRP DATE ''
PRP DESC 'DIO, SCHOTTKY, BAT54S, DUAL SERIES, 30V, 200MA, SC-70'
PRP MAXTEMP '150C'
PRP MFG_Name 'DIODES INC'
PRP MFG_PART_NUM 'BAT54SWQ-7-F'
PRP MINTEMP '-55C'
PRP MODIFY_DATE '9/4/2013'
PRP OTHER 'SERIES'
PRP P1 'SCHOTTKY'
PRP P2 '30V'
PRP P3 '200mA,200mW'
PRP SHEETPART ''
PRP SIZE 'SC-70'
PRP SUB ''
PRP Supplier_1 'Digi-Key'
PRP Supplier_Part_Number_1 'BAT54SWQ-7-FDICT-ND'
PRP VALENTIUM_PART_NUM '<VALENTIUM>'
PRP VALUE 'BAT54SW'
TOP 0 2.7454331 3.7503543 0 N 135 67 D6-1
TOP 1 2.694252 3.7503543 0 N 137 16 D6-2
TOP 2 2.7198425 3.6617716 0 N 140 1 D6-3
#
# CMP 99
CMP 33 2.8348425 3.706063 90 N D5 BAT54SW ;0=1,1=0.0433
PRP CATEGORY 'DIO, SCHOTTKY'
PRP DATE ''
PRP DESC 'DIO, SCHOTTKY, BAT54S, DUAL SERIES, 30V, 200MA, SC-70'
PRP MAXTEMP '150C'
PRP MFG_Name 'DIODES INC'
PRP MFG_PART_NUM 'BAT54SWQ-7-F'
PRP MINTEMP '-55C'
PRP MODIFY_DATE '9/4/2013'
PRP OTHER 'SERIES'
PRP P1 'SCHOTTKY'
PRP P2 '30V'
PRP P3 '200mA,200mW'
PRP SHEETPART ''
PRP SIZE 'SC-70'
PRP SUB ''
PRP Supplier_1 'Digi-Key'
PRP Supplier_Part_Number_1 'BAT54SWQ-7-FDICT-ND'
PRP VALENTIUM_PART_NUM '<VALENTIUM>'
PRP VALUE 'BAT54SW'
TOP 0 2.8604331 3.7503543 0 N 135 68 D5-1
TOP 1 2.809252 3.7503543 0 N 137 17 D5-2
TOP 2 2.8348425 3.6617716 0 N 141 1 D5-3
#
# CMP 100
CMP 9 4.3041338 3.6033465 0 N D4 RED ;0=1,1=0.0236
PRP CATEGORY 'LED'
PRP DATE ''
PRP DESC 'LED, RED, SML-LX0603, 635NM, 2V, 20MA, 0603'
PRP MAXTEMP '85C'
PRP MFG_Name 'LUMEX'
PRP MFG_PART_NUM 'SML-LX0603IW-TR'
PRP MINTEMP '-25C'
PRP MODIFY_DATE '9/4/2013'
PRP OTHER 'SML-LX0603'
PRP P1 '635NM'
PRP P2 '2V'
PRP P3 '20MA'
PRP SHEETPART ''
PRP SIZE '0603'
PRP SUB ''
PRP Supplier_1 'Digi-Key'
PRP Supplier_Part_Number_1 '67-1548-1-ND'
PRP VALENTIUM_PART_NUM '<VALENTIUM>'
PRP VALUE 'RED'
TOP 0 4.2755905 3.6033465 270 N 51 0 D4-1
TOP 1 4.3326771 3.6033465 270 N 137 36 D4-2
#
# CMP 101
CMP 30 6.2698425 3.701063 0 N D3 DFLZ39-TP ;0=1,1=0.0531
PRP CATEGORY 'DIO, ZENER'
PRP DATE ''
PRP DESC 'DIO, ZENER, DFLZ39, 39V, 5%, 1W, SOD123FL'
PRP MAXTEMP '150C'
PRP MFG_Name 'MICRO COMM'
PRP MFG_PART_NUM 'DFLZ39-TP'
PRP MINTEMP '-55C'
PRP MODIFY_DATE '9/4/2013'
PRP OTHER 'SERIES'
PRP P1 '39V'
PRP P2 '5%'
PRP P3 '1W'
PRP SHEETPART ''
PRP SIZE 'SOD123FL'
PRP SUB ''
PRP Supplier_1 'Digi-Key'
PRP Supplier_Part_Number_1 'DFLZ39-TPMSDKR-ND'
PRP VALENTIUM_PART_NUM '<VALENTIUM>'
PRP VALUE 'DFLZ39'
TOP 0 6.1979921 3.701063 270 N 53 1 D3-1
TOP 1 6.3416929 3.701063 270 N 111 4 D3-2
#
# CMP 102
CMP 30 6.2748425 3.566063 0 N D2 DFLZ39-TP ;0=1,1=0.0531
PRP CATEGORY 'DIO, ZENER'
PRP DATE ''
PRP DESC 'DIO, ZENER, DFLZ39, 39V, 5%, 1W, SOD123FL'
PRP MAXTEMP '150C'
PRP MFG_Name 'MICRO COMM'
PRP MFG_PART_NUM 'DFLZ39-TP'
PRP MINTEMP '-55C'
PRP MODIFY_DATE '9/4/2013'
PRP OTHER 'SERIES'
PRP P1 '39V'
PRP P2 '5%'
PRP P3 '1W'
PRP SHEETPART ''
PRP SIZE 'SOD123FL'
PRP SUB ''
PRP Supplier_1 'Digi-Key'
PRP Supplier_Part_Number_1 'DFLZ39-TPMSDKR-ND'
PRP VALENTIUM_PART_NUM '<VALENTIUM>'
PRP VALUE 'DFLZ39'
TOP 0 6.2029921 3.566063 270 N 53 3 D2-1
TOP 1 6.3466929 3.566063 270 N 52 4 D2-2
#
# CMP 103
CMP 30 5.9598425 3.701063 0 N D1 DFLZ39-TP ;0=1,1=0.0531
PRP CATEGORY 'DIO, ZENER'
PRP DATE ''
PRP DESC 'DIO, ZENER, DFLZ39, 39V, 5%, 1W, SOD123FL'
PRP MAXTEMP '150C'
PRP MFG_Name 'MICRO COMM'
PRP MFG_PART_NUM 'DFLZ39-TP'
PRP MINTEMP '-55C'
PRP MODIFY_DATE '9/4/2013'
PRP OTHER 'SERIES'
PRP P1 '39V'
PRP P2 '5%'
PRP P3 '1W'
PRP SHEETPART ''
PRP SIZE 'SOD123FL'
PRP SUB ''
PRP Supplier_1 'Digi-Key'
PRP Supplier_Part_Number_1 'DFLZ39-TPMSDKR-ND'
PRP VALENTIUM_PART_NUM '<VALENTIUM>'
PRP VALUE 'DFLZ39'
TOP 0 5.8879921 3.701063 270 N 55 1 D1-1
TOP 1 6.0316929 3.701063 270 N 54 1 D1-2
#
# CMP 104
CMP 6 3.6888425 3.298063 90 N C67 CAP_0603_0.01UF_50V ;0=1,1=0.0394
PRP CATEGORY 'CAP, CER'
PRP DATE '7/24/2013'
PRP DESC 'CAP, CER, 0.01UF, 50V, 10%, X7R, 0603'
PRP MAXTEMP '125C'
PRP MFG_Name 'KEMET'
PRP MFG_PART_NUM 'C0603C103K5RACTU'
PRP MINTEMP '-55C'
PRP MODIFY_DATE '10/23/2013'
PRP OTHER ''
PRP P1 '10%'
PRP P2 '50V'
PRP P3 'X7R'
PRP SHEETPART ''
PRP SIZE '0603'
PRP SUB ''
PRP Supplier_1 'Digi-Key'
PRP Supplier_Part_Number_1 '399-1091-1-ND'
PRP VALENTIUM_PART_NUM '<VALENTIUM>'
PRP VALUE '0.01uF'
TOP 0 3.6888425 3.3295591 0 N 135 69 C67-1
TOP 1 3.6888425 3.266567 0 N 108 11 C67-2
#
# CMP 105
CMP 5 3.7698425 3.218063 270 N C66 CAP_0402_0.1UF_50V ;0=1,1=0.0236
PRP CATEGORY 'CAP, CER'
PRP DATE ''
PRP DESC 'CAP, CER, 0.1UF, 50V, 10%, X7R, AEC-Q200, 0402'
PRP MAXTEMP '125C'
PRP MFG_Name 'TDK'
PRP MFG_PART_NUM 'CGA2B3X7R1H104K050BB'
PRP MINTEMP '-55C'
PRP MODIFY_DATE '10/23/2013'
PRP OTHER 'AEC-Q200'
PRP P1 '10%'
PRP P2 '50V'
PRP P3 'X7R'
PRP SHEETPART ''
PRP SIZE '0402'
PRP SUB ''
PRP Supplier_1 'Digi-Key'
PRP Supplier_Part_Number_1 '445-6899-1-ND'
PRP VALENTIUM_PART_NUM '<VALENTIUM>'
PRP VALUE '0.1UF'
TOP 0 3.7698425 3.2011339 180 N 135 70 C66-1
TOP 1 3.7698425 3.2349922 180 N 108 12 C66-2
#
# CMP 106
CMP 7 3.6938425 3.153063 270 N C65 CAP_0805_1UF_50V ;0=1,1=0.0551
PRP CATEGORY 'CAP, CER'
PRP DATE '10/31/2006 2:46:38 PM'
PRP DESC 'CAP, CER, 1.0UF, 50V, 10%, X7R, 0805'
PRP MAXTEMP '125C'
PRP MFG_Name 'MURATA'
PRP MFG_PART_NUM 'GCM21BR71H105KA03L'
PRP MINTEMP '-55C'
PRP MODIFY_DATE '10/23/2013'
PRP OTHER 'AEC-Q200'
PRP P1 '10%'
PRP P2 '50V'
PRP P3 'X7R'
PRP SHEETPART ''
PRP SIZE '0805'
PRP SUB ''
PRP Supplier_1 'Digi-Key'
PRP Supplier_Part_Number_1 '490-10675-1-ND'
PRP VALENTIUM_PART_NUM '<VALENTIUM>'
PRP VALUE '1.0UF'
TOP 0 3.6938425 3.1176299 180 N 135 71 C65-1
TOP 1 3.6938425 3.1884961 180 N 108 13 C65-2
#
# CMP 107
CMP 5 3.6998425 0.636063 180 N C63 CAP_0402_0.1UF_50V ;0=1,1=0.0236
PRP CATEGORY 'CAP, CER'
PRP DATE ''
PRP DESC 'CAP, CER, 0.1UF, 50V, 10%, X7R, AEC-Q200, 0402'
PRP MAXTEMP '125C'
PRP MFG_Name 'TDK'
PRP MFG_PART_NUM 'CGA2B3X7R1H104K050BB'
PRP MINTEMP '-55C'
PRP MODIFY_DATE '10/23/2013'
PRP OTHER 'AEC-Q200'
PRP P1 '10%'
PRP P2 '50V'
PRP P3 'X7R'
PRP SHEETPART ''
PRP SIZE '0402'
PRP SUB ''
PRP Supplier_1 'Digi-Key'
PRP Supplier_Part_Number_1 '445-6899-1-ND'
PRP VALENTIUM_PART_NUM '<VALENTIUM>'
PRP VALUE '0.1UF'
TOP 0 3.7167716 0.636063 90 N 145 13 C63-1
TOP 1 3.6829133 0.636063 90 N 135 72 C63-2
#
# CMP 108
CMP 7 3.6948425 0.726063 180 N C62 CAP_0805_10UF_25V ;0=1,1=0.0551
PRP CATEGORY 'CAP, CER'
PRP DATE '4/11/2006 3:37:28 PM'
PRP DESC 'CAP, CER, 10.UF, 10V, 10%, X5R, 0805'
PRP MAXTEMP '85C'
PRP MFG_Name 'TAIYO YUDEN'
PRP MFG_PART_NUM 'TMK212BBJ106KG-T'
PRP MINTEMP '-55C'
PRP MODIFY_DATE '10/23/2013'
PRP OTHER ''
PRP P1 '10%'
PRP P2 '25V'
PRP P3 'X5R'
PRP SHEETPART ''
PRP SIZE '0805'
PRP SUB ''
PRP Supplier_1 'MOUSER'
PRP Supplier_Part_Number_1 '963-TMK212BBJ106KG-T'
PRP VALENTIUM_PART_NUM '<VALENTIUM>'
PRP VALUE '10uF'
TOP 0 3.7302756 0.726063 90 N 145 14 C62-1
TOP 1 3.6594094 0.726063 90 N 135 73 C62-2
#
# CMP 109
CMP 5 2.7248425 3.576063 90 N C61 CAP_0402_0.1UF_50V ;0=1,1=0.0236
PRP CATEGORY 'CAP, CER'
PRP DATE ''
PRP DESC 'CAP, CER, 0.1UF, 50V, 10%, X7R, AEC-Q200, 0402'
PRP MAXTEMP '125C'
PRP MFG_Name 'TDK'
PRP MFG_PART_NUM 'CGA2B3X7R1H104K050BB'
PRP MINTEMP '-55C'
PRP MODIFY_DATE '10/23/2013'
PRP OTHER 'AEC-Q200'
PRP P1 '10%'
PRP P2 '50V'
PRP P3 'X7R'
PRP SHEETPART ''
PRP SIZE '0402'
PRP SUB ''
PRP Supplier_1 'Digi-Key'
PRP Supplier_Part_Number_1 '445-6899-1-ND'
PRP VALENTIUM_PART_NUM '<VALENTIUM>'
PRP VALUE '0.1UF'
TOP 0 2.7248425 3.5929921 0 N 145 15 C61-1
TOP 1 2.7248425 3.5591338 0 N 135 74 C61-2
#
# CMP 110
CMP 7 2.6398425 3.571063 90 N C60 CAP_0805_10UF_25V ;0=1,1=0.0551
PRP CATEGORY 'CAP, CER'
PRP DATE '4/11/2006 3:37:28 PM'
PRP DESC 'CAP, CER, 10.UF, 10V, 10%, X5R, 0805'
PRP MAXTEMP '85C'
PRP MFG_Name 'TAIYO YUDEN'
PRP MFG_PART_NUM 'TMK212BBJ106KG-T'
PRP MINTEMP '-55C'
PRP MODIFY_DATE '10/23/2013'
PRP OTHER ''
PRP P1 '10%'
PRP P2 '25V'
PRP P3 'X5R'
PRP SHEETPART ''
PRP SIZE '0805'
PRP SUB ''
PRP Supplier_1 'MOUSER'
PRP Supplier_Part_Number_1 '963-TMK212BBJ106KG-T'
PRP VALENTIUM_PART_NUM '<VALENTIUM>'
PRP VALUE '10uF'
TOP 0 2.6398425 3.6064961 0 N 145 16 C60-1
TOP 1 2.6398425 3.5356299 0 N 135 75 C60-2
#
# CMP 111
CMP 5 2.1398425 3.681063 270 N C59 CAP_0402_0.1UF_50V ;0=1,1=0.0236
PRP CATEGORY 'CAP, CER'
PRP DATE ''
PRP DESC 'CAP, CER, 0.1UF, 50V, 10%, X7R, AEC-Q200, 0402'
PRP MAXTEMP '125C'
PRP MFG_Name 'TDK'
PRP MFG_PART_NUM 'CGA2B3X7R1H104K050BB'
PRP MINTEMP '-55C'
PRP MODIFY_DATE '10/23/2013'
PRP OTHER 'AEC-Q200'
PRP P1 '10%'
PRP P2 '50V'
PRP P3 'X7R'
PRP SHEETPART ''
PRP SIZE '0402'
PRP SUB ''
PRP Supplier_1 'Digi-Key'
PRP Supplier_Part_Number_1 '445-6899-1-ND'
PRP VALENTIUM_PART_NUM '<VALENTIUM>'
PRP VALUE '0.1UF'
TOP 0 2.1398425 3.6641339 180 N 137 18 C59-1
TOP 1 2.1398425 3.6979922 180 N 135 76 C59-2
#
# CMP 112
CMP 7 2.2098425 3.681063 270 N C58 CAP_0805_10UF_25V ;0=1,1=0.0551
PRP CATEGORY 'CAP, CER'
PRP DATE '4/11/2006 3:37:28 PM'
PRP DESC 'CAP, CER, 10.UF, 10V, 10%, X5R, 0805'
PRP MAXTEMP '85C'
PRP MFG_Name 'TAIYO YUDEN'
PRP MFG_PART_NUM 'TMK212BBJ106KG-T'
PRP MINTEMP '-55C'
PRP MODIFY_DATE '10/23/2013'
PRP OTHER ''
PRP P1 '10%'
PRP P2 '25V'
PRP P3 'X5R'
PRP SHEETPART ''
PRP SIZE '0805'
PRP SUB ''
PRP Supplier_1 'MOUSER'
PRP Supplier_Part_Number_1 '963-TMK212BBJ106KG-T'
PRP VALENTIUM_PART_NUM '<VALENTIUM>'
PRP VALUE '10uF'
TOP 0 2.2098425 3.6456299 180 N 137 19 C58-1
TOP 1 2.2098425 3.7164961 180 N 135 77 C58-2
#
# CMP 113
CMP 5 6.5848425 3.056063 90 N C57 CAP_0402_0.1UF_50V ;0=1,1=0.0236
PRP CATEGORY 'CAP, CER'
PRP DATE ''
PRP DESC 'CAP, CER, 0.1UF, 50V, 10%, X7R, AEC-Q200, 0402'
PRP MAXTEMP '125C'
PRP MFG_Name 'TDK'
PRP MFG_PART_NUM 'CGA2B3X7R1H104K050BB'
PRP MINTEMP '-55C'
PRP MODIFY_DATE '10/23/2013'
PRP OTHER 'AEC-Q200'
PRP P1 '10%'
PRP P2 '50V'
PRP P3 'X7R'
PRP SHEETPART ''
PRP SIZE '0402'
PRP SUB ''
PRP Supplier_1 'Digi-Key'
PRP Supplier_Part_Number_1 '445-6899-1-ND'
PRP VALENTIUM_PART_NUM '<VALENTIUM>'
PRP VALUE '0.1UF'
TOP 0 6.5848425 3.0729921 0 N 137 20 C57-1
TOP 1 6.5848425 3.0391338 0 N 135 78 C57-2
#
# CMP 114
CMP 7 6.4748425 3.071063 180 N C56 CAP_0805_10UF_25V ;0=1,1=0.0551
PRP CATEGORY 'CAP, CER'
PRP DATE '4/11/2006 3:37:28 PM'
PRP DESC 'CAP, CER, 10.UF, 10V, 10%, X5R, 0805'
PRP MAXTEMP '85C'
PRP MFG_Name 'TAIYO YUDEN'
PRP MFG_PART_NUM 'TMK212BBJ106KG-T'
PRP MINTEMP '-55C'
PRP MODIFY_DATE '10/23/2013'
PRP OTHER ''
PRP P1 '10%'
PRP P2 '25V'
PRP P3 'X5R'
PRP SHEETPART ''
PRP SIZE '0805'
PRP SUB ''
PRP Supplier_1 'MOUSER'
PRP Supplier_Part_Number_1 '963-TMK212BBJ106KG-T'
PRP VALENTIUM_PART_NUM '<VALENTIUM>'
PRP VALUE '10uF'
TOP 0 6.5102756 3.071063 90 N 137 21 C56-1
TOP 1 6.4394094 3.071063 90 N 135 79 C56-2
#
# CMP 115
CMP 6 4.1948425 3.806063 90 N C55 GRT188R61E106ME13D ;0=1,1=0.0394
PRP CATEGORY 'CAP, CER'
PRP DATE '7/25/2013'
PRP DESC 'CAP, CER, 10.UF, 25V, 20%, X5R, AEC-Q200, 0603'
PRP MAXTEMP '85C'
PRP MFG_Name 'MURATA'
PRP MFG_PART_NUM 'GRT188R61E106ME13D'
PRP MINTEMP '-55C'
PRP MODIFY_DATE '10/23/2013'
PRP OTHER 'AEC-Q200'
PRP P1 '20%'
PRP P2 '25V'
PRP P3 'X5R'
PRP SHEETPART ''
PRP SIZE '0603'
PRP SUB ''
PRP Supplier_1 'Digi-Key'
PRP Supplier_Part_Number_1 '490-12323-6-ND'
PRP VALENTIUM_PART_NUM '<VALENTIUM>'
PRP VALUE '10.UF'
TOP 0 4.1948425 3.8375591 0 N 135 80 C55-1
TOP 1 4.1948425 3.774567 0 N 145 17 C55-2
#
# CMP 116
CMP 7 4.1048425 3.806063 90 N C54 CAP_0805_1UF_25V ;0=1,1=0.0551
PRP CATEGORY 'CAP, CER'
PRP DATE '4/11/2006 3:37:28 PM'
PRP DESC 'CAP, CER, 1.0UF, 25V, 10%, X5R, 0805'
PRP MAXTEMP '85C'
PRP MFG_Name 'AVX'
PRP MFG_PART_NUM '08053D105KAT2A'
PRP MINTEMP '-55C'
PRP MODIFY_DATE '10/23/2013'
PRP OTHER ''
PRP P1 '10%'
PRP P2 '25V'
PRP P3 'X5R'
PRP SHEETPART ''
PRP SIZE '0805'
PRP SUB ''
PRP Supplier_1 'Digi-Key'
PRP Supplier_Part_Number_1 '478-1409-1-ND'
PRP VALENTIUM_PART_NUM '<VALENTIUM>'
PRP VALUE '1.0UF'
TOP 0 4.1048425 3.8414961 0 N 135 81 C54-1
TOP 1 4.1048425 3.7706299 0 N 145 18 C54-2
#
# CMP 117
CMP 5 6.0648425 2.361063 270 N C22 CGA2B3X5R1H333K050BB ;0=1,1=0.0236
PRP CATEGORY 'CAP, CER'
PRP DATE ''
PRP DESC 'CAP, CER, 0.033UF, 50V, 10%, X7R, AEC-Q200, 0402'
PRP MAXTEMP '85C'
PRP MFG_Name 'TDK'
PRP MFG_PART_NUM 'CGA2B3X5R1H333K050BB'
PRP MINTEMP '-55C'
PRP MODIFY_DATE '10/23/2013'
PRP OTHER 'AEC-Q200'
PRP P1 '10%'
PRP P2 '50V'
PRP P3 'X7R'
PRP SHEETPART ''
PRP SIZE '0402'
PRP SUB ''
PRP Supplier_1 'Digi-Key'
PRP Supplier_Part_Number_1 '445-12207-1-ND'
PRP VALENTIUM_PART_NUM '<VALENTIUM>'
PRP VALUE '0.033UF'
TOP 0 6.0648425 2.3441339 180 N 58 0 C22-1
TOP 1 6.0648425 2.3779922 180 N 57 1 C22-2
#
# CMP 118
CMP 6 6.1248425 2.171063 0 N C21 CAP_0603_0.1UF_50V ;0=1,1=0.0394
PRP CATEGORY 'CAP, CER'
PRP DATE '7/24/2013'
PRP DESC 'CAP, CER, 0.1UF, 50V, 10%, X7R, 0603'
PRP MAXTEMP '125C'
PRP MFG_Name 'KEMET'
PRP MFG_PART_NUM 'C0603C104K5RACTU'
PRP MINTEMP '-55C'
PRP MODIFY_DATE '10/23/2013'
PRP OTHER ''
PRP P1 '10%'
PRP P2 '50V'
PRP P3 'X7R'
PRP SHEETPART ''
PRP SIZE '0603'
PRP SUB ''
PRP Supplier_1 'Digi-Key'
PRP Supplier_Part_Number_1 '399-5089-1-ND'
PRP VALENTIUM_PART_NUM '<VALENTIUM>'
PRP VALUE '0.1uF'
TOP 0 6.0933464 2.171063 270 N 135 82 C21-1
TOP 1 6.1563385 2.171063 270 N 59 0 C21-2
#
# CMP 119
CMP 5 6.9398425 1.906063 90 N C20 CGA2B3X5R1H333K050BB ;0=1,1=0.0236
PRP CATEGORY 'CAP, CER'
PRP DATE ''
PRP DESC 'CAP, CER, 0.033UF, 50V, 10%, X7R, AEC-Q200, 0402'
PRP MAXTEMP '85C'
PRP MFG_Name 'TDK'
PRP MFG_PART_NUM 'CGA2B3X5R1H333K050BB'
PRP MINTEMP '-55C'
PRP MODIFY_DATE '10/23/2013'
PRP OTHER 'AEC-Q200'
PRP P1 '10%'
PRP P2 '50V'
PRP P3 'X7R'
PRP SHEETPART ''
PRP SIZE '0402'
PRP SUB ''
PRP Supplier_1 'Digi-Key'
PRP Supplier_Part_Number_1 '445-12207-1-ND'
PRP VALENTIUM_PART_NUM '<VALENTIUM>'
PRP VALUE '0.033UF'
TOP 0 6.9398425 1.9229921 0 N 61 1 C20-1
TOP 1 6.9398425 1.8891338 0 N 60 1 C20-2
#
# CMP 120
CMP 6 6.8748425 2.096063 180 N C19 CAP_0603_0.1UF_50V ;0=1,1=0.0394
PRP CATEGORY 'CAP, CER'
PRP DATE '7/24/2013'
PRP DESC 'CAP, CER, 0.1UF, 50V, 10%, X7R, 0603'
PRP MAXTEMP '125C'
PRP MFG_Name 'KEMET'
PRP MFG_PART_NUM 'C0603C104K5RACTU'
PRP MINTEMP '-55C'
PRP MODIFY_DATE '10/23/2013'
PRP OTHER ''
PRP P1 '10%'
PRP P2 '50V'
PRP P3 'X7R'
PRP SHEETPART ''
PRP SIZE '0603'
PRP SUB ''
PRP Supplier_1 'Digi-Key'
PRP Supplier_Part_Number_1 '399-5089-1-ND'
PRP VALENTIUM_PART_NUM '<VALENTIUM>'
PRP VALUE '0.1uF'
TOP 0 6.9063386 2.096063 90 N 135 180 C19-1
TOP 1 6.8433465 2.096063 90 N 62 1 C19-2
#
# CMP 121
CMP 5 6.6598425 1.776063 180 N C18 CAP_0402_0.1UF_50V ;0=1,1=0.0236
PRP CATEGORY 'CAP, CER'
PRP DATE ''
PRP DESC 'CAP, CER, 0.1UF, 50V, 10%, X7R, AEC-Q200, 0402'
PRP MAXTEMP '125C'
PRP MFG_Name 'TDK'
PRP MFG_PART_NUM 'CGA2B3X7R1H104K050BB'
PRP MINTEMP '-55C'
PRP MODIFY_DATE '10/23/2013'
PRP OTHER 'AEC-Q200'
PRP P1 '10%'
PRP P2 '50V'
PRP P3 'X7R'
PRP SHEETPART ''
PRP SIZE '0402'
PRP SUB ''
PRP Supplier_1 'Digi-Key'
PRP Supplier_Part_Number_1 '445-6899-1-ND'
PRP VALENTIUM_PART_NUM '<VALENTIUM>'
PRP VALUE '0.1UF'
TOP 0 6.6767716 1.776063 90 N 145 19 C18-1
TOP 1 6.6429133 1.776063 90 N 135 83 C18-2
#
# CMP 122
CMP 5 6.6598425 1.721063 180 N C17 CAP_0402_0.1UF_50V ;0=1,1=0.0236
PRP CATEGORY 'CAP, CER'
PRP DATE ''
PRP DESC 'CAP, CER, 0.1UF, 50V, 10%, X7R, AEC-Q200, 0402'
PRP MAXTEMP '125C'
PRP MFG_Name 'TDK'
PRP MFG_PART_NUM 'CGA2B3X7R1H104K050BB'
PRP MINTEMP '-55C'
PRP MODIFY_DATE '10/23/2013'
PRP OTHER 'AEC-Q200'
PRP P1 '10%'
PRP P2 '50V'
PRP P3 'X7R'
PRP SHEETPART ''
PRP SIZE '0402'
PRP SUB ''
PRP Supplier_1 'Digi-Key'
PRP Supplier_Part_Number_1 '445-6899-1-ND'
PRP VALENTIUM_PART_NUM '<VALENTIUM>'
PRP VALUE '0.1UF'
TOP 0 6.6767716 1.721063 90 N 145 20 C17-1
TOP 1 6.6429133 1.721063 90 N 135 84 C17-2
#
# CMP 123
CMP 5 6.6598425 1.671063 180 N C16 CAP_0402_0.1UF_50V ;0=1,1=0.0236
PRP CATEGORY 'CAP, CER'
PRP DATE ''
PRP DESC 'CAP, CER, 0.1UF, 50V, 10%, X7R, AEC-Q200, 0402'
PRP MAXTEMP '125C'
PRP MFG_Name 'TDK'
PRP MFG_PART_NUM 'CGA2B3X7R1H104K050BB'
PRP MINTEMP '-55C'
PRP MODIFY_DATE '10/23/2013'
PRP OTHER 'AEC-Q200'
PRP P1 '10%'
PRP P2 '50V'
PRP P3 'X7R'
PRP SHEETPART ''
PRP SIZE '0402'
PRP SUB ''
PRP Supplier_1 'Digi-Key'
PRP Supplier_Part_Number_1 '445-6899-1-ND'
PRP VALENTIUM_PART_NUM '<VALENTIUM>'
PRP VALUE '0.1UF'
TOP 0 6.6767716 1.671063 90 N 145 21 C16-1
TOP 1 6.6429133 1.671063 90 N 135 85 C16-2
#
# CMP 124
CMP 5 6.6598425 1.611063 180 N C15 CAP_0402_0.1UF_50V ;0=1,1=0.0236
PRP CATEGORY 'CAP, CER'
PRP DATE ''
PRP DESC 'CAP, CER, 0.1UF, 50V, 10%, X7R, AEC-Q200, 0402'
PRP MAXTEMP '125C'
PRP MFG_Name 'TDK'
PRP MFG_PART_NUM 'CGA2B3X7R1H104K050BB'
PRP MINTEMP '-55C'
PRP MODIFY_DATE '10/23/2013'
PRP OTHER 'AEC-Q200'
PRP P1 '10%'
PRP P2 '50V'
PRP P3 'X7R'
PRP SHEETPART ''
PRP SIZE '0402'
PRP SUB ''
PRP Supplier_1 'Digi-Key'
PRP Supplier_Part_Number_1 '445-6899-1-ND'
PRP VALENTIUM_PART_NUM '<VALENTIUM>'
PRP VALUE '0.1UF'
TOP 0 6.6767716 1.611063 90 N 145 22 C15-1
TOP 1 6.6429133 1.611063 90 N 135 86 C15-2
#
# CMP 125
CMP 7 6.6648425 1.531063 180 N C14 CAP_0805_10UF_25V ;0=1,1=0.0551
PRP CATEGORY 'CAP, CER'
PRP DATE '4/11/2006 3:37:28 PM'
PRP DESC 'CAP, CER, 10.UF, 10V, 10%, X5R, 0805'
PRP MAXTEMP '85C'
PRP MFG_Name 'TAIYO YUDEN'
PRP MFG_PART_NUM 'TMK212BBJ106KG-T'
PRP MINTEMP '-55C'
PRP MODIFY_DATE '10/23/2013'
PRP OTHER ''
PRP P1 '10%'
PRP P2 '25V'
PRP P3 'X5R'
PRP SHEETPART ''
PRP SIZE '0805'
PRP SUB ''
PRP Supplier_1 'MOUSER'
PRP Supplier_Part_Number_1 '963-TMK212BBJ106KG-T'
PRP VALENTIUM_PART_NUM '<VALENTIUM>'
PRP VALUE '10uF'
TOP 0 6.7002756 1.531063 90 N 145 23 C14-1
TOP 1 6.6294094 1.531063 90 N 135 87 C14-2
#
# CMP 126
CMP 7 6.6648425 1.421063 180 N C13 CAP_0805_10UF_25V ;0=1,1=0.0551
PRP CATEGORY 'CAP, CER'
PRP DATE '4/11/2006 3:37:28 PM'
PRP DESC 'CAP, CER, 10.UF, 10V, 10%, X5R, 0805'
PRP MAXTEMP '85C'
PRP MFG_Name 'TAIYO YUDEN'
PRP MFG_PART_NUM 'TMK212BBJ106KG-T'
PRP MINTEMP '-55C'
PRP MODIFY_DATE '10/23/2013'
PRP OTHER ''
PRP P1 '10%'
PRP P2 '25V'
PRP P3 'X5R'
PRP SHEETPART ''
PRP SIZE '0805'
PRP SUB ''
PRP Supplier_1 'MOUSER'
PRP Supplier_Part_Number_1 '963-TMK212BBJ106KG-T'
PRP VALENTIUM_PART_NUM '<VALENTIUM>'
PRP VALUE '10uF'
TOP 0 6.7002756 1.421063 90 N 145 24 C13-1
TOP 1 6.6294094 1.421063 90 N 135 88 C13-2
#
# CMP 127
CMP 5 6.3448425 2.611063 0 N C12 CAP_0402_0.1UF_50V ;0=1,1=0.0236
PRP CATEGORY 'CAP, CER'
PRP DATE ''
PRP DESC 'CAP, CER, 0.1UF, 50V, 10%, X7R, AEC-Q200, 0402'
PRP MAXTEMP '125C'
PRP MFG_Name 'TDK'
PRP MFG_PART_NUM 'CGA2B3X7R1H104K050BB'
PRP MINTEMP '-55C'
PRP MODIFY_DATE '10/23/2013'
PRP OTHER 'AEC-Q200'
PRP P1 '10%'
PRP P2 '50V'
PRP P3 'X7R'
PRP SHEETPART ''
PRP SIZE '0402'
PRP SUB ''
PRP Supplier_1 'Digi-Key'
PRP Supplier_Part_Number_1 '445-6899-1-ND'
PRP VALENTIUM_PART_NUM '<VALENTIUM>'
PRP VALUE '0.1UF'
TOP 0 6.3279134 2.611063 270 N 137 22 C12-1
TOP 1 6.3617717 2.611063 270 N 135 89 C12-2
#
# CMP 128
CMP 5 6.3448425 2.556063 0 N C11 CAP_0402_0.1UF_50V ;0=1,1=0.0236
PRP CATEGORY 'CAP, CER'
PRP DATE ''
PRP DESC 'CAP, CER, 0.1UF, 50V, 10%, X7R, AEC-Q200, 0402'
PRP MAXTEMP '125C'
PRP MFG_Name 'TDK'
PRP MFG_PART_NUM 'CGA2B3X7R1H104K050BB'
PRP MINTEMP '-55C'
PRP MODIFY_DATE '10/23/2013'
PRP OTHER 'AEC-Q200'
PRP P1 '10%'
PRP P2 '50V'
PRP P3 'X7R'
PRP SHEETPART ''
PRP SIZE '0402'
PRP SUB ''
PRP Supplier_1 'Digi-Key'
PRP Supplier_Part_Number_1 '445-6899-1-ND'
PRP VALENTIUM_PART_NUM '<VALENTIUM>'
PRP VALUE '0.1UF'
TOP 0 6.3279134 2.556063 270 N 137 23 C11-1
TOP 1 6.3617717 2.556063 270 N 135 90 C11-2
#
# CMP 129
CMP 5 6.3448425 2.501063 0 N C10 CAP_0402_0.1UF_50V ;0=1,1=0.0236
PRP CATEGORY 'CAP, CER'
PRP DATE ''
PRP DESC 'CAP, CER, 0.1UF, 50V, 10%, X7R, AEC-Q200, 0402'
PRP MAXTEMP '125C'
PRP MFG_Name 'TDK'
PRP MFG_PART_NUM 'CGA2B3X7R1H104K050BB'
PRP MINTEMP '-55C'
PRP MODIFY_DATE '10/23/2013'
PRP OTHER 'AEC-Q200'
PRP P1 '10%'
PRP P2 '50V'
PRP P3 'X7R'
PRP SHEETPART ''
PRP SIZE '0402'
PRP SUB ''
PRP Supplier_1 'Digi-Key'
PRP Supplier_Part_Number_1 '445-6899-1-ND'
PRP VALENTIUM_PART_NUM '<VALENTIUM>'
PRP VALUE '0.1UF'
TOP 0 6.3279134 2.501063 270 N 137 24 C10-1
TOP 1 6.3617717 2.501063 270 N 135 91 C10-2
#
# CMP 130
CMP 5 6.3448425 2.656063 0 N C9 CAP_0402_0.1UF_50V ;0=1,1=0.0236
PRP CATEGORY 'CAP, CER'
PRP DATE ''
PRP DESC 'CAP, CER, 0.1UF, 50V, 10%, X7R, AEC-Q200, 0402'
PRP MAXTEMP '125C'
PRP MFG_Name 'TDK'
PRP MFG_PART_NUM 'CGA2B3X7R1H104K050BB'
PRP MINTEMP '-55C'
PRP MODIFY_DATE '10/23/2013'
PRP OTHER 'AEC-Q200'
PRP P1 '10%'
PRP P2 '50V'
PRP P3 'X7R'
PRP SHEETPART ''
PRP SIZE '0402'
PRP SUB ''
PRP Supplier_1 'Digi-Key'
PRP Supplier_Part_Number_1 '445-6899-1-ND'
PRP VALENTIUM_PART_NUM '<VALENTIUM>'
PRP VALUE '0.1UF'
TOP 0 6.3279134 2.656063 270 N 137 25 C9-1
TOP 1 6.3617717 2.656063 270 N 135 92 C9-2
#
# CMP 131
CMP 7 6.3720472 2.7913386 270 N C8 CAP_0805_10UF_25V ;0=1,1=0.0551
PRP CATEGORY 'CAP, CER'
PRP DATE '4/11/2006 3:37:28 PM'
PRP DESC 'CAP, CER, 10.UF, 10V, 10%, X5R, 0805'
PRP MAXTEMP '85C'
PRP MFG_Name 'TAIYO YUDEN'
PRP MFG_PART_NUM 'TMK212BBJ106KG-T'
PRP MINTEMP '-55C'
PRP MODIFY_DATE '10/23/2013'
PRP OTHER ''
PRP P1 '10%'
PRP P2 '25V'
PRP P3 'X5R'
PRP SHEETPART ''
PRP SIZE '0805'
PRP SUB ''
PRP Supplier_1 'MOUSER'
PRP Supplier_Part_Number_1 '963-TMK212BBJ106KG-T'
PRP VALENTIUM_PART_NUM '<VALENTIUM>'
PRP VALUE '10uF'
TOP 0 6.3720472 2.7559055 180 N 137 26 C8-1
TOP 1 6.3720472 2.8267717 180 N 135 93 C8-2
#
# CMP 132
CMP 7 6.253937 2.7913386 270 N C7 CAP_0805_10UF_25V ;0=1,1=0.0551
PRP CATEGORY 'CAP, CER'
PRP DATE '4/11/2006 3:37:28 PM'
PRP DESC 'CAP, CER, 10.UF, 10V, 10%, X5R, 0805'
PRP MAXTEMP '85C'
PRP MFG_Name 'TAIYO YUDEN'
PRP MFG_PART_NUM 'TMK212BBJ106KG-T'
PRP MINTEMP '-55C'
PRP MODIFY_DATE '10/23/2013'
PRP OTHER ''
PRP P1 '10%'
PRP P2 '25V'
PRP P3 'X5R'
PRP SHEETPART ''
PRP SIZE '0805'
PRP SUB ''
PRP Supplier_1 'MOUSER'
PRP Supplier_Part_Number_1 '963-TMK212BBJ106KG-T'
PRP VALENTIUM_PART_NUM '<VALENTIUM>'
PRP VALUE '10uF'
TOP 0 6.253937 2.7559055 180 N 137 27 C7-1
TOP 1 6.253937 2.8267717 180 N 135 94 C7-2
#
# CMP 133
CMP 7 6.6598425 2.131063 270 N C6 CAP_0805_10UF_25V ;0=1,1=0.0551
PRP CATEGORY 'CAP, CER'
PRP DATE '4/11/2006 3:37:28 PM'
PRP DESC 'CAP, CER, 10.UF, 10V, 10%, X5R, 0805'
PRP MAXTEMP '85C'
PRP MFG_Name 'TAIYO YUDEN'
PRP MFG_PART_NUM 'TMK212BBJ106KG-T'
PRP MINTEMP '-55C'
PRP MODIFY_DATE '10/23/2013'
PRP OTHER ''
PRP P1 '10%'
PRP P2 '25V'
PRP P3 'X5R'
PRP SHEETPART ''
PRP SIZE '0805'
PRP SUB ''
PRP Supplier_1 'MOUSER'
PRP Supplier_Part_Number_1 '963-TMK212BBJ106KG-T'
PRP VALENTIUM_PART_NUM '<VALENTIUM>'
PRP VALUE '10uF'
TOP 0 6.6598425 2.0956299 180 N 142 4 C6-1
TOP 1 6.6598425 2.1664961 180 N 135 95 C6-2
#
# CMP 134
CMP 7 6.3348425 2.146063 90 N C5 CAP_0805_10UF_25V ;0=1,1=0.0551
PRP CATEGORY 'CAP, CER'
PRP DATE '4/11/2006 3:37:28 PM'
PRP DESC 'CAP, CER, 10.UF, 10V, 10%, X5R, 0805'
PRP MAXTEMP '85C'
PRP MFG_Name 'TAIYO YUDEN'
PRP MFG_PART_NUM 'TMK212BBJ106KG-T'
PRP MINTEMP '-55C'
PRP MODIFY_DATE '10/23/2013'
PRP OTHER ''
PRP P1 '10%'
PRP P2 '25V'
PRP P3 'X5R'
PRP SHEETPART ''
PRP SIZE '0805'
PRP SUB ''
PRP Supplier_1 'MOUSER'
PRP Supplier_Part_Number_1 '963-TMK212BBJ106KG-T'
PRP VALENTIUM_PART_NUM '<VALENTIUM>'
PRP VALUE '10uF'
TOP 0 6.3348425 2.1814961 0 N 142 5 C5-1
TOP 1 6.3348425 2.1106299 0 N 135 96 C5-2
#
# CMP 135
CMP 6 6.5198425 1.986063 90 N C4 CAP_0603_0.01UF_50V ;0=1,1=0.0394
PRP CATEGORY 'CAP, CER'
PRP DATE '7/24/2013'
PRP DESC 'CAP, CER, 0.01UF, 50V, 10%, X7R, 0603'
PRP MAXTEMP '125C'
PRP MFG_Name 'KEMET'
PRP MFG_PART_NUM 'C0603C103K5RACTU'
PRP MINTEMP '-55C'
PRP MODIFY_DATE '10/23/2013'
PRP OTHER ''
PRP P1 '10%'
PRP P2 '50V'
PRP P3 'X7R'
PRP SHEETPART ''
PRP SIZE '0603'
PRP SUB ''
PRP Supplier_1 'Digi-Key'
PRP Supplier_Part_Number_1 '399-1091-1-ND'
PRP VALENTIUM_PART_NUM '<VALENTIUM>'
PRP VALUE '0.01uF'
TOP 0 6.5198425 2.0175591 0 N 64 1 C4-1
TOP 1 6.5198425 1.954567 0 N 63 2 C4-2
#
# CMP 136
CMP 6 6.4698425 2.271063 270 N C3 CAP_0603_0.01UF_50V ;0=1,1=0.0394
PRP CATEGORY 'CAP, CER'
PRP DATE '7/24/2013'
PRP DESC 'CAP, CER, 0.01UF, 50V, 10%, X7R, 0603'
PRP MAXTEMP '125C'
PRP MFG_Name 'KEMET'
PRP MFG_PART_NUM 'C0603C103K5RACTU'
PRP MINTEMP '-55C'
PRP MODIFY_DATE '10/23/2013'
PRP OTHER ''
PRP P1 '10%'
PRP P2 '50V'
PRP P3 'X7R'
PRP SHEETPART ''
PRP SIZE '0603'
PRP SUB ''
PRP Supplier_1 'Digi-Key'
PRP Supplier_Part_Number_1 '399-1091-1-ND'
PRP VALENTIUM_PART_NUM '<VALENTIUM>'
PRP VALUE '0.01uF'
TOP 0 6.4698425 2.2395669 180 N 66 0 C3-1
TOP 1 6.4698425 2.302559 180 N 65 0 C3-2
#
# CMP 137
CMP 5 5.6513779 3.359252 0 N C2 CAP_0402_0.1UF_50V ;0=1,1=0.0236
PRP CATEGORY 'CAP, CER'
PRP DATE ''
PRP DESC 'CAP, CER, 0.1UF, 50V, 10%, X7R, AEC-Q200, 0402'
PRP MAXTEMP '125C'
PRP MFG_Name 'TDK'
PRP MFG_PART_NUM 'CGA2B3X7R1H104K050BB'
PRP MINTEMP '-55C'
PRP MODIFY_DATE '10/23/2013'
PRP OTHER 'AEC-Q200'
PRP P1 '10%'
PRP P2 '50V'
PRP P3 'X7R'
PRP SHEETPART ''
PRP SIZE '0402'
PRP SUB ''
PRP Supplier_1 'Digi-Key'
PRP Supplier_Part_Number_1 '445-6899-1-ND'
PRP VALENTIUM_PART_NUM '<VALENTIUM>'
PRP VALUE '0.1UF'
TOP 0 5.6344488 3.359252 270 N 142 6 C2-1
TOP 1 5.6683071 3.359252 270 N 135 97 C2-2
#
# CMP 138
CMP 7 5.7765748 3.3612205 180 N C1 CAP_0805_10UF_25V ;0=1,1=0.0551
PRP CATEGORY 'CAP, CER'
PRP DATE '4/11/2006 3:37:28 PM'
PRP DESC 'CAP, CER, 10.UF, 10V, 10%, X5R, 0805'
PRP MAXTEMP '85C'
PRP MFG_Name 'TAIYO YUDEN'
PRP MFG_PART_NUM 'TMK212BBJ106KG-T'
PRP MINTEMP '-55C'
PRP MODIFY_DATE '10/23/2013'
PRP OTHER ''
PRP P1 '10%'
PRP P2 '25V'
PRP P3 'X5R'
PRP SHEETPART ''
PRP SIZE '0805'
PRP SUB ''
PRP Supplier_1 'MOUSER'
PRP Supplier_Part_Number_1 '963-TMK212BBJ106KG-T'
PRP VALENTIUM_PART_NUM '<VALENTIUM>'
PRP VALUE '10uF'
TOP 0 5.8120079 3.3612205 90 N 142 7 C1-1
TOP 1 5.7411417 3.3612205 90 N 135 98 C1-2
#
# CMP 139
CMP 34 0.6548425 0.906063 90 N AN8 1909763-1 ;0=1,1=0.3898
PRP CATEGORY 'CONN, JACK'
PRP DATE ''
PRP DESC 'CONN, JACK, UMCC, MALE, 50 OHM, U.FL, GOLD, SMT'
PRP MAXTEMP '90C'
PRP MFG_Name 'TE'
PRP MFG_PART_NUM '1909763-1'
PRP MINTEMP '-40C'
PRP MODIFY_DATE '10/10/2013'
PRP OTHER 'GOLD'
PRP P1 'MALE'
PRP P2 '50 OHM'
PRP P3 'ST'
PRP SHEETPART ''
PRP SIZE '1.25MM HT'
PRP SUB ''
PRP Supplier_1 'Digi-Key'
PRP Supplier_Part_Number_1 'A118077CT-ND'
PRP VALENTIUM_PART_NUM '<VALENTIUM>'
PRP VALUE 'UMCC'
TOP 0 0.5948031 0.906063 90 N 104 3 AN8-1
TOP 1 0.6548425 0.9641339 90 N 135 176 AN8-2
TOP 2 0.6548425 0.8479921 90 N 135 177 AN8-3
#
# CMP 140
CMP 34 0.6548425 1.431063 90 N AN7 1909763-1 ;0=1,1=0.3898
PRP CATEGORY 'CONN, JACK'
PRP DATE ''
PRP DESC 'CONN, JACK, UMCC, MALE, 50 OHM, U.FL, GOLD, SMT'
PRP MAXTEMP '90C'
PRP MFG_Name 'TE'
PRP MFG_PART_NUM '1909763-1'
PRP MINTEMP '-40C'
PRP MODIFY_DATE '10/10/2013'
PRP OTHER 'GOLD'
PRP P1 'MALE'
PRP P2 '50 OHM'
PRP P3 'ST'
PRP SHEETPART ''
PRP SIZE '1.25MM HT'
PRP SUB ''
PRP Supplier_1 'Digi-Key'
PRP Supplier_Part_Number_1 'A118077CT-ND'
PRP VALENTIUM_PART_NUM '<VALENTIUM>'
PRP VALUE 'UMCC'
TOP 0 0.5948031 1.431063 90 N 105 2 AN7-1
TOP 1 0.6548425 1.4891339 90 N 135 99 AN7-2
TOP 2 0.6548425 1.3729921 90 N 135 100 AN7-3
#
# CMP 141
CMP 34 0.6548425 2.481063 90 N AN6 1909763-1 ;0=1,1=0.0000
PRP CATEGORY 'CONN, JACK'
PRP DATE ''
PRP DESC 'CONN, JACK, UMCC, MALE, 50 OHM, U.FL, GOLD, SMT'
PRP MAXTEMP '90C'
PRP MFG_Name 'TE'
PRP MFG_PART_NUM '1909763-1'
PRP MINTEMP '-40C'
PRP MODIFY_DATE '10/10/2013'
PRP OTHER 'GOLD'
PRP P1 'MALE'
PRP P2 '50 OHM'
PRP P3 'ST'
PRP SHEETPART ''
PRP SIZE '1.25MM HT'
PRP SUB ''
PRP Supplier_1 'Digi-Key'
PRP Supplier_Part_Number_1 'A118077CT-ND'
PRP VALENTIUM_PART_NUM '<VALENTIUM>'
PRP VALUE 'UMCC'
TOP 0 0.5948031 2.481063 90 N 107 2 AN6-1
TOP 1 0.6548425 2.5391339 90 N 135 102 AN6-2
TOP 2 0.6548425 2.4229921 90 N 135 101 AN6-3
#
# CMP 142
CMP 34 0.6548425 1.956063 90 N AN5 1909763-1 ;0=1,1=0.0000
PRP CATEGORY 'CONN, JACK'
PRP DATE ''
PRP DESC 'CONN, JACK, UMCC, MALE, 50 OHM, U.FL, GOLD, SMT'
PRP MAXTEMP '90C'
PRP MFG_Name 'TE'
PRP MFG_PART_NUM '1909763-1'
PRP MINTEMP '-40C'
PRP MODIFY_DATE '10/10/2013'
PRP OTHER 'GOLD'
PRP P1 'MALE'
PRP P2 '50 OHM'
PRP P3 'ST'
PRP SHEETPART ''
PRP SIZE '1.25MM HT'
PRP SUB ''
PRP Supplier_1 'Digi-Key'
PRP Supplier_Part_Number_1 'A118077CT-ND'
PRP VALENTIUM_PART_NUM '<VALENTIUM>'
PRP VALUE 'UMCC'
TOP 0 0.5948031 1.956063 90 N 106 2 AN5-1
TOP 1 0.6548425 2.0141339 90 N 135 104 AN5-2
TOP 2 0.6548425 1.8979921 90 N 135 103 AN5-3
#
# CMP 143
CMP 3 0.1998425 0.906063 180 N AN4 RF-901-143-6FRX ;0=2,1=0.3898
PRP CATEGORY 'CONN, JACK'
PRP DATE ''
PRP DESC 'CONN, JACK, SMA, FEMALE, 50 OHM, R/A, GOLD, TH'
PRP MAXTEMP '165C'
PRP MFG_Name 'AMPHENOL'
PRP MFG_PART_NUM '901-143-6RFX'
PRP MINTEMP '-65C'
PRP MODIFY_DATE '10/10/2013'
PRP OTHER 'GOLD'
PRP P1 'FEMALE'
PRP P2 '50 OHM'
PRP P3 'R/A'
PRP SHEETPART ''
PRP SIZE '9.86MM HT'
PRP SUB ''
PRP Supplier_1 'Digi-Key'
PRP Supplier_Part_Number_1 'ARFX1232-ND'
PRP VALENTIUM_PART_NUM '<VALENTIUM>'
PRP VALUE 'SMA'
TOP 0 0.1998425 0.906063 180 N 104 0 AN4-1
TOP 1 0.2998425 1.006063 180 N 135 32 AN4-2
TOP 2 0.2998425 0.806063 180 N 135 33 AN4-3
TOP 3 0.0998425 0.806063 180 N 135 34 AN4-4
TOP 4 0.0998425 1.006063 180 N 135 35 AN4-5
#
# CMP 144
CMP 3 0.1998425 1.431063 180 N AN3 RF-901-143-6FRX ;0=2,1=0.3898
PRP CATEGORY 'CONN, JACK'
PRP DATE ''
PRP DESC 'CONN, JACK, SMA, FEMALE, 50 OHM, R/A, GOLD, TH'
PRP MAXTEMP '165C'
PRP MFG_Name 'AMPHENOL'
PRP MFG_PART_NUM '901-143-6RFX'
PRP MINTEMP '-65C'
PRP MODIFY_DATE '10/10/2013'
PRP OTHER 'GOLD'
PRP P1 'FEMALE'
PRP P2 '50 OHM'
PRP P3 'R/A'
PRP SHEETPART ''
PRP SIZE '9.86MM HT'
PRP SUB ''
PRP Supplier_1 'Digi-Key'
PRP Supplier_Part_Number_1 'ARFX1232-ND'
PRP VALENTIUM_PART_NUM '<VALENTIUM>'
PRP VALUE 'SMA'
TOP 0 0.1998425 1.431063 180 N 105 0 AN3-1
TOP 1 0.2998425 1.531063 180 N 135 17 AN3-2
TOP 2 0.2998425 1.331063 180 N 135 18 AN3-3
TOP 3 0.0998425 1.331063 180 N 135 19 AN3-4
TOP 4 0.0998425 1.531063 180 N 135 20 AN3-5
#
# CMP 145
CMP 3 0.1998425 1.956063 180 N AN2 RF-901-143-6FRX ;0=2,1=0.3898
PRP CATEGORY 'CONN, JACK'
PRP DATE ''
PRP DESC 'CONN, JACK, SMA, FEMALE, 50 OHM, R/A, GOLD, TH'
PRP MAXTEMP '165C'
PRP MFG_Name 'AMPHENOL'
PRP MFG_PART_NUM '901-143-6RFX'
PRP MINTEMP '-65C'
PRP MODIFY_DATE '10/10/2013'
PRP OTHER 'GOLD'
PRP P1 'FEMALE'
PRP P2 '50 OHM'
PRP P3 'R/A'
PRP SHEETPART ''
PRP SIZE '9.86MM HT'
PRP SUB ''
PRP Supplier_1 'Digi-Key'
PRP Supplier_Part_Number_1 'ARFX1232-ND'
PRP VALENTIUM_PART_NUM '<VALENTIUM>'
PRP VALUE 'SMA'
TOP 0 0.1998425 1.956063 180 N 106 0 AN2-1
TOP 1 0.2998425 2.056063 180 N 135 21 AN2-2
TOP 2 0.2998425 1.856063 180 N 135 22 AN2-3
TOP 3 0.0998425 1.856063 180 N 135 23 AN2-4
TOP 4 0.0998425 2.056063 180 N 135 24 AN2-5
#
# CMP 146
CMP 3 0.1998425 2.481063 180 N AN1 RF-901-143-6FRX ;0=2,1=0.3898
PRP CATEGORY 'CONN, JACK'
PRP DATE ''
PRP DESC 'CONN, JACK, SMA, FEMALE, 50 OHM, R/A, GOLD, TH'
PRP MAXTEMP '165C'
PRP MFG_Name 'AMPHENOL'
PRP MFG_PART_NUM '901-143-6RFX'
PRP MINTEMP '-65C'
PRP MODIFY_DATE '10/10/2013'
PRP OTHER 'GOLD'
PRP P1 'FEMALE'
PRP P2 '50 OHM'
PRP P3 'R/A'
PRP SHEETPART ''
PRP SIZE '9.86MM HT'
PRP SUB ''
PRP Supplier_1 'Digi-Key'
PRP Supplier_Part_Number_1 'ARFX1232-ND'
PRP VALENTIUM_PART_NUM '<VALENTIUM>'
PRP VALUE 'SMA'
TOP 0 0.1998425 2.481063 180 N 107 0 AN1-1
TOP 1 0.2998425 2.581063 180 N 135 25 AN1-2
TOP 2 0.2998425 2.381063 180 N 135 26 AN1-3
TOP 3 0.0998425 2.381063 180 N 135 27 AN1-4
TOP 4 0.0998425 2.581063 180 N 135 28 AN1-5
#

### steps/pcb/layers/drill/tools
THICKNESS=0
USER_PARAMS=

TOOLS {
    NUM=1
    TYPE=VIA
    MIN_TOL=0
    MAX_TOL=0
    BIT=
    FINISH_SIZE=8
    DRILL_SIZE=8
}

TOOLS {
    NUM=2
    TYPE=PLATED
    MIN_TOL=0
    MAX_TOL=0
    BIT=
    FINISH_SIZE=21.66
    DRILL_SIZE=21.66
}

TOOLS {
    NUM=3
    TYPE=PLATED
    MIN_TOL=0
    MAX_TOL=0
    BIT=
    FINISH_SIZE=29.9213
    DRILL_SIZE=29.9213
}

TOOLS {
    NUM=4
    TYPE=PLATED
    MIN_TOL=0
    MAX_TOL=0
    BIT=
    FINISH_SIZE=30
    DRILL_SIZE=30
}

TOOLS {
    NUM=5
    TYPE=PLATED
    MIN_TOL=0
    MAX_TOL=0
    BIT=
    FINISH_SIZE=39.3701
    DRILL_SIZE=39.3701
}

TOOLS {
    NUM=6
    TYPE=PLATED
    MIN_TOL=0
    MAX_TOL=0
    BIT=
    FINISH_SIZE=41.3386
    DRILL_SIZE=41.3386
}

TOOLS {
    NUM=7
    TYPE=PLATED
    MIN_TOL=0
    MAX_TOL=0
    BIT=
    FINISH_SIZE=50
    DRILL_SIZE=50
}

TOOLS {
    NUM=8
    TYPE=PLATED
    MIN_TOL=0
    MAX_TOL=0
    BIT=
    FINISH_SIZE=60
    DRILL_SIZE=60
}

TOOLS {
    NUM=9
    TYPE=PLATED
    MIN_TOL=0
    MAX_TOL=0
    BIT=
    FINISH_SIZE=64.9606
    DRILL_SIZE=64.9606
}

TOOLS {
    NUM=10
    TYPE=PLATED
    MIN_TOL=0
    MAX_TOL=0
    BIT=
    FINISH_SIZE=68
    DRILL_SIZE=68
}

TOOLS {
    NUM=11
    TYPE=PLATED
    MIN_TOL=0
    MAX_TOL=0
    BIT=
    FINISH_SIZE=70.8661
    DRILL_SIZE=70.8661
}

TOOLS {
    NUM=12
    TYPE=PLATED
    MIN_TOL=0
    MAX_TOL=0
    BIT=
    FINISH_SIZE=118.11
    DRILL_SIZE=118.11
}

TOOLS {
    NUM=13
    TYPE=VIA
    MIN_TOL=0
    MAX_TOL=0
    BIT=
    FINISH_SIZE=125.9843
    DRILL_SIZE=125.9843
}

TOOLS {
    NUM=14
    TYPE=NON_PLATED
    MIN_TOL=0
    MAX_TOL=0
    BIT=
    FINISH_SIZE=35.4331
    DRILL_SIZE=35.4331
}

TOOLS {
    NUM=15
    TYPE=NON_PLATED
    MIN_TOL=0
    MAX_TOL=0
    BIT=
    FINISH_SIZE=65.9843
    DRILL_SIZE=65.9843
}

TOOLS {
    NUM=16
    TYPE=NON_PLATED
    MIN_TOL=0
    MAX_TOL=0
    BIT=
    FINISH_SIZE=118.1102
    DRILL_SIZE=118.1102
}

TOOLS {
    NUM=17
    TYPE=NON_PLATED
    MIN_TOL=0
    MAX_TOL=0
    BIT=
    FINISH_SIZE=125.1969
    DRILL_SIZE=125.1969
}

